# ODB++ job TAP-GM-V2_2.zip
### matrix/matrix

STEP {
    COL=1
    NAME=PCB
}


LAYER {
    ROW=1
    CONTEXT=BOARD
    TYPE=COMPONENT
    NAME=COMP_+_TOP
    POLARITY=POSITIVE
    START_NAME=
    END_NAME=
    OLD_NAME=
}

LAYER {
    ROW=2
    CONTEXT=BOARD
    TYPE=SILK_SCREEN
    NAME=TOP_OVERLAY
    POLARITY=POSITIVE
    START_NAME=
    END_NAME=
    OLD_NAME=
}

LAYER {
    ROW=3
    CONTEXT=BOARD
    TYPE=SOLDER_PASTE
    NAME=TOP_PASTE
    POLARITY=POSITIVE
    START_NAME=
    END_NAME=
    OLD_NAME=
}

LAYER {
    ROW=4
    CONTEXT=BOARD
    TYPE=SOLDER_MASK
    NAME=TOP_SOLDER
    POLARITY=POSITIVE
    START_NAME=
    END_NAME=
    OLD_NAME=
}

LAYER {
    ROW=5
    CONTEXT=BOARD
    TYPE=SIGNAL
    NAME=TOP
    POLARITY=POSITIVE
    START_NAME=
    END_NAME=
    OLD_NAME=
}

LAYER {
    ROW=6
    CONTEXT=BOARD
    TYPE=SIGNAL
    NAME=SGND
    POLARITY=POSITIVE
    START_NAME=
    END_NAME=
    OLD_NAME=
}

LAYER {
    ROW=7
    CONTEXT=BOARD
    TYPE=SIGNAL
    NAME=IN1
    POLARITY=POSITIVE
    START_NAME=
    END_NAME=
    OLD_NAME=
}

LAYER {
    ROW=8
    CONTEXT=BOARD
    TYPE=SIGNAL
    NAME=IN2
    POLARITY=POSITIVE
    START_NAME=
    END_NAME=
    OLD_NAME=
}

LAYER {
    ROW=9
    CONTEXT=BOARD
    TYPE=SIGNAL
    NAME=SGND1
    POLARITY=POSITIVE
    START_NAME=
    END_NAME=
    OLD_NAME=
}

LAYER {
    ROW=10
    CONTEXT=BOARD
    TYPE=SIGNAL
    NAME=BOTTOM
    POLARITY=POSITIVE
    START_NAME=
    END_NAME=
    OLD_NAME=
}

LAYER {
    ROW=11
    CONTEXT=BOARD
    TYPE=SOLDER_MASK
    NAME=BOTTOM_SOLDER
    POLARITY=POSITIVE
    START_NAME=
    END_NAME=
    OLD_NAME=
}

LAYER {
    ROW=12
    CONTEXT=BOARD
    TYPE=SOLDER_PASTE
    NAME=BOTTOM_PASTE
    POLARITY=POSITIVE
    START_NAME=
    END_NAME=
    OLD_NAME=
}

LAYER {
    ROW=13
    CONTEXT=BOARD
    TYPE=SILK_SCREEN
    NAME=BOTTOM_OVERLAY
    POLARITY=POSITIVE
    START_NAME=
    END_NAME=
    OLD_NAME=
}

LAYER {
    ROW=14
    CONTEXT=BOARD
    TYPE=DRILL
    NAME=DRILL
    POLARITY=POSITIVE
    START_NAME=TOP
    END_NAME=BOTTOM
    OLD_NAME=
}

LAYER {
    ROW=15
    CONTEXT=BOARD
    TYPE=COMPONENT
    NAME=COMP_+_BOT
    POLARITY=POSITIVE
    START_NAME=
    END_NAME=
    OLD_NAME=
}

### misc/attrlist
.customer = 
.comment = 
.technology = 
.global_camtek_aoiset = 
.drc_route_keepin_lyr = 
.drc_comp_keepin_lyr = 
.drc_tp_keepin_lyr = 
.drc_route_keepout_lyr = 
.drc_via_keepout_lyr = 
.drc_trace_keepout_lyr = 
.drc_trace_keepout_lyr = 
.drc_plane_keepout_lyr = 
.drc_pad_keepout_lyr = 
.drc_comp_keepout_lyr = 
.drc_comp_height_lyr = 
.drc_tp_keepout_lyr = 
.variant_list = 
.primary_side = top
.design_origin_x = 0
.design_origin_y = 0
.board_thickness = 0.0472
_board_material = thermon

### steps/pcb/stephdr
X_DATUM=0.0000
Y_DATUM=0.0000

TOP_ACTIVE=0
BOTTOM_ACTIVE=0
RIGHT_ACTIVE=0
LEFT_ACTIVE=0
ONLINE_DRC_NAME=
ONLINE_DRC_MODE=DISABLED
ONLINE_DRC_STAT=RED
ONLINE_DRC_TIME=0
ONLINE_DRC_BEEP_VOL=2
ONLINE_DRC_BEEP_TONE=500
ONLINE_NET_MODE=DISABLED
ONLINE_NET_STAT=RED
ONLINE_NET_TIME=0
ONLINE_NET_BEEP_VOL=2
ONLINE_NET_BEEP_TONE=1000

### steps/pcb/attrlist
.out_drill_full = no
.out_drill_optional = no
.out_rout_optional = no
.array_with_rotation = no
.flipped_out_of_date = no
.comment = 
.out_name = 
.assembly_proc_top = 
.assembly_proc_bottom = 
.all_eda_layers = 
.etm_tester = 
.flipped_of = 
.pnl_scheme = 
.pnl_pcb = 
.pnl_class = 
.pnl_place = 
.fs_direction_top = right2left
.fs_direction_bottom = right2left
.smt_direction_top = right2left
.smt_direction_bottom = right2left
.viacap_layer = none
.etm_pin_style = regular
.etm_repear_fmt = none
.out_drill_order = 0
.out_rout_order = 0
.etm_adapter_h = 3750.000000
.gold_plating = no

### steps/pcb/layers/bottom/attrlist
.out_mirror = no
.lpol_done = no
.cu_base = no
.comment =
.inp_file =
.eda_layers = "BOTTOM"
.out_angle = 0.0
.out_polarity = positive
.layer_hdi_type = buildup
.out_x_scale = 1.000000
.out_y_scale = 1.000000
.out_comp = 0.000000
.et_adjacency = 20.000000
.layer_dielectric = 0.0004
.copper_weight = 0.85106383

### steps/pcb/layers/bottom_overlay/attrlist
.out_mirror = no
.lpol_done = no
.cu_base = no
.comment =
.inp_file =
.eda_layers = "BottomOverlay"
.out_angle = 0.0
.out_polarity = positive
.layer_hdi_type = buildup
.out_x_scale = 1.000000
.out_y_scale = 1.000000
.out_comp = 0.000000
.et_adjacency = 20.000000
.layer_dielectric = 0.0001
.copper_weight = 1

### steps/pcb/layers/bottom_paste/attrlist
.out_mirror = no
.lpol_done = no
.cu_base = no
.comment =
.inp_file =
.eda_layers = "BottomPaste"
.out_angle = 0.0
.out_polarity = positive
.layer_hdi_type = buildup
.out_x_scale = 1.000000
.out_y_scale = 1.000000
.out_comp = 0.000000
.et_adjacency = 20.000000
.layer_dielectric = 0.0001
.copper_weight = 1

### steps/pcb/layers/bottom_solder/attrlist
.out_mirror = no
.lpol_done = no
.cu_base = no
.comment =
.inp_file =
.eda_layers = "BottomSolderMask"
.out_angle = 0.0
.out_polarity = positive
.layer_hdi_type = buildup
.out_x_scale = 1.000000
.out_y_scale = 1.000000
.out_comp = 0.000000
.et_adjacency = 20.000000
.layer_dielectric = 0.0001
.copper_weight = 1

### steps/pcb/layers/drill/attrlist
.out_mirror = no
.lpol_done = no
.cu_base = no
.comment =
.inp_file =
.eda_layers = ""
.out_angle = 0.0
.out_polarity = positive
.layer_hdi_type = buildup
.out_x_scale = 1.000000
.out_y_scale = 1.000000
.out_comp = 0.000000
.et_adjacency = 20.000000
.layer_dielectric = 0.0001
.copper_weight = 1

### steps/pcb/layers/in1/attrlist
.out_mirror = no
.lpol_done = no
.cu_base = no
.comment =
.inp_file =
.eda_layers = "IN1"
.out_angle = 0.0
.out_polarity = positive
.layer_hdi_type = buildup
.out_x_scale = 1.000000
.out_y_scale = 1.000000
.out_comp = 0.000000
.et_adjacency = 20.000000
.layer_dielectric = 0.008
.copper_weight = 0.85106383

### steps/pcb/layers/in2/attrlist
.out_mirror = no
.lpol_done = no
.cu_base = no
.comment =
.inp_file =
.eda_layers = "IN2"
.out_angle = 0.0
.out_polarity = positive
.layer_hdi_type = buildup
.out_x_scale = 1.000000
.out_y_scale = 1.000000
.out_comp = 0.000000
.et_adjacency = 20.000000
.layer_dielectric = 0.008
.copper_weight = 0.85106383

### steps/pcb/layers/sgnd/attrlist
.out_mirror = no
.lpol_done = no
.cu_base = no
.comment =
.inp_file =
.eda_layers = "SGND"
.out_angle = 0.0
.out_polarity = positive
.layer_hdi_type = buildup
.out_x_scale = 1.000000
.out_y_scale = 1.000000
.out_comp = 0.000000
.et_adjacency = 20.000000
.layer_dielectric = 0.008
.copper_weight = 0.85106383

### steps/pcb/layers/sgnd1/attrlist
.out_mirror = no
.lpol_done = no
.cu_base = no
.comment =
.inp_file =
.eda_layers = "SGND1"
.out_angle = 0.0
.out_polarity = positive
.layer_hdi_type = buildup
.out_x_scale = 1.000000
.out_y_scale = 1.000000
.out_comp = 0.000000
.et_adjacency = 20.000000
.layer_dielectric = 0.008
.copper_weight = 0.85106383

### steps/pcb/layers/top/attrlist
.out_mirror = no
.lpol_done = no
.cu_base = no
.comment =
.inp_file =
.eda_layers = "TOP"
.out_angle = 0.0
.out_polarity = positive
.layer_hdi_type = buildup
.out_x_scale = 1.000000
.out_y_scale = 1.000000
.out_comp = 0.000000
.et_adjacency = 20.000000
.layer_dielectric = 0.008
.copper_weight = 0.85106383

### steps/pcb/layers/top_overlay/attrlist
.out_mirror = no
.lpol_done = no
.cu_base = no
.comment =
.inp_file =
.eda_layers = "TopOverlay"
.out_angle = 0.0
.out_polarity = positive
.layer_hdi_type = buildup
.out_x_scale = 1.000000
.out_y_scale = 1.000000
.out_comp = 0.000000
.et_adjacency = 20.000000
.layer_dielectric = 0.0001
.copper_weight = 1

### steps/pcb/layers/top_paste/attrlist
.out_mirror = no
.lpol_done = no
.cu_base = no
.comment =
.inp_file =
.eda_layers = "TopPaste"
.out_angle = 0.0
.out_polarity = positive
.layer_hdi_type = buildup
.out_x_scale = 1.000000
.out_y_scale = 1.000000
.out_comp = 0.000000
.et_adjacency = 20.000000
.layer_dielectric = 0.0001
.copper_weight = 1

### steps/pcb/layers/top_solder/attrlist
.out_mirror = no
.lpol_done = no
.cu_base = no
.comment =
.inp_file =
.eda_layers = "TopSolderMask"
.out_angle = 0.0
.out_polarity = positive
.layer_hdi_type = buildup
.out_x_scale = 1.000000
.out_y_scale = 1.000000
.out_comp = 0.000000
.et_adjacency = 20.000000
.layer_dielectric = 0.0001
.copper_weight = 1

### steps/pcb/profile
#
#Layer features
#
S P 0
OB 0.5905512 0.1771654 I
OS 0.5905512 0.5019685
OS 1.3129921 0.5019685
OS 1.3129921 0.1771654
OS 1.6279528 0.1771654
OS 1.6279528 0.4301181
OS 1.6282986 0.4371606
OS 1.6310465 0.4509751
OS 1.6364367 0.4639881
OS 1.6442619 0.4756995
OS 1.6542216 0.4856592
OS 1.665933 0.4934844
OS 1.678946 0.4988746
OS 1.6927605 0.5016225
OS 1.7068456 0.5016225
OS 1.7206601 0.4988746
OS 1.7336731 0.4934844
OS 1.7453845 0.4856592
OS 1.7553442 0.4756995
OS 1.7631694 0.4639881
OS 1.7685596 0.4509751
OS 1.7713075 0.4371606
OS 1.7716536 0.4301181
OS 1.7716536 0.019685
OS 1.7913386 0
OS 2.1929134 0
OS 2.2125984 0.019685
OS 2.2125984 0.2933071
OS 2.2129183 0.2981889
OS 2.2154454 0.30762
OS 2.2203273 0.3160757
OS 2.2272313 0.3229797
OS 2.235687 0.3278616
OS 2.2451181 0.3303887
OS 2.2548818 0.3303887
OS 2.2643129 0.3278616
OS 2.2727686 0.3229797
OS 2.2796726 0.3160757
OS 2.2845545 0.30762
OS 2.2870816 0.2981889
OS 2.2874016 0.2933071
OS 2.2874016 0.019685
OS 2.3070866 0
OS 3.1023622 0
OS 3.1220472 0.019685
OS 3.1220472 0.5019685
OS 7.0875986 0.5019685
OS 7.0875984 4.3759843
OS 0 4.3759843
OS 0 0.1771654
OS 0.5905512 0.1771654
OE
SE

### steps/pcb/eda/data
# 11/17/2020 9:36:29 AM
#
HDR Altium Designer file - Version 1.0.0.30000
LYR bottom_overlay bottom_paste in2 in1 sgnd sgnd1 bottom_solder top_overlay bottom top_paste top_solder top drill 
#
#NET 0
NET $NONE$
SNT TOP T 76 31
FID C 1 76
FID C 6 119
FID C 8 303
SNT TOP T 76 4
FID C 1 13
FID C 6 43
FID C 8 231
SNT TOP T 76 5
FID C 1 14
FID C 6 44
FID C 8 232
SNT TOP T 76 6
FID C 1 15
FID C 6 45
FID C 8 233
SNT TOP T 76 7
FID C 1 16
FID C 6 49
FID C 8 237
SNT TOP T 76 18
FID C 1 47
FID C 6 87
FID C 8 271
SNT TOP T 41 0
FID C 6 72
FID C 10 283
FID H 12 36
SNT TOP T 41 0
FID C 6 73
FID C 10 284
FID H 12 37
SNT TOP T 81 0
FID C 6 151
FID C 8 333
FID C 10 829
FID C 11 2196
FID H 12 72
SNT TOP T 81 0
FID C 6 156
FID C 8 338
FID C 10 873
FID C 11 2240
FID H 12 77
SNT TOP T 77 332
FID C 6 112
FID C 8 296
FID C 10 447
FID C 11 1816
FID H 12 38
SNT TOP T 77 328
FID C 6 113
FID C 8 297
FID C 10 448
FID C 11 1817
FID H 12 39
SNT TOP T 77 332
FID C 6 54
FID C 8 243
FID C 10 215
FID C 11 1589
FID H 12 33
SNT TOP T 77 332
FID C 6 38
FID C 8 225
FID C 10 136
FID C 11 1508
FID H 12 28
SNT TOP T 77 328
FID C 6 37
FID C 8 224
FID C 10 135
FID C 11 1507
FID H 12 27
SNT TOP T 77 328
FID C 6 53
FID C 8 242
FID C 10 214
FID C 11 1588
FID H 12 32
SNT TOP T 77 332
FID C 6 121
FID C 8 305
FID C 10 559
FID C 11 1928
FID H 12 42
SNT TOP T 77 328
FID C 6 122
FID C 8 306
FID C 10 560
FID C 11 1929
FID H 12 43
SNT TOP T 77 0
FID C 6 123
FID C 10 566
FID H 12 44
SNT TOP T 77 0
FID C 6 35
FID C 10 131
FID H 12 25
SNT TOP T 77 0
FID C 6 36
FID C 10 132
FID H 12 26
SNT TOP T 77 0
FID C 6 124
FID C 10 567
FID H 12 45
SNT TOP T 13 0
FID C 6 132
FID C 8 314
FID C 10 703
FID C 11 2070
FID H 12 53
SNT TOP B 0 0
FID C 6 71
FID C 10 282
FID H 12 35
SNT TOP B 0 0
FID C 6 70
FID C 10 281
FID H 12 34
SNT TOP T 44 11
FID C 6 114
FID C 8 298
FID C 10 449
FID C 11 1818
FID H 12 40
SNT TOP T 44 10
FID C 6 120
FID C 8 304
FID C 10 488
FID C 11 1857
FID H 12 41
SNT TOP T 80 0
FID C 6 125
FID C 8 307
FID C 10 632
FID C 11 1999
FID H 12 46
SNT TOP T 80 0
FID C 6 126
FID C 8 308
FID C 10 648
FID C 11 2015
FID H 12 47
SNT TOP T 43 1
FID C 9 582
FID C 10 630
FID C 11 1997
SNT TOP T 43 5
FID C 9 578
FID C 10 626
FID C 11 1993
SNT TOP T 43 6
FID C 9 577
FID C 10 625
FID C 11 1992
SNT TOP T 43 15
FID C 9 608
FID C 10 660
FID C 11 2027
SNT TOP T 43 14
FID C 9 607
FID C 10 659
FID C 11 2026
SNT TOP T 43 13
FID C 9 606
FID C 10 658
FID C 11 2025
SNT TOP T 77 336
FID C 9 408
FID C 10 451
FID C 11 1820
SNT TOP T 77 322
FID C 9 188
FID C 10 223
FID C 11 1597
SNT TOP T 77 323
FID C 9 187
FID C 10 222
FID C 11 1596
SNT TOP T 77 324
FID C 9 409
FID C 10 452
FID C 11 1821
SNT TOP T 77 336
FID C 9 178
FID C 10 211
FID C 11 1585
SNT TOP T 77 277
FID C 9 313
FID C 10 353
FID C 11 1722
SNT TOP T 77 271
FID C 9 328
FID C 10 368
FID C 11 1737
SNT TOP T 77 265
FID C 9 353
FID C 10 393
FID C 11 1762
SNT TOP T 77 259
FID C 9 368
FID C 10 408
FID C 11 1777
SNT TOP T 77 247
FID C 9 400
FID C 10 440
FID C 11 1809
SNT TOP T 77 246
FID C 9 401
FID C 10 441
FID C 11 1810
SNT TOP T 77 244
FID C 9 406
FID C 10 446
FID C 11 1815
SNT TOP T 77 245
FID C 9 405
FID C 10 445
FID C 11 1814
SNT TOP T 77 248
FID C 9 393
FID C 10 433
FID C 11 1802
SNT TOP T 77 249
FID C 9 392
FID C 10 432
FID C 11 1801
SNT TOP T 77 250
FID C 9 388
FID C 10 428
FID C 11 1797
SNT TOP T 77 251
FID C 9 387
FID C 10 427
FID C 11 1796
SNT TOP T 77 254
FID C 9 379
FID C 10 419
FID C 11 1788
SNT TOP T 77 256
FID C 9 375
FID C 10 415
FID C 11 1784
SNT TOP T 77 290
FID C 9 280
FID C 10 320
FID C 11 1689
SNT TOP T 77 288
FID C 9 285
FID C 10 325
FID C 11 1694
SNT TOP T 77 310
FID C 9 217
FID C 10 252
FID C 11 1626
SNT TOP T 77 308
FID C 9 227
FID C 10 262
FID C 11 1636
SNT TOP T 77 320
FID C 9 192
FID C 10 227
FID C 11 1601
SNT TOP T 77 318
FID C 9 197
FID C 10 232
FID C 11 1606
SNT TOP T 77 316
FID C 9 202
FID C 10 237
FID C 11 1611
SNT TOP T 77 314
FID C 9 207
FID C 10 242
FID C 11 1616
SNT TOP T 77 298
FID C 9 255
FID C 10 295
FID C 11 1664
SNT TOP T 77 294
FID C 9 265
FID C 10 305
FID C 11 1674
SNT TOP T 77 296
FID C 9 261
FID C 10 301
FID C 11 1670
SNT TOP T 77 300
FID C 9 250
FID C 10 289
FID C 11 1659
SNT TOP T 77 304
FID C 9 241
FID C 10 276
FID C 11 1650
SNT TOP T 77 306
FID C 9 232
FID C 10 267
FID C 11 1641
SNT TOP T 77 286
FID C 9 289
FID C 10 329
FID C 11 1698
SNT TOP T 77 317
FID C 9 201
FID C 10 236
FID C 11 1610
SNT TOP T 77 319
FID C 9 196
FID C 10 231
FID C 11 1605
SNT TOP T 77 297
FID C 9 260
FID C 10 300
FID C 11 1669
SNT TOP T 77 299
FID C 9 254
FID C 10 294
FID C 11 1663
SNT TOP T 77 287
FID C 9 288
FID C 10 328
FID C 11 1697
SNT TOP T 77 289
FID C 9 284
FID C 10 324
FID C 11 1693
SNT TOP T 77 291
FID C 9 279
FID C 10 319
FID C 11 1688
SNT TOP T 77 295
FID C 9 264
FID C 10 304
FID C 11 1673
SNT TOP T 77 305
FID C 9 240
FID C 10 275
FID C 11 1649
SNT TOP T 77 315
FID C 9 206
FID C 10 241
FID C 11 1615
SNT TOP T 77 311
FID C 9 216
FID C 10 251
FID C 11 1625
SNT TOP T 77 309
FID C 9 226
FID C 10 261
FID C 11 1635
SNT TOP T 77 307
FID C 9 231
FID C 10 266
FID C 11 1640
SNT TOP T 77 301
FID C 9 249
FID C 10 288
FID C 11 1658
SNT TOP T 77 321
FID C 9 191
FID C 10 226
FID C 11 1600
SNT TOP T 77 284
FID C 9 294
FID C 10 334
FID C 11 1703
SNT TOP T 77 285
FID C 9 293
FID C 10 333
FID C 11 1702
SNT TOP T 77 336
FID C 9 107
FID C 10 137
FID C 11 1509
SNT TOP T 77 324
FID C 9 106
FID C 10 134
FID C 11 1506
SNT TOP T 77 238
FID C 9 146
FID C 10 176
FID C 11 1548
SNT TOP T 77 239
FID C 9 94
FID C 10 120
FID C 11 1494
SNT TOP T 77 199
FID C 9 74
FID C 10 100
FID C 11 1474
SNT TOP T 77 205
FID C 9 77
FID C 10 103
FID C 11 1477
SNT TOP T 77 180
FID C 9 117
FID C 10 147
FID C 11 1519
SNT TOP T 77 174
FID C 9 114
FID C 10 144
FID C 11 1516
SNT TOP T 77 170
FID C 9 112
FID C 10 142
FID C 11 1514
SNT TOP T 77 211
FID C 9 80
FID C 10 106
FID C 11 1480
SNT TOP T 77 197
FID C 9 73
FID C 10 99
FID C 11 1473
SNT TOP T 77 167
FID C 9 58
FID C 10 84
FID C 11 1458
SNT TOP T 77 168
FID C 9 111
FID C 10 141
FID C 11 1513
SNT TOP T 77 209
FID C 9 79
FID C 10 105
FID C 11 1479
SNT TOP T 77 175
FID C 9 62
FID C 10 88
FID C 11 1462
SNT TOP T 77 181
FID C 9 65
FID C 10 91
FID C 11 1465
SNT TOP T 77 171
FID C 9 60
FID C 10 86
FID C 11 1460
SNT TOP T 77 201
FID C 9 75
FID C 10 101
FID C 11 1475
SNT TOP T 77 207
FID C 9 78
FID C 10 104
FID C 11 1478
SNT TOP T 77 195
FID C 9 72
FID C 10 98
FID C 11 1472
SNT TOP T 77 189
FID C 9 69
FID C 10 95
FID C 11 1469
SNT TOP T 77 187
FID C 9 68
FID C 10 94
FID C 11 1468
SNT TOP T 77 177
FID C 9 63
FID C 10 89
FID C 11 1463
SNT TOP T 77 191
FID C 9 70
FID C 10 96
FID C 11 1470
SNT TOP T 77 166
FID C 9 110
FID C 10 140
FID C 11 1512
SNT TOP T 77 169
FID C 9 59
FID C 10 85
FID C 11 1459
SNT TOP T 77 176
FID C 9 115
FID C 10 145
FID C 11 1517
SNT TOP T 77 217
FID C 9 83
FID C 10 109
FID C 11 1483
SNT TOP T 77 215
FID C 9 82
FID C 10 108
FID C 11 1482
SNT TOP T 77 179
FID C 9 64
FID C 10 90
FID C 11 1464
SNT TOP T 77 185
FID C 9 67
FID C 10 93
FID C 11 1467
SNT TOP T 77 190
FID C 9 122
FID C 10 152
FID C 11 1524
SNT TOP T 77 188
FID C 9 121
FID C 10 151
FID C 11 1523
SNT TOP T 77 229
FID C 9 89
FID C 10 115
FID C 11 1489
SNT TOP T 77 204
FID C 9 129
FID C 10 159
FID C 11 1531
SNT TOP T 77 208
FID C 9 131
FID C 10 161
FID C 11 1533
SNT TOP T 77 235
FID C 9 92
FID C 10 118
FID C 11 1492
SNT TOP T 77 198
FID C 9 126
FID C 10 156
FID C 11 1528
SNT TOP T 77 218
FID C 9 136
FID C 10 166
FID C 11 1538
SNT TOP T 77 226
FID C 9 140
FID C 10 170
FID C 11 1542
SNT TOP T 77 231
FID C 9 90
FID C 10 116
FID C 11 1490
SNT TOP T 77 221
FID C 9 85
FID C 10 111
FID C 11 1485
SNT TOP T 77 178
FID C 9 116
FID C 10 146
FID C 11 1518
SNT TOP T 77 230
FID C 9 142
FID C 10 172
FID C 11 1544
SNT TOP T 77 234
FID C 9 144
FID C 10 174
FID C 11 1546
SNT TOP T 77 237
FID C 9 93
FID C 10 119
FID C 11 1493
SNT TOP T 77 225
FID C 9 87
FID C 10 113
FID C 11 1487
SNT TOP T 77 219
FID C 9 84
FID C 10 110
FID C 11 1484
SNT TOP T 77 227
FID C 9 88
FID C 10 114
FID C 11 1488
SNT TOP T 77 210
FID C 9 132
FID C 10 162
FID C 11 1534
SNT TOP T 77 206
FID C 9 130
FID C 10 160
FID C 11 1532
SNT TOP T 77 228
FID C 9 141
FID C 10 171
FID C 11 1543
SNT TOP T 77 216
FID C 9 135
FID C 10 165
FID C 11 1537
SNT TOP T 77 224
FID C 9 139
FID C 10 169
FID C 11 1541
SNT TOP T 77 236
FID C 9 145
FID C 10 175
FID C 11 1547
SNT TOP T 77 220
FID C 9 137
FID C 10 167
FID C 11 1539
SNT TOP T 77 196
FID C 9 125
FID C 10 155
FID C 11 1527
SNT TOP T 77 97
FID C 9 215
FID C 10 250
FID C 11 1624
SNT TOP T 77 95
FID C 9 211
FID C 10 246
FID C 11 1620
SNT TOP T 77 90
FID C 9 199
FID C 10 234
FID C 11 1608
SNT TOP T 77 88
FID C 9 194
FID C 10 229
FID C 11 1603
SNT TOP T 77 161
FID C 9 399
FID C 10 439
FID C 11 1808
SNT TOP T 77 159
FID C 9 391
FID C 10 431
FID C 11 1800
SNT TOP T 77 151
FID C 9 373
FID C 10 413
FID C 11 1782
SNT TOP T 77 149
FID C 9 367
FID C 10 407
FID C 11 1776
SNT TOP T 77 141
FID C 9 347
FID C 10 387
FID C 11 1756
SNT TOP T 77 139
FID C 9 334
FID C 10 374
FID C 11 1743
SNT TOP T 77 145
FID C 9 356
FID C 10 396
FID C 11 1765
SNT TOP T 77 131
FID C 9 312
FID C 10 352
FID C 11 1721
SNT TOP T 77 129
FID C 9 307
FID C 10 347
FID C 11 1716
SNT TOP T 77 137
FID C 9 327
FID C 10 367
FID C 11 1736
SNT TOP T 77 135
FID C 9 322
FID C 10 362
FID C 11 1731
SNT TOP T 77 121
FID C 9 287
FID C 10 327
FID C 11 1696
SNT TOP T 77 127
FID C 9 301
FID C 10 341
FID C 11 1710
SNT TOP T 77 119
FID C 9 283
FID C 10 323
FID C 11 1692
SNT TOP T 77 125
FID C 9 296
FID C 10 336
FID C 11 1705
SNT TOP T 77 115
FID C 9 270
FID C 10 310
FID C 11 1679
SNT TOP T 77 101
FID C 9 230
FID C 10 265
FID C 11 1639
SNT TOP T 77 107
FID C 9 248
FID C 10 287
FID C 11 1657
SNT TOP T 77 105
FID C 9 243
FID C 10 278
FID C 11 1652
SNT TOP T 77 84
FID C 9 185
FID C 10 220
FID C 11 1594
SNT TOP T 77 86
FID C 9 189
FID C 10 224
FID C 11 1598
SNT TOP T 77 87
FID C 9 190
FID C 10 225
FID C 11 1599
SNT TOP T 77 85
FID C 9 186
FID C 10 221
FID C 11 1595
SNT TOP T 77 100
FID C 9 229
FID C 10 264
FID C 11 1638
SNT TOP T 77 98
FID C 9 224
FID C 10 259
FID C 11 1633
SNT TOP T 77 114
FID C 9 269
FID C 10 309
FID C 11 1678
SNT TOP T 77 140
FID C 9 346
FID C 10 386
FID C 11 1755
SNT TOP T 77 138
FID C 9 333
FID C 10 373
FID C 11 1742
SNT TOP T 77 146
FID C 9 361
FID C 10 401
FID C 11 1770
SNT TOP T 77 148
FID C 9 366
FID C 10 406
FID C 11 1775
SNT TOP T 77 156
FID C 9 385
FID C 10 425
FID C 11 1794
SNT TOP T 77 158
FID C 9 390
FID C 10 430
FID C 11 1799
SNT TOP T 77 324
FID C 9 177
FID C 10 210
FID C 11 1584
SNT TOP T 77 54
FID C 9 478
FID C 10 522
FID C 11 1891
SNT TOP T 77 56
FID C 9 477
FID C 10 521
FID C 11 1890
SNT TOP T 77 61
FID C 9 531
FID C 10 579
FID C 11 1946
SNT TOP T 77 40
FID C 9 485
FID C 10 529
FID C 11 1898
SNT TOP T 77 336
FID C 9 514
FID C 10 558
FID C 11 1927
SNT TOP T 77 324
FID C 9 515
FID C 10 561
FID C 11 1930
SNT TOP T 77 83
FID C 9 520
FID C 10 568
FID C 11 1935
SNT TOP T 77 82
FID C 9 464
FID C 10 508
FID C 11 1877
SNT TOP T 77 81
FID C 9 521
FID C 10 569
FID C 11 1936
SNT TOP T 77 79
FID C 9 522
FID C 10 570
FID C 11 1937
SNT TOP T 77 77
FID C 9 523
FID C 10 571
FID C 11 1938
SNT TOP T 77 75
FID C 9 524
FID C 10 572
FID C 11 1939
SNT TOP T 77 71
FID C 9 526
FID C 10 574
FID C 11 1941
SNT TOP T 77 69
FID C 9 527
FID C 10 575
FID C 11 1942
SNT TOP T 77 60
FID C 9 475
FID C 10 519
FID C 11 1888
SNT TOP T 77 55
FID C 9 534
FID C 10 582
FID C 11 1949
SNT TOP T 77 18
FID C 9 496
FID C 10 540
FID C 11 1909
SNT TOP T 77 58
FID C 9 476
FID C 10 520
FID C 11 1889
SNT TOP T 77 20
FID C 9 495
FID C 10 539
FID C 11 1908
SNT TOP T 77 47
FID C 9 538
FID C 10 586
FID C 11 1953
SNT TOP T 77 39
FID C 9 542
FID C 10 590
FID C 11 1957
SNT TOP T 77 41
FID C 9 541
FID C 10 589
FID C 11 1956
SNT TOP T 77 44
FID C 9 483
FID C 10 527
FID C 11 1896
SNT TOP T 77 50
FID C 9 480
FID C 10 524
FID C 11 1893
SNT TOP T 77 45
FID C 9 539
FID C 10 587
FID C 11 1954
SNT TOP T 77 16
FID C 9 497
FID C 10 541
FID C 11 1910
SNT TOP T 77 14
FID C 9 498
FID C 10 542
FID C 11 1911
SNT TOP T 77 17
FID C 9 553
FID C 10 601
FID C 11 1968
SNT TOP T 77 15
FID C 9 554
FID C 10 602
FID C 11 1969
SNT TOP T 77 19
FID C 9 552
FID C 10 600
FID C 11 1967
SNT TOP T 77 31
FID C 9 546
FID C 10 594
FID C 11 1961
SNT TOP T 77 29
FID C 9 547
FID C 10 595
FID C 11 1962
SNT TOP T 77 21
FID C 9 551
FID C 10 599
FID C 11 1966
SNT TOP T 77 27
FID C 9 548
FID C 10 596
FID C 11 1963
SNT TOP T 77 34
FID C 9 488
FID C 10 532
FID C 11 1901
SNT TOP T 77 64
FID C 9 473
FID C 10 517
FID C 11 1886
SNT TOP T 77 36
FID C 9 487
FID C 10 531
FID C 11 1900
SNT TOP T 77 66
FID C 9 472
FID C 10 516
FID C 11 1885
SNT TOP T 77 68
FID C 9 471
FID C 10 515
FID C 11 1884
SNT TOP T 0 4
FID C 9 430
FID C 10 473
FID C 11 1842
SNT TOP T 0 6
FID C 9 439
FID C 10 482
FID C 11 1851
SNT TOP T 42 0
FID C 9 743
FID C 10 815
FID C 11 2182
SNT TOP T 42 6
FID C 9 722
FID C 10 794
FID C 11 2161
SNT TOP T 42 7
FID C 9 723
FID C 10 795
FID C 11 2162
SNT TOP T 42 8
FID C 9 724
FID C 10 796
FID C 11 2163
SNT TOP T 42 11
FID C 9 727
FID C 10 799
FID C 11 2166
SNT TOP T 42 12
FID C 9 728
FID C 10 800
FID C 11 2167
SNT TOP T 42 20
FID C 9 751
FID C 10 823
FID C 11 2190
SNT TOP T 42 21
FID C 9 750
FID C 10 822
FID C 11 2189
SNT TOP T 42 22
FID C 9 749
FID C 10 821
FID C 11 2188
SNT TOP T 42 23
FID C 9 748
FID C 10 820
FID C 11 2187
SNT TOP T 40 17
FID C 9 596
FID C 10 645
FID C 11 2012
SNT TOP T 40 15
FID C 9 595
FID C 10 644
FID C 11 2011
SNT TOP T 40 12
FID C 9 621
FID C 10 674
FID C 11 2041
SNT TOP T 40 13
FID C 9 594
FID C 10 643
FID C 11 2010
SNT TOP T 40 10
FID C 9 620
FID C 10 673
FID C 11 2040
SNT TOP T 40 11
FID C 9 593
FID C 10 642
FID C 11 2009
SNT TOP T 40 9
FID C 9 592
FID C 10 641
FID C 11 2008
SNT TOP T 76 41
FID C 9 176
FID C 10 209
FID C 11 1583
SNT TOP T 76 40
FID C 9 169
FID C 10 202
FID C 11 1575
SNT TOP T 76 43
FID C 9 209
FID C 10 244
FID C 11 1618
SNT TOP T 76 61
FID C 9 407
FID C 10 450
FID C 11 1819
SNT TOP T 76 36
FID C 9 165
FID C 10 195
FID C 11 1568
SNT TOP T 76 37
FID C 9 166
FID C 10 196
FID C 11 1569
SNT TOP T 76 42
FID C 9 179
FID C 10 212
FID C 11 1586
SNT TOP T 44 6
FID C 9 437
FID C 10 480
FID C 11 1849
SNT TOP T 44 7
FID C 9 438
FID C 10 481
FID C 11 1850
SNT TOP T 38 7
FID C 9 508
FID C 10 552
FID C 11 1921
SNT TOP T 38 6
FID C 9 507
FID C 10 551
FID C 11 1920
SNT TOP T 38 2
FID C 9 456
FID C 10 500
FID C 11 1869
SNT TOP T 39 0
FID C 9 513
FID C 10 557
FID C 11 1926
SNT TOP T 39 8
FID C 9 505
FID C 10 549
FID C 11 1918
SNT TOP T 39 6
FID C 9 451
FID C 10 495
FID C 11 1864
SNT TOP T 39 7
FID C 9 458
FID C 10 502
FID C 11 1871
SNT TOP T 37 2
FID C 9 798
FID C 10 878
FID C 11 2245
SNT TOP T 37 1
FID C 9 797
FID C 10 877
FID C 11 2244
SNT TOP T 34 1
FID C 9 103
FID C 10 129
FID C 11 1503
SNT TOP T 34 5
FID C 9 99
FID C 10 125
FID C 11 1499
SNT TOP T 34 6
FID C 9 98
FID C 10 124
FID C 11 1498
SNT TOP T 34 15
FID C 9 159
FID C 10 189
FID C 11 1562
SNT TOP T 34 14
FID C 9 158
FID C 10 188
FID C 11 1561
SNT TOP T 34 13
FID C 9 157
FID C 10 187
FID C 11 1560
SNT TOP T 80 9
FID C 9 585
FID C 10 634
FID C 11 2001
SNT TOP T 80 0
FID C 9 569
FID C 10 617
FID C 11 1984
SNT TOP T 80 0
FID C 9 568
FID C 10 616
FID C 11 1983
SNT TOP T 80 0
FID C 9 611
FID C 10 663
FID C 11 2030
SNT TOP T 80 0
FID C 9 612
FID C 10 664
FID C 11 2031
SNT TOP T 35 0
FID C 9 180
FID C 10 213
FID C 11 1587
SNT TOP T 35 0
FID C 9 256
FID C 10 296
FID C 11 1665
SNT TOP T 35 9
FID C 9 208
FID C 10 243
FID C 11 1617
SNT TOP T 35 6
FID C 9 234
FID C 10 269
FID C 11 1643
SNT TOP T 35 0
FID C 9 251
FID C 10 290
FID C 11 1660
SNT TOP T 35 0
FID C 9 193
FID C 10 228
FID C 11 1602
SNT TOP T 35 0
FID C 9 233
FID C 10 268
FID C 11 1642
SNT TOP T 35 0
FID C 9 198
FID C 10 233
FID C 11 1607
SNT TOP T 12 8
FID C 9 418
FID C 10 461
FID C 11 1830
SNT TOP T 12 9
FID C 9 419
FID C 10 462
FID C 11 1831
SNT TOP T 12 10
FID C 9 420
FID C 10 463
FID C 11 1832
SNT TOP T 12 11
FID C 9 421
FID C 10 464
FID C 11 1833
SNT TOP T 12 7
FID C 9 338
FID C 10 378
FID C 11 1747
SNT TOP T 12 6
FID C 9 339
FID C 10 379
FID C 11 1748
SNT TOP T 12 5
FID C 9 340
FID C 10 380
FID C 11 1749
SNT TOP T 12 4
FID C 9 341
FID C 10 381
FID C 11 1750
SNT TOP T 12 3
FID C 9 342
FID C 10 382
FID C 11 1751
SNT TOP T 12 0
FID C 9 345
FID C 10 385
FID C 11 1754
SNT VIA
FID C 6 22
FID C 8 212
FID C 10 22
FID C 11 1397
FID H 12 13
SNT VIA
FID C 6 21
FID C 8 211
FID C 10 21
FID C 11 1396
FID H 12 12
#NET 1
NET NetC54_2
SNT TOP T 43 11
FID C 9 604
FID C 10 656
FID C 11 2023
SNT TOP T 58 0
FID C 9 635
FID C 10 688
FID C 11 2055
SNT TOP T 115 1
FID C 9 636
FID C 10 690
FID C 11 2057
SNT TOP T 116 1
FID C 9 625
FID C 10 678
FID C 11 2045
SNT TOP T 80 6
FID C 9 598
FID C 10 647
FID C 11 2014
SNT TRC
FID C 11 940
SNT TRC
FID C 11 922
SNT TRC
FID C 11 951
SNT TRC
FID C 11 961
SNT TRC
FID C 11 965
SNT TRC
FID C 11 964
SNT TRC
FID C 11 1006
SNT TRC
FID C 11 997
SNT TRC
FID C 11 1002
SNT TRC
FID C 11 901
SNT TRC
FID C 11 900
SNT TRC
FID C 11 902
SNT TRC
FID C 11 919
#NET 2
NET GPS1_TX
SNT TOP T 3 0
FID C 2 481
FID C 6 33
FID C 8 223
FID C 10 81
FID C 11 1456
FID H 12 24
SNT TOP T 41 4
FID C 9 275
FID C 10 315
FID C 11 1684
SNT TOP T 77 163
FID C 9 404
FID C 10 444
FID C 11 1813
SNT TRC
FID C 2 111
SNT TRC
FID C 2 110
SNT TRC
FID C 2 112
SNT TRC
FID C 2 180
SNT TRC
FID C 2 221
SNT TRC
FID C 2 202
SNT TRC
FID C 2 182
SNT TRC
FID C 2 181
SNT TRC
FID C 3 121
SNT TRC
FID C 3 201
SNT TRC
FID C 3 205
SNT TRC
FID C 11 346
SNT TRC
FID C 11 353
SNT TRC
FID C 11 566
SNT TRC
FID C 11 574
SNT VIA
FID C 2 532
FID C 3 597
FID C 6 289
FID C 8 474
FID C 10 1013
FID C 11 2384
FID H 12 210
SNT VIA
FID C 2 490
FID C 3 563
FID C 6 184
FID C 8 369
FID C 10 908
FID C 11 2279
FID H 12 105
SNT VIA
FID C 2 533
FID C 3 598
FID C 6 290
FID C 8 475
FID C 10 1014
FID C 11 2385
FID H 12 211
SNT VIA
FID C 3 643
FID C 6 402
FID C 8 587
FID C 10 1126
FID C 11 2497
FID H 12 323
#NET 3
NET GPS1_TP1
SNT TOP T 7 0
FID C 9 237
FID C 10 272
FID C 11 1646
SNT TOP T 41 7
FID C 9 220
FID C 10 255
FID C 11 1629
SNT TOP T 77 35
FID C 9 544
FID C 10 592
FID C 11 1959
SNT TOP T 1 0
FID C 9 38
FID C 10 60
FID C 11 1435
SNT TRC
FID C 2 188
SNT TRC
FID C 2 189
SNT TRC
FID C 2 195
SNT TRC
FID C 2 177
SNT TRC
FID C 2 196
SNT TRC
FID C 2 176
SNT TRC
FID C 2 178
SNT TRC
FID C 2 103
SNT TRC
FID C 2 102
SNT TRC
FID C 2 108
SNT TRC
FID C 2 109
SNT TRC
FID C 3 483
SNT TRC
FID C 3 463
SNT TRC
FID C 3 458
SNT TRC
FID C 3 425
SNT TRC
FID C 3 420
SNT TRC
FID C 3 189
SNT TRC
FID C 3 124
SNT TRC
FID C 3 112
SNT TRC
FID C 11 313
SNT TRC
FID C 11 317
SNT TRC
FID C 11 330
SNT TRC
FID C 11 329
SNT TRC
FID C 11 104
SNT TRC
FID C 11 97
SNT TRC
FID C 11 96
SNT TRC
FID C 11 809
SNT TRC
FID C 11 876
SNT TRC
FID C 11 850
SNT VIA
FID C 2 527
FID C 3 590
FID C 6 273
FID C 8 458
FID C 10 997
FID C 11 2368
FID H 12 194
SNT VIA
FID C 2 529
FID C 6 275
FID C 8 460
FID C 10 999
FID C 11 2370
FID H 12 196
SNT VIA
FID C 2 487
FID C 6 169
FID C 8 354
FID C 10 893
FID C 11 2264
FID H 12 90
SNT VIA
FID C 2 489
FID C 3 561
FID C 6 182
FID C 8 367
FID C 10 906
FID C 11 2277
FID H 12 103
SNT VIA
FID C 3 681
FID C 6 488
FID C 8 673
FID C 10 1212
FID C 11 2583
FID H 12 409
#NET 4
NET GPS1_RX
SNT TOP T 2 0
FID C 2 482
FID C 6 48
FID C 8 236
FID C 10 200
FID C 11 1573
FID H 12 31
SNT TOP T 41 6
FID C 9 274
FID C 10 314
FID C 11 1683
SNT TOP T 77 162
FID C 9 403
FID C 10 443
FID C 11 1812
SNT TRC
FID C 2 154
SNT TRC
FID C 2 147
SNT TRC
FID C 2 248
SNT TRC
FID C 2 246
SNT TRC
FID C 2 247
SNT TRC
FID C 2 255
SNT TRC
FID C 2 174
SNT TRC
FID C 2 173
SNT TRC
FID C 2 257
SNT TRC
FID C 2 244
SNT TRC
FID C 2 286
SNT TRC
FID C 2 249
SNT TRC
FID C 2 245
SNT TRC
FID C 3 266
SNT TRC
FID C 3 282
SNT TRC
FID C 3 232
SNT TRC
FID C 3 375
SNT TRC
FID C 11 394
SNT TRC
FID C 11 376
SNT TRC
FID C 11 563
SNT TRC
FID C 11 564
SNT TRC
FID C 11 573
SNT TRC
FID C 2 32
SNT TRC
FID C 2 1
SNT TRC
FID C 2 36
SNT TRC
FID C 2 28
SNT VIA
FID C 2 543
FID C 3 607
FID C 6 309
FID C 8 494
FID C 10 1033
FID C 11 2404
FID H 12 230
SNT VIA
FID C 2 547
FID C 6 319
FID C 8 504
FID C 10 1043
FID C 11 2414
FID H 12 240
SNT VIA
FID C 3 642
FID C 6 400
FID C 8 585
FID C 10 1124
FID C 11 2495
FID H 12 321
#NET 5
NET NetC44_1
SNT TOP B 14 0
FID C 1 27
FID C 6 62
FID C 8 251
SNT TOP T 76 12
FID C 1 26
FID C 6 61
FID C 8 250
SNT TRC
FID C 8 62
SNT TRC
FID C 8 63
SNT TRC
FID C 8 1
SNT TRC
FID C 8 2
#NET 6
NET NetC45_1
SNT TOP B 13 0
FID C 1 32
FID C 6 67
FID C 8 256
SNT TOP T 76 13
FID C 1 31
FID C 6 66
FID C 8 255
SNT TRC
FID C 8 69
SNT TRC
FID C 8 4
#NET 7
NET NetC46_1
SNT TOP B 12 0
FID C 1 37
FID C 6 77
FID C 8 261
SNT TOP T 76 15
FID C 1 36
FID C 6 76
FID C 8 260
SNT TRC
FID C 8 87
SNT TRC
FID C 8 8
SNT TRC
FID C 8 7
SNT TRC
FID C 8 6
#NET 8
NET NetC47_1
SNT TOP B 11 0
FID C 1 44
FID C 6 84
FID C 8 268
SNT TOP T 76 16
FID C 1 39
FID C 6 79
FID C 8 263
SNT TRC
FID C 8 96
SNT TRC
FID C 8 10
#NET 9
NET NetC48_1
SNT TOP B 10 0
FID C 1 52
FID C 6 92
FID C 8 276
SNT TOP T 76 20
FID C 1 51
FID C 6 91
FID C 8 275
SNT TRC
FID C 8 112
SNT TRC
FID C 8 12
SNT TRC
FID C 8 11
#NET 10
NET NetC50_1
SNT TOP B 8 0
FID C 1 61
FID C 6 101
FID C 8 285
SNT TOP T 76 24
FID C 1 63
FID C 6 103
FID C 8 287
SNT TRC
FID C 8 135
SNT TRC
FID C 8 17
SNT TRC
FID C 8 18
#NET 11
NET NetC51_1
SNT TOP B 7 0
FID C 1 64
FID C 6 104
FID C 8 288
SNT TOP T 76 25
FID C 1 66
FID C 6 106
FID C 8 290
SNT TRC
FID C 8 137
SNT TRC
FID C 8 23
SNT TRC
FID C 8 21
SNT TRC
FID C 8 22
#NET 12
NET NetC52_1
SNT TOP B 6 0
FID C 1 70
FID C 6 110
FID C 8 294
SNT TOP T 76 28
FID C 1 69
FID C 6 109
FID C 8 293
SNT TRC
FID C 8 148
SNT TRC
FID C 8 26
SNT TRC
FID C 8 25
SNT TRC
FID C 8 27
#NET 13
NET NetC53_1
SNT TOP B 5 0
FID C 1 73
FID C 6 116
FID C 8 300
SNT TOP T 76 29
FID C 1 72
FID C 6 115
FID C 8 299
SNT TRC
FID C 8 154
SNT TRC
FID C 8 157
SNT TRC
FID C 8 30
SNT TRC
FID C 8 31
#NET 14
NET NetC72_2
SNT TOP T 16 1
FID C 9 643
FID C 10 697
FID C 11 2064
SNT TOP T 84 1
FID C 9 657
FID C 10 714
FID C 11 2081
SNT TOP T 15 1
FID C 9 652
FID C 10 709
FID C 11 2076
SNT TOP T 83 0
FID C 9 630
FID C 10 683
FID C 11 2050
SNT TRC
FID C 11 1019
SNT TRC
FID C 11 1042
SNT TRC
FID C 11 1038
SNT TRC
FID C 11 1036
SNT TRC
FID C 11 1017
SNT TRC
FID C 11 1009
SNT TRC
FID C 11 1004
SNT TRC
FID C 11 1003
SNT TRC
FID C 11 999
SNT TRC
FID C 11 990
SNT TRC
FID C 11 989
#NET 15
NET NetC85_2
SNT TOP T 28 1
FID C 9 758
FID C 10 833
FID C 11 2200
SNT TOP T 42 26
FID C 9 745
FID C 10 817
FID C 11 2184
SNT TOP T 37 0
FID C 9 781
FID C 10 856
FID C 11 2223
SNT TRC
FID C 11 1280
SNT TRC
FID C 11 1307
SNT TRC
FID C 11 1350
SNT TRC
FID C 11 1342
SNT TRC
FID C 11 1309
#NET 16
NET NetC86_2
SNT TOP T 29 1
FID C 9 759
FID C 10 834
FID C 11 2201
SNT TOP T 42 25
FID C 9 746
FID C 10 818
FID C 11 2185
SNT TOP T 37 3
FID C 9 782
FID C 10 857
FID C 11 2224
SNT TRC
FID C 11 1281
SNT TRC
FID C 11 1293
SNT TRC
FID C 11 1310
SNT TRC
FID C 11 1351
SNT TRC
FID C 11 1343
SNT TRC
FID C 11 1311
#NET 17
NET NetD11_1
SNT TOP T 57 1
FID C 9 14
FID C 10 36
FID C 11 1411
SNT TOP T 93 0
FID C 9 15
FID C 10 37
FID C 11 1412
SNT TRC
FID C 11 62
SNT TRC
FID C 11 63
#NET 18
NET NetD12_1
SNT TOP T 56 1
FID C 9 26
FID C 10 48
FID C 11 1423
SNT TOP T 92 0
FID C 9 27
FID C 10 49
FID C 11 1424
SNT TRC
FID C 11 79
SNT TRC
FID C 11 80
#NET 19
NET NetP2_B17
SNT TOP T 62 1
FID C 9 266
FID C 10 306
FID C 11 1675
SNT TOP T 76 48
FID C 9 268
FID C 10 308
FID C 11 1677
SNT TRC
FID C 11 372
SNT TRC
FID C 11 373
SNT TRC
FID C 11 380
SNT TRC
FID C 11 387
SNT TRC
FID C 11 379
SNT TRC
FID C 11 378
#NET 20
NET NetP2_B31
SNT TOP T 61 1
FID C 9 414
FID C 10 457
FID C 11 1826
SNT TOP T 76 62
FID C 9 416
FID C 10 459
FID C 11 1828
SNT TRC
FID C 11 580
SNT TRC
FID C 11 583
SNT TRC
FID C 11 582
SNT TRC
FID C 11 581
#NET 21
NET NetR3_1
SNT TOP T 73 0
FID C 9 696
FID C 10 768
FID C 11 2135
SNT TOP T 45 6
FID C 9 690
FID C 10 762
FID C 11 2129
SNT TRC
FID C 11 1152
SNT TRC
FID C 11 1155
SNT TRC
FID C 11 1169
#NET 22
NET NetR4_2
SNT TOP T 46 4
FID C 9 787
FID C 10 864
FID C 11 2231
SNT TOP T 71 1
FID C 9 786
FID C 10 863
FID C 11 2230
SNT TOP T 72 1
FID C 9 793
FID C 10 870
FID C 11 2237
SNT TRC
FID C 11 1362
SNT TRC
FID C 11 1365
SNT TRC
FID C 11 1374
SNT TRC
FID C 11 1375
SNT TRC
FID C 11 1359
SNT TRC
FID C 11 1360
SNT TRC
FID C 11 1361
#NET 23
NET NetR5_1
SNT TOP T 36 0
FID C 9 686
FID C 10 758
FID C 11 2125
SNT TOP T 70 1
FID C 9 699
FID C 10 771
FID C 11 2138
SNT TOP T 45 4
FID C 9 692
FID C 10 764
FID C 11 2131
SNT TRC
FID C 11 1171
SNT TRC
FID C 11 1156
SNT TRC
FID C 11 1153
SNT TRC
FID C 11 1149
SNT TRC
FID C 11 1147
SNT TRC
FID C 11 1146
SNT TRC
FID C 11 1145
SNT TRC
FID C 11 1144
SNT TRC
FID C 11 1143
SNT TRC
FID C 11 1141
#NET 24
NET NetR18_2
SNT TOP T 67 1
FID C 9 395
FID C 10 435
FID C 11 1804
SNT TOP T 44 0
FID C 9 396
FID C 10 436
FID C 11 1805
SNT TRC
FID C 11 562
#NET 25
NET NetR20_2
SNT TOP T 65 1
FID C 9 427
FID C 10 470
FID C 11 1839
SNT TOP T 44 4
FID C 9 428
FID C 10 471
FID C 11 1840
SNT TRC
FID C 11 597
#NET 26
NET NetR21_2
SNT TOP T 64 1
FID C 9 450
FID C 10 494
FID C 11 1863
SNT TOP T 44 8
FID C 9 447
FID C 10 491
FID C 11 1860
SNT TRC
FID C 11 650
SNT TRC
FID C 11 654
#NET 27
NET NetR27_2
SNT TOP T 43 10
FID C 9 603
FID C 10 655
FID C 11 2022
SNT TOP T 58 1
FID C 9 629
FID C 10 682
FID C 11 2049
SNT TRC
FID C 11 921
SNT TRC
FID C 11 958
SNT TRC
FID C 11 971
#NET 28
NET NetR32_1
SNT TOP T 49 1
FID C 9 660
FID C 10 717
FID C 11 2084
SNT TOP T 51 1
FID C 9 662
FID C 10 719
FID C 11 2086
SNT TOP T 53 0
FID C 9 661
FID C 10 718
FID C 11 2085
SNT TRC
FID C 11 1059
SNT TRC
FID C 11 1060
SNT TRC
FID C 11 1058
#NET 29
NET NetR33_1
SNT TOP T 50 1
FID C 9 670
FID C 10 732
FID C 11 2099
SNT TOP T 52 0
FID C 9 669
FID C 10 731
FID C 11 2098
SNT TOP T 48 1
FID C 9 668
FID C 10 728
FID C 11 2095
SNT TRC
FID C 11 1093
SNT TRC
FID C 11 1092
SNT TRC
FID C 11 1089
#NET 30
NET NetR42_1
SNT TOP T 32 0
FID C 9 461
FID C 10 505
FID C 11 1874
SNT TOP T 38 4
FID C 9 462
FID C 10 506
FID C 11 1875
SNT TRC
FID C 11 720
SNT TRC
FID C 11 719
#NET 31
NET NetR43_2
SNT TOP T 33 1
FID C 9 163
FID C 10 193
FID C 11 1566
SNT TOP T 34 10
FID C 9 154
FID C 10 184
FID C 11 1557
SNT TRC
FID C 11 253
SNT TRC
FID C 11 233
#NET 32
NET NetU6_3
SNT TOP T 43 2
FID C 9 581
FID C 10 629
FID C 11 1996
SNT TOP T 43 9
FID C 9 602
FID C 10 654
FID C 11 2021
SNT TRC
FID C 8 182
SNT TRC
FID C 8 184
SNT TRC
FID C 8 186
SNT TRC
FID C 11 859
SNT TRC
FID C 11 879
SNT TRC
FID C 11 920
SNT TRC
FID C 11 931
SNT TRC
FID C 11 937
SNT VIA
FID C 6 491
FID C 8 676
FID C 10 1215
FID C 11 2586
FID H 12 412
SNT VIA
FID C 6 509
FID C 8 694
FID C 10 1233
FID C 11 2604
FID H 12 430
#NET 33
NET NetU16_3
SNT TOP T 34 2
FID C 9 102
FID C 10 128
FID C 11 1502
SNT TOP T 34 9
FID C 9 153
FID C 10 183
FID C 11 1556
SNT TRC
FID C 11 169
SNT TRC
FID C 11 170
SNT TRC
FID C 11 184
SNT TRC
FID C 11 210
#NET 34
NET NetJP2_2
SNT TOP T 2 1
FID C 3 550
FID C 6 47
FID C 8 235
FID C 10 199
FID C 11 1572
FID H 12 30
SNT TOP T 34 0
FID C 9 104
FID C 10 130
FID C 11 1504
SNT TRC
FID C 3 159
SNT TRC
FID C 3 127
SNT TRC
FID C 3 132
SNT TRC
FID C 3 160
SNT TRC
FID C 11 149
SNT TRC
FID C 11 152
SNT TRC
FID C 11 166
SNT TRC
FID C 11 150
SNT TRC
FID C 11 148
SNT VIA
FID C 3 567
FID C 6 190
FID C 8 375
FID C 10 914
FID C 11 2285
FID H 12 111
#NET 35
NET NetJP1_2
SNT TOP T 3 1
FID C 6 32
FID C 8 222
FID C 10 80
FID C 11 1455
FID H 12 23
SNT TOP T 34 3
FID C 9 101
FID C 10 127
FID C 11 1501
SNT TRC
FID C 11 143
SNT TRC
FID C 11 142
#NET 36
NET NetJ4_3
SNT TOP T 34 7
FID C 9 97
FID C 10 123
FID C 11 1497
SNT TOP T 35 8
FID C 9 218
FID C 10 253
FID C 11 1627
SNT TRC
FID C 11 174
SNT TRC
FID C 11 173
SNT TRC
FID C 11 167
SNT TRC
FID C 11 175
SNT TRC
FID C 11 291
SNT TRC
FID C 11 316
SNT TRC
FID C 11 188
#NET 37
NET NetJ4_2
SNT TOP T 34 8
FID C 9 152
FID C 10 182
FID C 11 1555
SNT TOP T 35 7
FID C 9 228
FID C 10 263
FID C 11 1637
SNT TRC
FID C 3 154
SNT TRC
FID C 3 155
SNT TRC
FID C 11 232
SNT TRC
FID C 11 246
SNT TRC
FID C 11 247
SNT TRC
FID C 11 323
SNT TRC
FID C 11 324
SNT VIA
FID C 3 577
FID C 6 230
FID C 8 415
FID C 10 954
FID C 11 2325
FID H 12 151
SNT VIA
FID C 3 589
FID C 6 272
FID C 8 457
FID C 10 996
FID C 11 2367
FID H 12 193
#NET 38
NET 5721_STATUS
SNT TOP T 77 147
FID C 9 362
FID C 10 402
FID C 11 1771
SNT TOP T 39 1
FID C 9 506
FID C 10 550
FID C 11 1919
SNT TRC
FID C 2 438
SNT TRC
FID C 2 437
SNT TRC
FID C 3 347
SNT TRC
FID C 3 457
SNT TRC
FID C 3 459
SNT TRC
FID C 3 466
SNT TRC
FID C 11 742
SNT TRC
FID C 11 741
SNT TRC
FID C 11 743
SNT TRC
FID C 11 767
SNT TRC
FID C 11 516
SNT TRC
FID C 11 515
SNT VIA
FID C 2 614
FID C 6 469
FID C 8 654
FID C 10 1193
FID C 11 2564
FID H 12 390
SNT VIA
FID C 2 615
FID C 3 673
FID C 6 470
FID C 8 655
FID C 10 1194
FID C 11 2565
FID H 12 391
SNT VIA
FID C 3 635
FID C 6 377
FID C 8 562
FID C 10 1101
FID C 11 2472
FID H 12 298
#NET 39
NET SDA
SNT TOP T 77 144
FID C 9 355
FID C 10 395
FID C 11 1764
SNT TOP T 0 3
FID C 9 431
FID C 10 474
FID C 11 1843
SNT TOP T 38 9
FID C 9 463
FID C 10 507
FID C 11 1876
SNT TOP T 39 3
FID C 9 452
FID C 10 496
FID C 11 1865
SNT TOP T 12 14
FID C 9 424
FID C 10 467
FID C 11 1836
SNT TRC
FID C 2 423
SNT TRC
FID C 2 422
SNT TRC
FID C 2 420
SNT TRC
FID C 2 418
SNT TRC
FID C 2 421
SNT TRC
FID C 2 419
SNT TRC
FID C 3 349
SNT TRC
FID C 3 344
SNT TRC
FID C 11 721
SNT TRC
FID C 11 605
SNT TRC
FID C 11 609
SNT TRC
FID C 11 611
SNT TRC
FID C 11 626
SNT TRC
FID C 11 600
SNT TRC
FID C 11 589
SNT TRC
FID C 11 724
SNT TRC
FID C 11 722
SNT TRC
FID C 11 726
SNT TRC
FID C 11 643
SNT TRC
FID C 11 723
SNT TRC
FID C 11 625
SNT TRC
FID C 11 606
SNT TRC
FID C 11 604
SNT TRC
FID C 11 610
SNT TRC
FID C 11 699
SNT TRC
FID C 11 644
SNT TRC
FID C 11 666
SNT TRC
FID C 11 668
SNT TRC
FID C 11 669
SNT TRC
FID C 11 670
SNT TRC
FID C 11 507
SNT TRC
FID C 11 511
SNT VIA
FID C 2 609
FID C 3 667
FID C 6 451
FID C 8 636
FID C 10 1175
FID C 11 2546
FID H 12 372
SNT VIA
FID C 2 608
FID C 6 450
FID C 8 635
FID C 10 1174
FID C 11 2545
FID H 12 371
SNT VIA
FID C 2 607
FID C 6 449
FID C 8 634
FID C 10 1173
FID C 11 2544
FID H 12 370
SNT VIA
FID C 3 634
FID C 6 376
FID C 8 561
FID C 10 1100
FID C 11 2471
FID H 12 297
#NET 40
NET SCL
SNT TOP T 77 150
FID C 9 372
FID C 10 412
FID C 11 1781
SNT TOP T 0 1
FID C 9 435
FID C 10 478
FID C 11 1847
SNT TOP T 38 1
FID C 9 457
FID C 10 501
FID C 11 1870
SNT TOP T 39 2
FID C 9 459
FID C 10 503
FID C 11 1872
SNT TOP T 12 15
FID C 9 425
FID C 10 468
FID C 11 1837
SNT TRC
FID C 2 401
SNT TRC
FID C 2 404
SNT TRC
FID C 2 402
SNT TRC
FID C 2 403
SNT TRC
FID C 2 405
SNT TRC
FID C 3 350
SNT TRC
FID C 11 689
SNT TRC
FID C 11 697
SNT TRC
FID C 11 710
SNT TRC
FID C 11 672
SNT TRC
FID C 11 702
SNT TRC
FID C 11 693
SNT TRC
FID C 11 688
SNT TRC
FID C 11 692
SNT TRC
FID C 11 660
SNT TRC
FID C 11 649
SNT TRC
FID C 11 652
SNT TRC
FID C 11 617
SNT TRC
FID C 11 616
SNT TRC
FID C 11 594
SNT TRC
FID C 11 593
SNT TRC
FID C 11 590
SNT TRC
FID C 11 595
SNT TRC
FID C 11 655
SNT TRC
FID C 11 639
SNT TRC
FID C 11 642
SNT TRC
FID C 11 624
SNT TRC
FID C 11 525
SNT TRC
FID C 11 534
SNT TRC
FID C 11 526
SNT VIA
FID C 2 597
FID C 3 656
FID C 6 428
FID C 8 613
FID C 10 1152
FID C 11 2523
FID H 12 349
SNT VIA
FID C 2 598
FID C 6 429
FID C 8 614
FID C 10 1153
FID C 11 2524
FID H 12 350
SNT VIA
FID C 2 599
FID C 6 430
FID C 8 615
FID C 10 1154
FID C 11 2525
FID H 12 351
SNT VIA
FID C 3 637
FID C 6 381
FID C 8 566
FID C 10 1105
FID C 11 2476
FID H 12 302
#NET 41
NET SCK
SNT TOP T 77 28
FID C 9 491
FID C 10 535
FID C 11 1904
SNT TOP T 42 18
FID C 9 741
FID C 10 813
FID C 11 2180
SNT TRC
FID C 2 409
SNT TRC
FID C 2 410
SNT TRC
FID C 2 413
SNT TRC
FID C 2 412
SNT TRC
FID C 3 549
SNT TRC
FID C 3 437
SNT TRC
FID C 3 441
SNT TRC
FID C 11 1265
SNT TRC
FID C 11 1266
SNT TRC
FID C 11 667
SNT TRC
FID C 11 683
SNT TRC
FID C 11 727
SNT VIA
FID C 3 713
FID C 6 570
FID C 8 755
FID C 10 1294
FID C 11 2665
FID H 12 491
SNT VIA
FID C 2 604
FID C 3 665
FID C 6 446
FID C 8 631
FID C 10 1170
FID C 11 2541
FID H 12 367
SNT VIA
FID C 2 602
FID C 6 436
FID C 8 621
FID C 10 1160
FID C 11 2531
FID H 12 357
#NET 42
NET MAC_10Mout
SNT TOP T 40 22
FID C 2 486
FID C 6 143
FID C 8 325
FID C 10 739
FID C 11 2106
FID H 12 64
SNT TOP T 40 20
FID C 2 485
FID C 6 141
FID C 8 323
FID C 10 737
FID C 11 2104
FID H 12 62
SNT TOP T 13 8
FID C 2 484
FID C 6 133
FID C 8 315
FID C 10 704
FID C 11 2071
FID H 12 54
SNT TOP T 4 0
FID C 9 39
FID C 10 61
FID C 11 1436
SNT TOP T 77 96
FID C 9 214
FID C 10 249
FID C 11 1623
SNT TOP T 77 94
FID C 9 210
FID C 10 245
FID C 11 1619
SNT TOP T 77 116
FID C 9 277
FID C 10 317
FID C 11 1686
SNT TRC
FID C 2 475
SNT TRC
FID C 2 476
SNT TRC
FID C 2 473
SNT TRC
FID C 2 472
SNT TRC
FID C 2 471
SNT TRC
FID C 2 479
SNT TRC
FID C 2 480
SNT TRC
FID C 2 478
SNT TRC
FID C 2 477
SNT TRC
FID C 2 474
SNT TRC
FID C 3 227
SNT TRC
FID C 3 98
SNT TRC
FID C 3 225
SNT TRC
FID C 3 95
SNT TRC
FID C 3 93
SNT TRC
FID C 3 94
SNT TRC
FID C 3 187
SNT TRC
FID C 11 107
SNT TRC
FID C 11 99
SNT TRC
FID C 11 98
SNT TRC
FID C 11 1105
SNT TRC
FID C 11 1104
SNT TRC
FID C 11 314
SNT TRC
FID C 11 315
SNT TRC
FID C 11 384
SNT TRC
FID C 11 371
SNT TRC
FID C 11 304
SNT VIA
FID C 2 632
FID C 3 701
FID C 6 540
FID C 8 725
FID C 10 1264
FID C 11 2635
FID H 12 461
SNT VIA
FID C 2 631
FID C 3 700
FID C 6 539
FID C 8 724
FID C 10 1263
FID C 11 2634
FID H 12 460
SNT VIA
FID C 3 554
FID C 6 170
FID C 8 355
FID C 10 894
FID C 11 2265
FID H 12 91
SNT VIA
FID C 3 605
FID C 6 304
FID C 8 489
FID C 10 1028
FID C 11 2399
FID H 12 225
SNT VIA
FID C 3 588
FID C 6 270
FID C 8 455
FID C 10 994
FID C 11 2365
FID H 12 191
#NET 43
NET OE_5356
SNT TOP T 77 89
FID C 9 195
FID C 10 230
FID C 11 1604
SNT TOP T 38 0
FID C 9 454
FID C 10 498
FID C 11 1867
SNT TRC
FID C 2 406
SNT TRC
FID C 2 407
SNT TRC
FID C 2 408
SNT TRC
FID C 2 169
SNT TRC
FID C 2 165
SNT TRC
FID C 3 316
SNT TRC
FID C 3 194
SNT TRC
FID C 3 314
SNT TRC
FID C 3 427
SNT TRC
FID C 3 429
SNT TRC
FID C 3 426
SNT TRC
FID C 3 183
SNT TRC
FID C 3 193
SNT TRC
FID C 11 659
SNT TRC
FID C 11 658
SNT TRC
FID C 11 656
SNT TRC
FID C 11 292
SNT VIA
FID C 2 600
FID C 6 431
FID C 8 616
FID C 10 1155
FID C 11 2526
FID H 12 352
SNT VIA
FID C 2 601
FID C 3 658
FID C 6 433
FID C 8 618
FID C 10 1157
FID C 11 2528
FID H 12 354
SNT VIA
FID C 2 522
FID C 3 585
FID C 6 260
FID C 8 445
FID C 10 984
FID C 11 2355
FID H 12 181
SNT VIA
FID C 2 519
FID C 6 255
FID C 8 440
FID C 10 979
FID C 11 2350
FID H 12 176
#NET 44
NET NetR19_2
SNT TOP T 66 1
FID C 9 411
FID C 10 454
FID C 11 1823
SNT TOP T 44 2
FID C 9 412
FID C 10 455
FID C 11 1824
SNT TRC
FID C 11 577
#NET 45
NET NetR2_1
SNT TOP T 46 6
FID C 9 789
FID C 10 866
FID C 11 2233
SNT TOP T 74 0
FID C 9 784
FID C 10 861
FID C 11 2228
SNT TRC
FID C 11 1363
SNT TRC
FID C 11 1357
SNT TRC
FID C 11 1356
#NET 46
NET NetJ3_3
SNT TOP T 43 7
FID C 9 576
FID C 10 624
FID C 11 1991
SNT TOP T 80 8
FID C 9 586
FID C 10 635
FID C 11 2002
SNT TRC
FID C 11 872
SNT TRC
FID C 11 870
SNT TRC
FID C 11 857
SNT TRC
FID C 11 873
SNT TRC
FID C 11 883
#NET 47
NET NetJ3_2
SNT TOP T 43 8
FID C 9 601
FID C 10 653
FID C 11 2020
SNT TOP T 80 7
FID C 9 587
FID C 10 636
FID C 11 2003
SNT TRC
FID C 11 905
SNT TRC
FID C 11 911
SNT TRC
FID C 11 913
SNT TRC
FID C 11 885
SNT TRC
FID C 11 886
#NET 48
NET NetD14_1
SNT TOP T 54 1
FID C 9 50
FID C 10 72
FID C 11 1447
SNT TOP T 90 0
FID C 9 51
FID C 10 73
FID C 11 1448
SNT TRC
FID C 11 126
SNT TRC
FID C 11 127
#NET 49
NET NetD13_1
SNT TOP T 55 1
FID C 9 42
FID C 10 64
FID C 11 1439
SNT TOP T 91 0
FID C 9 43
FID C 10 65
FID C 11 1440
SNT TRC
FID C 11 112
SNT TRC
FID C 11 113
#NET 50
NET NetD10_1
SNT TOP T 94 0
FID C 9 516
FID C 10 562
FID C 11 1931
SNT TOP T 59 1
FID C 9 561
FID C 10 609
FID C 11 1976
SNT TRC
FID C 11 815
SNT TRC
FID C 11 780
SNT TRC
FID C 11 794
#NET 51
NET NetD9_1
SNT TOP T 60 1
FID C 9 562
FID C 10 610
FID C 11 1977
SNT TOP T 95 0
FID C 9 519
FID C 10 565
FID C 11 1934
SNT TRC
FID C 11 783
SNT TRC
FID C 11 796
SNT TRC
FID C 11 816
#NET 52
NET NetD4_1
SNT TOP T 75 1
FID C 9 638
FID C 10 692
FID C 11 2059
SNT TOP T 100 0
FID C 9 646
FID C 10 700
FID C 11 2067
SNT TRC
FID C 11 1008
#NET 53
NET NetD2_2
SNT TOP T 81 2
FID C 6 150
FID C 8 332
FID C 10 828
FID C 11 2195
FID H 12 71
SNT TOP T 81 3
FID C 6 153
FID C 8 335
FID C 10 860
FID C 11 2227
FID H 12 74
SNT TOP T 81 4
FID C 6 155
FID C 8 337
FID C 10 872
FID C 11 2239
FID H 12 76
SNT TOP T 102 1
FID C 9 709
FID C 10 781
FID C 11 2148
SNT TRC
FID C 11 1296
SNT TRC
FID C 11 1353
SNT TRC
FID C 11 1236
SNT TRC
FID C 11 1273
SNT TRC
FID C 11 1295
SNT TRC
FID C 11 1235
SNT TRC
FID C 11 1227
SNT TRC
FID C 11 1208
#NET 54
NET NetD2_1
SNT TOP T 47 0
FID C 6 145
FID C 8 327
FID C 10 743
FID C 11 2110
FID H 12 66
SNT TOP T 102 0
FID C 9 694
FID C 10 766
FID C 11 2133
SNT TOP T 85 0
FID C 9 684
FID C 10 754
FID C 11 2121
SNT TOP T 101 0
FID C 9 693
FID C 10 765
FID C 11 2132
SNT TRC
FID C 11 1136
SNT TRC
FID C 11 1137
SNT TRC
FID C 11 1154
SNT TRC
FID C 11 1148
SNT TRC
FID C 11 1139
SNT TRC
FID C 11 1119
SNT TRC
FID C 11 1166
SNT TRC
FID C 11 1176
SNT TRC
FID C 11 1167
SNT TRC
FID C 11 1160
SNT TRC
FID C 11 1161
SNT TRC
FID C 11 1165
SNT TRC
FID C 11 1159
SNT TRC
FID C 11 1158
SNT TRC
FID C 11 1163
SNT TRC
FID C 11 1164
SNT TRC
FID C 11 1114
SNT TRC
FID C 11 1138
#NET 55
NET NetD1_2
SNT TOP T 82 0
FID C 6 147
FID C 8 329
FID C 10 756
FID C 11 2123
FID H 12 68
SNT TOP T 103 1
FID C 9 680
FID C 10 750
FID C 11 2117
SNT TRC
FID C 11 1129
SNT TRC
FID C 11 1135
SNT TRC
FID C 11 1140
#NET 56
NET NetD1_1
SNT TOP T 47 1
FID C 6 144
FID C 8 326
FID C 10 742
FID C 11 2109
FID H 12 65
SNT TOP T 103 0
FID C 9 677
FID C 10 746
FID C 11 2113
SNT TRC
FID C 11 1122
SNT TRC
FID C 11 1113
SNT TRC
FID C 11 1116
SNT TRC
FID C 11 1112
SNT TRC
FID C 11 1121
#NET 57
NET NetC49_1
SNT TOP B 9 0
FID C 1 55
FID C 6 95
FID C 8 279
SNT TOP T 76 21
FID C 1 54
FID C 6 94
FID C 8 278
SNT TRC
FID C 8 115
SNT TRC
FID C 8 118
SNT TRC
FID C 8 15
SNT TRC
FID C 8 14
#NET 58
NET NetC22_2
SNT TOP T 68 1
FID C 9 678
FID C 10 748
FID C 11 2115
SNT TOP T 117 1
FID C 9 683
FID C 10 753
FID C 11 2120
SNT TRC
FID C 11 1132
SNT TRC
FID C 11 1130
SNT TRC
FID C 11 1126
SNT TRC
FID C 11 1128
#NET 59
NET NetC22_1
SNT TOP T 117 0
FID C 9 682
FID C 10 752
FID C 11 2119
SNT TOP T 45 5
FID C 9 691
FID C 10 763
FID C 11 2130
SNT TRC
FID C 11 1134
SNT TRC
FID C 11 1133
#NET 60
NET NetC21_2
SNT TOP T 118 1
FID C 9 688
FID C 10 760
FID C 11 2127
SNT TOP T 45 7
FID C 9 689
FID C 10 761
FID C 11 2128
SNT TRC
FID C 11 1151
SNT TRC
FID C 11 1150
#NET 61
NET NetC20_2
SNT TOP T 69 1
FID C 9 799
FID C 10 879
FID C 11 2246
SNT TOP T 119 1
FID C 9 795
FID C 10 875
FID C 11 2242
SNT TRC
FID C 11 1381
SNT TRC
FID C 11 1378
#NET 62
NET NetC20_1
SNT TOP T 46 5
FID C 9 788
FID C 10 865
FID C 11 2232
SNT TOP T 119 0
FID C 9 796
FID C 10 876
FID C 11 2243
SNT TRC
FID C 11 1377
SNT TRC
FID C 11 1366
#NET 63
NET NetC19_2
SNT TOP T 46 7
FID C 9 790
FID C 10 867
FID C 11 2234
SNT TOP T 120 1
FID C 9 792
FID C 10 869
FID C 11 2236
SNT TRC
FID C 11 1372
SNT TRC
FID C 11 1368
SNT TRC
FID C 11 1367
#NET 64
NET NetC4_2
SNT TOP T 46 2
FID C 9 764
FID C 10 839
FID C 11 2206
SNT TOP T 79 1
FID C 9 701
FID C 10 773
FID C 11 2140
SNT TOP T 135 1
FID C 9 753
FID C 10 825
FID C 11 2192
SNT TRC
FID C 11 1284
SNT TRC
FID C 11 1285
SNT TRC
FID C 11 1288
SNT TRC
FID C 11 1195
SNT TRC
FID C 11 1223
SNT TRC
FID C 11 1269
#NET 65
NET NetC4_1
SNT TOP T 46 0
FID C 9 766
FID C 10 841
FID C 11 2208
SNT TOP T 135 0
FID C 9 754
FID C 10 826
FID C 11 2193
SNT TRC
FID C 11 1286
SNT TRC
FID C 11 1287
#NET 66
NET NetC3_2
SNT TOP T 136 1
FID C 9 739
FID C 10 811
FID C 11 2178
SNT TOP T 78 1
FID C 9 777
FID C 10 852
FID C 11 2219
SNT TOP T 45 2
FID C 9 712
FID C 10 784
FID C 11 2151
SNT TRC
FID C 11 1211
SNT TRC
FID C 11 1231
SNT TRC
FID C 11 1244
SNT TRC
FID C 11 1261
SNT TRC
FID C 11 1322
SNT TRC
FID C 11 1334
#NET 67
NET NetC3_1
SNT TOP T 136 0
FID C 9 738
FID C 10 810
FID C 11 2177
SNT TOP T 45 0
FID C 9 710
FID C 10 782
FID C 11 2149
SNT TRC
FID C 11 1259
SNT TRC
FID C 11 1210
#NET 68
NET MOSI
SNT TOP T 77 24
FID C 9 493
FID C 10 537
FID C 11 1906
SNT TOP T 42 16
FID C 9 735
FID C 10 807
FID C 11 2174
SNT TRC
FID C 2 395
SNT TRC
FID C 2 396
SNT TRC
FID C 2 397
SNT TRC
FID C 3 468
SNT TRC
FID C 3 470
SNT TRC
FID C 3 413
SNT TRC
FID C 11 1249
SNT TRC
FID C 11 1243
SNT TRC
FID C 11 1233
SNT TRC
FID C 11 641
SNT TRC
FID C 11 712
SNT TRC
FID C 11 661
SNT VIA
FID C 3 709
FID C 6 563
FID C 8 748
FID C 10 1287
FID C 11 2658
FID H 12 484
SNT VIA
FID C 2 595
FID C 3 655
FID C 6 425
FID C 8 610
FID C 10 1149
FID C 11 2520
FID H 12 346
SNT VIA
FID C 2 594
FID C 6 424
FID C 8 609
FID C 10 1148
FID C 11 2519
FID H 12 345
#NET 69
NET MISO
SNT TOP T 77 26
FID C 9 492
FID C 10 536
FID C 11 1905
SNT TOP T 42 19
FID C 9 752
FID C 10 824
FID C 11 2191
SNT TRC
FID C 2 417
SNT TRC
FID C 2 415
SNT TRC
FID C 2 414
SNT TRC
FID C 2 416
SNT TRC
FID C 3 445
SNT TRC
FID C 11 1282
SNT TRC
FID C 11 1275
SNT TRC
FID C 11 704
SNT TRC
FID C 11 728
SNT VIA
FID C 2 606
FID C 3 666
FID C 6 448
FID C 8 633
FID C 10 1172
FID C 11 2543
FID H 12 369
SNT VIA
FID C 3 714
FID C 6 571
FID C 8 756
FID C 10 1295
FID C 11 2666
FID H 12 492
SNT VIA
FID C 2 605
FID C 6 447
FID C 8 632
FID C 10 1171
FID C 11 2542
FID H 12 368
#NET 70
NET MAC_USB_PWR
SNT TOP T 77 91
FID C 9 200
FID C 10 235
FID C 11 1609
SNT TOP T 40 5
FID C 9 590
FID C 10 639
FID C 11 2006
SNT TRC
FID C 2 170
SNT TRC
FID C 2 171
SNT TRC
FID C 2 172
SNT TRC
FID C 3 501
SNT TRC
FID C 3 509
SNT TRC
FID C 3 499
SNT TRC
FID C 3 464
SNT TRC
FID C 3 456
SNT TRC
FID C 3 184
SNT TRC
FID C 11 914
SNT TRC
FID C 11 893
SNT TRC
FID C 11 929
SNT TRC
FID C 11 930
SNT TRC
FID C 11 889
SNT TRC
FID C 11 296
SNT VIA
FID C 2 524
FID C 3 586
FID C 6 262
FID C 8 447
FID C 10 986
FID C 11 2357
FID H 12 183
SNT VIA
FID C 3 689
FID C 6 506
FID C 8 691
FID C 10 1230
FID C 11 2601
FID H 12 427
SNT VIA
FID C 2 523
FID C 6 261
FID C 8 446
FID C 10 985
FID C 11 2356
FID H 12 182
#NET 71
NET MAC_USB-
SNT TOP T 77 157
FID C 9 386
FID C 10 426
FID C 11 1795
SNT TOP T 40 3
FID C 9 589
FID C 10 638
FID C 11 2005
SNT TRC
FID C 2 350
SNT TRC
FID C 2 351
SNT TRC
FID C 3 496
SNT TRC
FID C 3 373
SNT TRC
FID C 3 497
SNT TRC
FID C 3 516
SNT TRC
FID C 3 513
SNT TRC
FID C 3 512
SNT TRC
FID C 3 507
SNT TRC
FID C 11 892
SNT TRC
FID C 11 924
SNT TRC
FID C 11 912
SNT TRC
FID C 11 888
SNT TRC
FID C 11 556
SNT TRC
FID C 11 557
SNT TRC
FID C 11 558
SNT VIA
FID C 2 578
FID C 3 640
FID C 6 395
FID C 8 580
FID C 10 1119
FID C 11 2490
FID H 12 316
SNT VIA
FID C 3 688
FID C 6 504
FID C 8 689
FID C 10 1228
FID C 11 2599
FID H 12 425
SNT VIA
FID C 2 579
FID C 6 396
FID C 8 581
FID C 10 1120
FID C 11 2491
FID H 12 317
#NET 72
NET MAC_USB+
SNT TOP T 77 155
FID C 9 382
FID C 10 422
FID C 11 1791
SNT TOP T 40 1
FID C 9 588
FID C 10 637
FID C 11 2004
SNT TRC
FID C 2 349
SNT TRC
FID C 3 491
SNT TRC
FID C 3 498
SNT TRC
FID C 3 485
SNT TRC
FID C 3 418
SNT TRC
FID C 3 422
SNT TRC
FID C 3 356
SNT TRC
FID C 3 500
SNT TRC
FID C 3 505
SNT TRC
FID C 3 510
SNT TRC
FID C 11 903
SNT TRC
FID C 11 915
SNT TRC
FID C 11 887
SNT TRC
FID C 11 898
SNT TRC
FID C 11 899
SNT TRC
FID C 11 551
SNT TRC
FID C 11 543
SNT TRC
FID C 11 544
SNT VIA
FID C 2 576
FID C 3 638
FID C 6 391
FID C 8 576
FID C 10 1115
FID C 11 2486
FID H 12 312
SNT VIA
FID C 3 687
FID C 6 503
FID C 8 688
FID C 10 1227
FID C 11 2598
FID H 12 424
SNT VIA
FID C 2 577
FID C 6 392
FID C 8 577
FID C 10 1116
FID C 11 2487
FID H 12 313
#NET 73
NET MAC_TX
SNT TOP T 40 27
FID C 3 552
FID C 6 131
FID C 8 313
FID C 10 702
FID C 11 2069
FID H 12 52
SNT TOP T 13 2
FID C 6 137
FID C 8 319
FID C 10 729
FID C 11 2096
FID H 12 58
SNT TOP T 10 0
FID C 9 53
FID C 10 75
FID C 11 1450
SNT TOP T 77 109
FID C 9 253
FID C 10 293
FID C 11 1662
SNT TRC
FID C 3 527
SNT TRC
FID C 3 229
SNT TRC
FID C 3 134
SNT TRC
FID C 3 115
SNT TRC
FID C 3 180
SNT TRC
FID C 3 224
SNT TRC
FID C 3 188
SNT TRC
FID C 3 114
SNT TRC
FID C 3 117
SNT TRC
FID C 3 118
SNT TRC
FID C 3 119
SNT TRC
FID C 3 116
SNT TRC
FID C 11 1027
SNT TRC
FID C 11 138
SNT TRC
FID C 11 135
SNT TRC
FID C 11 356
SNT TRC
FID C 11 355
SNT TRC
FID C 11 365
SNT TRC
FID C 11 369
SNT TRC
FID C 11 350
SNT TRC
FID C 11 351
SNT TRC
FID C 11 1073
SNT TRC
FID C 11 1088
SNT TRC
FID C 11 1087
SNT VIA
FID C 3 562
FID C 6 183
FID C 8 368
FID C 10 907
FID C 11 2278
FID H 12 104
SNT VIA
FID C 3 604
FID C 6 303
FID C 8 488
FID C 10 1027
FID C 11 2398
FID H 12 224
#NET 74
NET MAC_RX
SNT TOP T 40 26
FID C 3 551
FID C 6 130
FID C 8 312
FID C 10 689
FID C 11 2056
FID H 12 51
SNT TOP T 13 3
FID C 6 139
FID C 8 321
FID C 10 735
FID C 11 2102
FID H 12 60
SNT TOP T 8 0
FID C 9 184
FID C 10 219
FID C 11 1593
SNT TOP T 77 111
FID C 9 259
FID C 10 299
FID C 11 1668
SNT TRC
FID C 2 166
SNT TRC
FID C 2 236
SNT TRC
FID C 2 192
SNT TRC
FID C 2 167
SNT TRC
FID C 2 190
SNT TRC
FID C 2 191
SNT TRC
FID C 2 193
SNT TRC
FID C 2 194
SNT TRC
FID C 3 523
SNT TRC
FID C 3 223
SNT TRC
FID C 11 1001
SNT TRC
FID C 11 1020
SNT TRC
FID C 11 290
SNT TRC
FID C 11 283
SNT TRC
FID C 11 362
SNT TRC
FID C 11 361
SNT TRC
FID C 11 1075
SNT TRC
FID C 11 1091
SNT TRC
FID C 11 1103
SNT TRC
FID C 11 1090
SNT TRC
FID C 11 370
SNT VIA
FID C 2 520
FID C 6 257
FID C 8 442
FID C 10 981
FID C 11 2352
FID H 12 178
SNT VIA
FID C 2 540
FID C 3 603
FID C 6 302
FID C 8 487
FID C 10 1026
FID C 11 2397
FID H 12 223
#NET 75
NET MAC_PPS_OUT-
SNT TOP T 77 126
FID C 9 300
FID C 10 340
FID C 11 1709
SNT TOP T 40 18
FID C 9 624
FID C 10 677
FID C 11 2044
SNT TRC
FID C 2 262
SNT TRC
FID C 2 263
SNT TRC
FID C 2 264
SNT TRC
FID C 2 265
SNT TRC
FID C 3 517
SNT TRC
FID C 3 514
SNT TRC
FID C 3 480
SNT TRC
FID C 3 478
SNT TRC
FID C 3 450
SNT TRC
FID C 3 446
SNT TRC
FID C 3 291
SNT TRC
FID C 3 286
SNT TRC
FID C 3 287
SNT TRC
FID C 11 945
SNT TRC
FID C 11 950
SNT TRC
FID C 11 946
SNT TRC
FID C 11 415
SNT TRC
FID C 11 412
SNT TRC
FID C 11 413
SNT VIA
FID C 2 553
FID C 3 618
FID C 6 333
FID C 8 518
FID C 10 1057
FID C 11 2428
FID H 12 254
SNT VIA
FID C 3 692
FID C 6 511
FID C 8 696
FID C 10 1235
FID C 11 2606
FID H 12 432
SNT VIA
FID C 2 551
FID C 6 331
FID C 8 516
FID C 10 1055
FID C 11 2426
FID H 12 252
#NET 76
NET MAC_PPS_OUT+
SNT TOP T 13 7
FID C 6 134
FID C 8 316
FID C 10 722
FID C 11 2089
FID H 12 55
SNT TOP T 5 0
FID C 9 37
FID C 10 59
FID C 11 1434
SNT TOP T 77 124
FID C 9 295
FID C 10 335
FID C 11 1704
SNT TOP T 40 16
FID C 9 623
FID C 10 676
FID C 11 2043
SNT TRC
FID C 2 259
SNT TRC
FID C 3 273
SNT TRC
FID C 3 460
SNT TRC
FID C 3 461
SNT TRC
FID C 3 524
SNT TRC
FID C 3 525
SNT TRC
FID C 3 256
SNT TRC
FID C 3 96
SNT TRC
FID C 11 103
SNT TRC
FID C 11 102
SNT TRC
FID C 11 95
SNT TRC
FID C 11 94
SNT TRC
FID C 11 403
SNT TRC
FID C 11 402
SNT TRC
FID C 11 401
SNT TRC
FID C 11 985
SNT TRC
FID C 11 998
SNT TRC
FID C 11 972
SNT TRC
FID C 11 956
SNT TRC
FID C 11 978
SNT TRC
FID C 11 983
SNT VIA
FID C 2 550
FID C 3 615
FID C 6 326
FID C 8 511
FID C 10 1050
FID C 11 2421
FID H 12 247
SNT VIA
FID C 3 694
FID C 6 519
FID C 8 704
FID C 10 1243
FID C 11 2614
FID H 12 440
SNT VIA
FID C 3 553
FID C 6 168
FID C 8 353
FID C 10 892
FID C 11 2263
FID H 12 89
SNT VIA
FID C 2 549
FID C 6 325
FID C 8 510
FID C 10 1049
FID C 11 2420
FID H 12 246
#NET 77
NET MAC_PPS_IN1-
SNT TOP T 77 136
FID C 9 326
FID C 10 366
FID C 11 1735
SNT TOP T 40 2
FID C 9 616
FID C 10 669
FID C 11 2036
SNT TRC
FID C 2 298
SNT TRC
FID C 2 299
SNT TRC
FID C 2 300
SNT TRC
FID C 3 526
SNT TRC
FID C 3 479
SNT TRC
FID C 3 506
SNT TRC
FID C 3 508
SNT TRC
FID C 3 318
SNT TRC
FID C 3 390
SNT TRC
FID C 3 477
SNT TRC
FID C 3 388
SNT TRC
FID C 11 986
SNT TRC
FID C 11 975
SNT TRC
FID C 11 952
SNT TRC
FID C 11 1000
SNT TRC
FID C 11 469
SNT TRC
FID C 11 476
SNT TRC
FID C 11 470
SNT VIA
FID C 2 566
FID C 3 627
FID C 6 356
FID C 8 541
FID C 10 1080
FID C 11 2451
FID H 12 277
SNT VIA
FID C 3 696
FID C 6 522
FID C 8 707
FID C 10 1246
FID C 11 2617
FID H 12 443
SNT VIA
FID C 2 567
FID C 6 361
FID C 8 546
FID C 10 1085
FID C 11 2456
FID H 12 282
#NET 78
NET MAC_PPS_IN1+
SNT TOP T 77 134
FID C 9 321
FID C 10 361
FID C 11 1730
SNT TOP T 40 0
FID C 9 615
FID C 10 668
FID C 11 2035
SNT TRC
FID C 2 292
SNT TRC
FID C 2 294
SNT TRC
FID C 2 293
SNT TRC
FID C 3 515
SNT TRC
FID C 3 462
SNT TRC
FID C 3 455
SNT TRC
FID C 3 315
SNT TRC
FID C 11 944
SNT TRC
FID C 11 943
SNT TRC
FID C 11 949
SNT TRC
FID C 11 465
SNT TRC
FID C 11 462
SNT TRC
FID C 11 461
SNT TRC
FID C 11 459
SNT TRC
FID C 11 458
SNT VIA
FID C 2 562
FID C 3 626
FID C 6 352
FID C 8 537
FID C 10 1076
FID C 11 2447
FID H 12 273
SNT VIA
FID C 3 691
FID C 6 510
FID C 8 695
FID C 10 1234
FID C 11 2605
FID H 12 431
SNT VIA
FID C 2 563
FID C 6 353
FID C 8 538
FID C 10 1077
FID C 11 2448
FID H 12 274
#NET 79
NET MAC_PPS_IN0-
SNT TOP T 77 130
FID C 9 311
FID C 10 351
FID C 11 1720
SNT TOP T 40 6
FID C 9 618
FID C 10 671
FID C 11 2038
SNT TRC
FID C 2 284
SNT TRC
FID C 2 285
SNT TRC
FID C 3 487
SNT TRC
FID C 3 305
SNT TRC
FID C 3 486
SNT TRC
FID C 3 306
SNT TRC
FID C 11 984
SNT TRC
FID C 11 980
SNT TRC
FID C 11 954
SNT TRC
FID C 11 435
SNT TRC
FID C 11 434
SNT VIA
FID C 2 559
FID C 3 623
FID C 6 344
FID C 8 529
FID C 10 1068
FID C 11 2439
FID H 12 265
SNT VIA
FID C 3 693
FID C 6 518
FID C 8 703
FID C 10 1242
FID C 11 2613
FID H 12 439
SNT VIA
FID C 2 558
FID C 6 343
FID C 8 528
FID C 10 1067
FID C 11 2438
FID H 12 264
#NET 80
NET MAC_PPS_IN0+
SNT TOP T 13 6
FID C 6 136
FID C 8 318
FID C 10 726
FID C 11 2093
FID H 12 57
SNT TOP T 6 0
FID C 9 40
FID C 10 62
FID C 11 1437
SNT TOP T 7 1
FID C 9 236
FID C 10 271
FID C 11 1645
SNT TOP T 77 128
FID C 9 306
FID C 10 346
FID C 11 1715
SNT TOP T 40 4
FID C 9 617
FID C 10 670
FID C 11 2037
SNT TRC
FID C 2 279
SNT TRC
FID C 2 278
SNT TRC
FID C 2 276
SNT TRC
FID C 2 280
SNT TRC
FID C 2 273
SNT TRC
FID C 2 274
SNT TRC
FID C 2 277
SNT TRC
FID C 2 275
SNT TRC
FID C 2 271
SNT TRC
FID C 2 283
SNT TRC
FID C 2 270
SNT TRC
FID C 2 272
SNT TRC
FID C 3 447
SNT TRC
FID C 3 444
SNT TRC
FID C 3 297
SNT TRC
FID C 3 277
SNT TRC
FID C 3 288
SNT TRC
FID C 3 298
SNT TRC
FID C 3 235
SNT TRC
FID C 3 238
SNT TRC
FID C 3 222
SNT TRC
FID C 3 136
SNT TRC
FID C 3 218
SNT TRC
FID C 3 135
SNT TRC
FID C 3 97
SNT TRC
FID C 11 953
SNT TRC
FID C 11 976
SNT TRC
FID C 11 988
SNT TRC
FID C 11 981
SNT TRC
FID C 11 1083
SNT TRC
FID C 11 100
SNT TRC
FID C 11 105
SNT TRC
FID C 11 101
SNT TRC
FID C 11 106
SNT TRC
FID C 11 325
SNT TRC
FID C 11 327
SNT TRC
FID C 11 428
SNT TRC
FID C 11 426
SNT TRC
FID C 11 427
SNT TRC
FID C 11 991
SNT TRC
FID C 11 1021
SNT TRC
FID C 11 354
SNT TRC
FID C 11 449
SNT TRC
FID C 11 326
SNT TRC
FID C 11 4
SNT TRC
FID C 11 21
SNT VIA
FID C 2 555
FID C 3 619
FID C 6 337
FID C 8 522
FID C 10 1061
FID C 11 2432
FID H 12 258
SNT VIA
FID C 3 695
FID C 6 520
FID C 8 705
FID C 10 1244
FID C 11 2615
FID H 12 441
SNT VIA
FID C 3 555
FID C 6 171
FID C 8 356
FID C 10 895
FID C 11 2266
FID H 12 92
SNT VIA
FID C 2 556
FID C 3 620
FID C 6 338
FID C 8 523
FID C 10 1062
FID C 11 2433
FID H 12 259
SNT VIA
FID C 2 561
FID C 6 351
FID C 8 536
FID C 10 1075
FID C 11 2446
FID H 12 272
#NET 81
NET NetBT1_2
SNT TOP T 14 1
FID C 9 665
FID C 10 723
FID C 11 2090
SNT TOP T 12 13
FID C 9 423
FID C 10 466
FID C 11 1835
SNT TRC
FID C 3 443
SNT TRC
FID C 3 476
SNT TRC
FID C 3 394
SNT TRC
FID C 3 404
SNT TRC
FID C 3 402
SNT TRC
FID C 3 528
SNT TRC
FID C 11 601
SNT TRC
FID C 11 591
SNT TRC
FID C 11 588
SNT TRC
FID C 11 1071
SNT TRC
FID C 11 1072
SNT TRC
FID C 11 1076
SNT TRC
FID C 11 1074
SNT VIA
FID C 3 648
FID C 6 412
FID C 8 597
FID C 10 1136
FID C 11 2507
FID H 12 333
SNT VIA
FID C 3 698
FID C 6 535
FID C 8 720
FID C 10 1259
FID C 11 2630
FID H 12 456
#NET 82
NET MAC_BITE
SNT TOP T 40 25
FID C 2 483
FID C 6 129
FID C 8 311
FID C 10 665
FID C 11 2032
FID H 12 50
SNT TOP T 13 1
FID C 6 135
FID C 8 317
FID C 10 725
FID C 11 2092
FID H 12 56
SNT TOP T 77 120
FID C 9 286
FID C 10 326
FID C 11 1695
SNT TRC
FID C 2 470
SNT TRC
FID C 2 469
SNT TRC
FID C 3 255
SNT TRC
FID C 3 246
SNT TRC
FID C 3 253
SNT TRC
FID C 11 1084
SNT TRC
FID C 11 1081
SNT TRC
FID C 11 1086
SNT TRC
FID C 11 942
SNT TRC
FID C 11 1005
SNT TRC
FID C 11 393
SNT TRC
FID C 11 392
SNT VIA
FID C 2 630
FID C 3 690
FID C 6 507
FID C 8 692
FID C 10 1231
FID C 11 2602
FID H 12 428
SNT VIA
FID C 3 610
FID C 6 315
FID C 8 500
FID C 10 1039
FID C 11 2410
FID H 12 236
#NET 83
NET MAC_ALARM
SNT TOP T 77 118
FID C 9 282
FID C 10 322
FID C 11 1691
SNT TOP T 40 19
FID C 9 597
FID C 10 646
FID C 11 2013
SNT TRC
FID C 2 256
SNT TRC
FID C 3 471
SNT TRC
FID C 3 469
SNT TRC
FID C 3 449
SNT TRC
FID C 3 442
SNT TRC
FID C 3 299
SNT TRC
FID C 3 252
SNT TRC
FID C 3 294
SNT TRC
FID C 11 894
SNT TRC
FID C 11 895
SNT TRC
FID C 11 891
SNT TRC
FID C 11 896
SNT TRC
FID C 11 391
SNT TRC
FID C 11 390
SNT VIA
FID C 2 545
FID C 3 612
FID C 6 317
FID C 8 502
FID C 10 1041
FID C 11 2412
FID H 12 238
SNT VIA
FID C 3 686
FID C 6 500
FID C 8 685
FID C 10 1224
FID C 11 2595
FID H 12 421
SNT VIA
FID C 2 546
FID C 6 318
FID C 8 503
FID C 10 1042
FID C 11 2413
FID H 12 239
#NET 84
NET IMU_PS1
SNT TOP T 77 59
FID C 9 532
FID C 10 580
FID C 11 1947
SNT TOP T 42 4
FID C 9 731
FID C 10 803
FID C 11 2170
SNT TRC
FID C 2 468
SNT TRC
FID C 2 466
SNT TRC
FID C 2 465
SNT TRC
FID C 2 467
SNT TRC
FID C 3 538
SNT TRC
FID C 3 537
SNT TRC
FID C 3 520
SNT TRC
FID C 3 504
SNT TRC
FID C 3 503
SNT TRC
FID C 3 502
SNT TRC
FID C 3 519
SNT TRC
FID C 11 1190
SNT TRC
FID C 11 1234
SNT TRC
FID C 11 1237
SNT TRC
FID C 11 897
SNT TRC
FID C 11 871
SNT TRC
FID C 11 803
SNT TRC
FID C 11 862
SNT VIA
FID C 2 629
FID C 3 685
FID C 6 499
FID C 8 684
FID C 10 1223
FID C 11 2594
FID H 12 420
SNT VIA
FID C 3 704
FID C 6 551
FID C 8 736
FID C 10 1275
FID C 11 2646
FID H 12 472
SNT VIA
FID C 2 628
FID C 6 498
FID C 8 683
FID C 10 1222
FID C 11 2593
FID H 12 419
#NET 85
NET IMU_PS0
SNT TOP T 77 57
FID C 9 533
FID C 10 581
FID C 11 1948
SNT TOP T 42 5
FID C 9 721
FID C 10 793
FID C 11 2160
SNT TRC
FID C 2 462
SNT TRC
FID C 2 464
SNT TRC
FID C 2 460
SNT TRC
FID C 2 459
SNT TRC
FID C 2 461
SNT TRC
FID C 3 541
SNT TRC
FID C 3 522
SNT TRC
FID C 3 540
SNT TRC
FID C 3 495
SNT TRC
FID C 3 494
SNT TRC
FID C 3 493
SNT TRC
FID C 3 521
SNT TRC
FID C 11 1206
SNT TRC
FID C 11 1205
SNT TRC
FID C 11 867
SNT TRC
FID C 11 804
SNT TRC
FID C 11 869
SNT VIA
FID C 2 625
FID C 3 684
FID C 6 494
FID C 8 679
FID C 10 1218
FID C 11 2589
FID H 12 415
SNT VIA
FID C 3 707
FID C 6 554
FID C 8 739
FID C 10 1278
FID C 11 2649
FID H 12 475
SNT VIA
FID C 2 627
FID C 6 497
FID C 8 682
FID C 10 1221
FID C 11 2592
FID H 12 418
#NET 86
NET IMU_NRST
SNT TOP T 77 51
FID C 9 536
FID C 10 584
FID C 11 1951
SNT TOP T 42 10
FID C 9 726
FID C 10 798
FID C 11 2165
SNT TRC
FID C 2 453
SNT TRC
FID C 2 446
SNT TRC
FID C 2 445
SNT TRC
FID C 2 447
SNT TRC
FID C 2 450
SNT TRC
FID C 3 490
SNT TRC
FID C 3 533
SNT TRC
FID C 3 536
SNT TRC
FID C 11 1184
SNT TRC
FID C 11 1189
SNT TRC
FID C 11 1207
SNT TRC
FID C 11 1209
SNT TRC
FID C 11 874
SNT TRC
FID C 11 854
SNT TRC
FID C 11 875
SNT TRC
FID C 11 819
SNT TRC
FID C 11 832
SNT TRC
FID C 11 805
SNT VIA
FID C 2 622
FID C 3 682
FID C 6 489
FID C 8 674
FID C 10 1213
FID C 11 2584
FID H 12 410
SNT VIA
FID C 3 702
FID C 6 548
FID C 8 733
FID C 10 1272
FID C 11 2643
FID H 12 469
SNT VIA
FID C 2 621
FID C 6 487
FID C 8 672
FID C 10 1211
FID C 11 2582
FID H 12 408
#NET 87
NET IMU_INT
SNT TOP T 77 49
FID C 9 537
FID C 10 585
FID C 11 1952
SNT TOP T 42 13
FID C 9 729
FID C 10 801
FID C 11 2168
SNT TRC
FID C 2 448
SNT TRC
FID C 2 449
SNT TRC
FID C 2 444
SNT TRC
FID C 2 443
SNT TRC
FID C 3 532
SNT TRC
FID C 3 484
SNT TRC
FID C 3 482
SNT TRC
FID C 3 481
SNT TRC
FID C 3 531
SNT TRC
FID C 11 1202
SNT TRC
FID C 11 1201
SNT TRC
FID C 11 1228
SNT TRC
FID C 11 1226
SNT TRC
FID C 11 1203
SNT TRC
FID C 11 1204
SNT TRC
FID C 11 1214
SNT TRC
FID C 11 806
SNT TRC
FID C 11 835
SNT TRC
FID C 11 849
SNT TRC
FID C 11 820
SNT TRC
FID C 11 860
SNT VIA
FID C 2 618
FID C 3 679
FID C 6 482
FID C 8 667
FID C 10 1206
FID C 11 2577
FID H 12 403
SNT VIA
FID C 3 706
FID C 6 553
FID C 8 738
FID C 10 1277
FID C 11 2648
FID H 12 474
SNT VIA
FID C 2 619
FID C 6 484
FID C 8 669
FID C 10 1208
FID C 11 2579
FID H 12 405
#NET 88
NET IMU_ENV_SDA
SNT TOP T 77 200
FID C 9 127
FID C 10 157
FID C 11 1529
SNT TOP T 42 15
FID C 9 732
FID C 10 804
FID C 11 2171
SNT TRC
FID C 2 442
SNT TRC
FID C 2 440
SNT TRC
FID C 2 441
SNT TRC
FID C 2 439
SNT TRC
FID C 3 546
SNT TRC
FID C 3 545
SNT TRC
FID C 3 399
SNT TRC
FID C 3 414
SNT TRC
FID C 3 415
SNT TRC
FID C 3 149
SNT TRC
FID C 3 151
SNT TRC
FID C 3 467
SNT TRC
FID C 3 465
SNT TRC
FID C 3 395
SNT TRC
FID C 3 434
SNT TRC
FID C 3 435
SNT TRC
FID C 3 148
SNT TRC
FID C 3 143
SNT TRC
FID C 3 475
SNT TRC
FID C 3 474
SNT TRC
FID C 3 473
SNT TRC
FID C 3 472
SNT TRC
FID C 11 1240
SNT TRC
FID C 11 1239
SNT TRC
FID C 11 1238
SNT TRC
FID C 11 844
SNT TRC
FID C 11 215
SNT VIA
FID C 3 711
FID C 6 566
FID C 8 751
FID C 10 1290
FID C 11 2661
FID H 12 487
SNT VIA
FID C 2 617
FID C 3 678
FID C 6 480
FID C 8 665
FID C 10 1204
FID C 11 2575
FID H 12 401
SNT VIA
FID C 2 616
FID C 3 674
FID C 6 472
FID C 8 657
FID C 10 1196
FID C 11 2567
FID H 12 393
SNT VIA
FID C 3 572
FID C 6 217
FID C 8 402
FID C 10 941
FID C 11 2312
FID H 12 138
#NET 89
NET IMU_ENV_SCL
SNT TOP T 77 194
FID C 9 124
FID C 10 154
FID C 11 1526
SNT TOP T 42 14
FID C 9 730
FID C 10 802
FID C 11 2169
SNT TRC
FID C 2 433
SNT TRC
FID C 2 436
SNT TRC
FID C 2 435
SNT TRC
FID C 2 434
SNT TRC
FID C 2 432
SNT TRC
FID C 2 431
SNT TRC
FID C 3 436
SNT TRC
FID C 3 417
SNT TRC
FID C 3 416
SNT TRC
FID C 3 397
SNT TRC
FID C 3 152
SNT TRC
FID C 3 433
SNT TRC
FID C 3 396
SNT TRC
FID C 3 454
SNT TRC
FID C 3 542
SNT TRC
FID C 11 1213
SNT TRC
FID C 11 1212
SNT TRC
FID C 11 779
SNT TRC
FID C 11 214
SNT TRC
FID C 11 228
SNT VIA
FID C 3 708
FID C 6 555
FID C 8 740
FID C 10 1279
FID C 11 2650
FID H 12 476
SNT VIA
FID C 2 613
FID C 3 672
FID C 6 465
FID C 8 650
FID C 10 1189
FID C 11 2560
FID H 12 386
SNT VIA
FID C 2 611
FID C 3 670
FID C 6 456
FID C 8 641
FID C 10 1180
FID C 11 2551
FID H 12 377
SNT VIA
FID C 3 576
FID C 6 228
FID C 8 413
FID C 10 952
FID C 11 2323
FID H 12 149
#NET 90
NET IMU_CLKSEL0
SNT TOP T 77 67
FID C 9 528
FID C 10 576
FID C 11 1943
SNT TOP T 42 9
FID C 9 725
FID C 10 797
FID C 11 2164
SNT TRC
FID C 2 451
SNT TRC
FID C 2 452
SNT TRC
FID C 2 458
SNT TRC
FID C 3 539
SNT TRC
FID C 3 488
SNT TRC
FID C 3 489
SNT TRC
FID C 11 1191
SNT TRC
FID C 11 1199
SNT TRC
FID C 11 1219
SNT TRC
FID C 11 1192
SNT TRC
FID C 11 881
SNT TRC
FID C 11 812
SNT TRC
FID C 11 801
SNT VIA
FID C 2 620
FID C 3 680
FID C 6 486
FID C 8 671
FID C 10 1210
FID C 11 2581
FID H 12 407
SNT VIA
FID C 3 705
FID C 6 552
FID C 8 737
FID C 10 1276
FID C 11 2647
FID H 12 473
SNT VIA
FID C 2 624
FID C 6 493
FID C 8 678
FID C 10 1217
FID C 11 2588
FID H 12 414
#NET 91
NET IMU_BOOT
SNT TOP T 77 65
FID C 9 529
FID C 10 577
FID C 11 1944
SNT TOP T 42 3
FID C 9 734
FID C 10 806
FID C 11 2173
SNT TRC
FID C 2 456
SNT TRC
FID C 2 454
SNT TRC
FID C 2 457
SNT TRC
FID C 2 463
SNT TRC
FID C 2 455
SNT TRC
FID C 3 535
SNT TRC
FID C 3 543
SNT TRC
FID C 3 544
SNT TRC
FID C 3 534
SNT TRC
FID C 3 492
SNT TRC
FID C 11 1247
SNT TRC
FID C 11 1248
SNT TRC
FID C 11 802
SNT TRC
FID C 11 851
SNT TRC
FID C 11 861
SNT VIA
FID C 3 710
FID C 6 565
FID C 8 750
FID C 10 1289
FID C 11 2660
FID H 12 486
SNT VIA
FID C 2 623
FID C 3 683
FID C 6 490
FID C 8 675
FID C 10 1214
FID C 11 2585
FID H 12 411
SNT VIA
FID C 2 626
FID C 6 495
FID C 8 680
FID C 10 1219
FID C 11 2590
FID H 12 416
#NET 92
NET NetJP1_3
SNT TOP T 3 2
FID C 6 31
FID C 8 221
FID C 10 79
FID C 11 1454
FID H 12 22
SNT TOP T 10 1
FID C 9 54
FID C 10 76
FID C 11 1451
SNT TOP T 11 1
FID C 9 55
FID C 10 77
FID C 11 1452
SNT TRC
FID C 11 141
SNT TRC
FID C 11 139
SNT TRC
FID C 11 137
SNT TRC
FID C 11 136
#NET 93
NET GPS1_TP2
SNT TOP T 41 8
FID C 9 273
FID C 10 313
FID C 11 1682
SNT TOP T 77 37
FID C 9 543
FID C 10 591
FID C 11 1958
SNT TRC
FID C 2 269
SNT TRC
FID C 2 254
SNT TRC
FID C 2 252
SNT TRC
FID C 2 253
SNT TRC
FID C 2 290
SNT TRC
FID C 3 239
SNT TRC
FID C 3 281
SNT TRC
FID C 3 283
SNT TRC
FID C 3 448
SNT TRC
FID C 3 451
SNT TRC
FID C 11 375
SNT TRC
FID C 11 808
SNT TRC
FID C 11 843
SNT TRC
FID C 11 836
SNT TRC
FID C 2 39
SNT TRC
FID C 2 30
SNT VIA
FID C 2 544
FID C 3 608
FID C 6 313
FID C 8 498
FID C 10 1037
FID C 11 2408
FID H 12 234
SNT VIA
FID C 2 554
FID C 6 335
FID C 8 520
FID C 10 1059
FID C 11 2430
FID H 12 256
SNT VIA
FID C 3 677
FID C 6 477
FID C 8 662
FID C 10 1201
FID C 11 2572
FID H 12 398
#NET 94
NET NetJP2_3
SNT TOP T 2 2
FID C 6 46
FID C 8 234
FID C 10 198
FID C 11 1571
FID H 12 29
SNT TOP T 8 1
FID C 9 183
FID C 10 218
FID C 11 1592
SNT TOP T 9 1
FID C 9 174
FID C 10 207
FID C 11 1581
SNT TRC
FID C 11 264
SNT TRC
FID C 11 258
SNT TRC
FID C 11 278
#NET 95
NET RTC_MFP
SNT TOP T 77 214
FID C 9 134
FID C 10 164
FID C 11 1536
SNT TOP T 12 2
FID C 9 343
FID C 10 383
FID C 11 1752
SNT TRC
FID C 2 385
SNT TRC
FID C 2 384
SNT TRC
FID C 2 388
SNT TRC
FID C 2 386
SNT TRC
FID C 2 387
SNT TRC
FID C 3 147
SNT TRC
FID C 11 493
SNT TRC
FID C 11 524
SNT TRC
FID C 11 579
SNT TRC
FID C 11 584
SNT TRC
FID C 11 244
SNT TRC
FID C 11 216
SNT VIA
FID C 2 586
FID C 3 646
FID C 6 408
FID C 8 593
FID C 10 1132
FID C 11 2503
FID H 12 329
SNT VIA
FID C 2 587
FID C 6 409
FID C 8 594
FID C 10 1133
FID C 11 2504
FID H 12 330
SNT VIA
FID C 3 574
FID C 6 225
FID C 8 410
FID C 10 949
FID C 11 2320
FID H 12 146
#NET 96
NET GPS1_RST
SNT TOP T 41 5
FID C 9 221
FID C 10 256
FID C 11 1630
SNT TOP T 77 25
FID C 9 549
FID C 10 597
FID C 11 1964
SNT TRC
FID C 2 168
SNT TRC
FID C 2 175
SNT TRC
FID C 3 440
SNT TRC
FID C 3 439
SNT TRC
FID C 3 423
SNT TRC
FID C 3 421
SNT TRC
FID C 3 185
SNT TRC
FID C 11 294
SNT TRC
FID C 11 309
SNT TRC
FID C 11 295
SNT TRC
FID C 11 762
SNT TRC
FID C 11 799
SNT TRC
FID C 11 764
SNT VIA
FID C 2 525
FID C 3 587
FID C 6 264
FID C 8 449
FID C 10 988
FID C 11 2359
FID H 12 185
SNT VIA
FID C 2 521
FID C 6 258
FID C 8 443
FID C 10 982
FID C 11 2353
FID H 12 179
SNT VIA
FID C 3 671
FID C 6 460
FID C 8 645
FID C 10 1184
FID C 11 2555
FID H 12 381
#NET 97
NET GPS2_TX
SNT TOP B 0 4
FID C 1 41
FID C 6 81
FID C 8 265
SNT TOP T 11 0
FID C 9 56
FID C 10 78
FID C 11 1453
SNT TOP T 77 165
FID C 9 57
FID C 10 83
FID C 11 1457
SNT TRC
FID C 2 157
SNT TRC
FID C 2 161
SNT TRC
FID C 2 159
SNT TRC
FID C 2 158
SNT TRC
FID C 2 156
SNT TRC
FID C 2 155
SNT TRC
FID C 2 138
SNT TRC
FID C 2 142
SNT TRC
FID C 2 153
SNT TRC
FID C 2 160
SNT TRC
FID C 2 107
SNT TRC
FID C 2 106
SNT TRC
FID C 2 128
SNT TRC
FID C 2 113
SNT TRC
FID C 2 126
SNT TRC
FID C 3 195
SNT TRC
FID C 3 202
SNT TRC
FID C 3 210
SNT TRC
FID C 3 248
SNT TRC
FID C 3 260
SNT TRC
FID C 3 179
SNT TRC
FID C 3 190
SNT TRC
FID C 3 126
SNT TRC
FID C 3 128
SNT TRC
FID C 3 178
SNT TRC
FID C 8 92
SNT TRC
FID C 8 103
SNT TRC
FID C 8 97
SNT TRC
FID C 8 102
SNT TRC
FID C 11 133
SNT TRC
FID C 11 134
SNT TRC
FID C 11 146
SNT TRC
FID C 11 151
SNT TRC
FID C 11 145
SNT VIA
FID C 2 515
FID C 3 582
FID C 6 251
FID C 8 436
FID C 10 975
FID C 11 2346
FID H 12 172
SNT VIA
FID C 2 516
FID C 3 583
FID C 6 252
FID C 8 437
FID C 10 976
FID C 11 2347
FID H 12 173
SNT VIA
FID C 2 488
FID C 6 181
FID C 8 366
FID C 10 905
FID C 11 2276
FID H 12 102
SNT VIA
FID C 3 614
FID C 6 323
FID C 8 508
FID C 10 1047
FID C 11 2418
FID H 12 244
SNT VIA
FID C 3 566
FID C 6 188
FID C 8 373
FID C 10 912
FID C 11 2283
FID H 12 109
#NET 98
NET GPS2_TP2
SNT TOP B 0 8
FID C 1 43
FID C 6 83
FID C 8 267
SNT TOP T 77 48
FID C 9 481
FID C 10 525
FID C 11 1894
SNT TRC
FID C 2 394
SNT TRC
FID C 2 393
SNT TRC
FID C 3 403
SNT TRC
FID C 3 262
SNT TRC
FID C 3 259
SNT TRC
FID C 3 265
SNT TRC
FID C 8 100
SNT TRC
FID C 8 93
SNT TRC
FID C 8 99
SNT TRC
FID C 8 101
SNT TRC
FID C 11 628
SNT TRC
FID C 11 634
SNT TRC
FID C 11 627
SNT VIA
FID C 2 593
FID C 3 652
FID C 6 420
FID C 8 605
FID C 10 1144
FID C 11 2515
FID H 12 341
SNT VIA
FID C 3 613
FID C 6 322
FID C 8 507
FID C 10 1046
FID C 11 2417
FID H 12 243
SNT VIA
FID C 2 592
FID C 6 419
FID C 8 604
FID C 10 1143
FID C 11 2514
FID H 12 340
#NET 99
NET GPS2_TP1
SNT TOP B 0 7
FID C 1 24
FID C 6 59
FID C 8 248
SNT TOP T 77 46
FID C 9 482
FID C 10 526
FID C 11 1895
SNT TRC
FID C 2 391
SNT TRC
FID C 2 392
SNT TRC
FID C 3 311
SNT TRC
FID C 3 214
SNT TRC
FID C 3 317
SNT TRC
FID C 3 380
SNT TRC
FID C 3 197
SNT TRC
FID C 3 207
SNT TRC
FID C 3 204
SNT TRC
FID C 3 198
SNT TRC
FID C 3 382
SNT TRC
FID C 8 61
SNT TRC
FID C 8 59
SNT TRC
FID C 11 615
SNT TRC
FID C 11 633
SNT TRC
FID C 11 623
SNT TRC
FID C 11 637
SNT VIA
FID C 3 595
FID C 6 286
FID C 8 471
FID C 10 1010
FID C 11 2381
FID H 12 207
SNT VIA
FID C 2 591
FID C 3 650
FID C 6 417
FID C 8 602
FID C 10 1141
FID C 11 2512
FID H 12 338
SNT VIA
FID C 2 590
FID C 6 416
FID C 8 601
FID C 10 1140
FID C 11 2511
FID H 12 337
#NET 100
NET GPS2_RX
SNT TOP B 0 6
FID C 1 42
FID C 6 82
FID C 8 266
SNT TOP T 9 0
FID C 9 175
FID C 10 208
FID C 11 1582
SNT TOP T 77 164
FID C 9 109
FID C 10 139
FID C 11 1511
SNT TRC
FID C 2 239
SNT TRC
FID C 2 238
SNT TRC
FID C 2 115
SNT TRC
FID C 2 116
SNT TRC
FID C 2 114
SNT TRC
FID C 2 117
SNT TRC
FID C 2 131
SNT TRC
FID C 2 130
SNT TRC
FID C 2 132
SNT TRC
FID C 2 136
SNT TRC
FID C 2 140
SNT TRC
FID C 2 141
SNT TRC
FID C 2 143
SNT TRC
FID C 2 152
SNT TRC
FID C 2 243
SNT TRC
FID C 2 241
SNT TRC
FID C 2 240
SNT TRC
FID C 2 223
SNT TRC
FID C 2 281
SNT TRC
FID C 2 242
SNT TRC
FID C 3 226
SNT TRC
FID C 3 213
SNT TRC
FID C 3 163
SNT TRC
FID C 3 162
SNT TRC
FID C 3 142
SNT TRC
FID C 3 206
SNT TRC
FID C 3 122
SNT TRC
FID C 3 141
SNT TRC
FID C 8 90
SNT TRC
FID C 8 83
SNT TRC
FID C 11 277
SNT TRC
FID C 11 273
SNT TRC
FID C 11 274
SNT TRC
FID C 11 226
SNT TRC
FID C 11 212
SNT TRC
FID C 11 222
SNT VIA
FID C 2 541
FID C 3 606
FID C 6 305
FID C 8 490
FID C 10 1029
FID C 11 2400
FID H 12 226
SNT VIA
FID C 2 491
FID C 3 564
FID C 6 185
FID C 8 370
FID C 10 909
FID C 11 2280
FID H 12 106
SNT VIA
FID C 2 514
FID C 6 247
FID C 8 432
FID C 10 971
FID C 11 2342
FID H 12 168
SNT VIA
FID C 2 536
FID C 3 601
FID C 6 295
FID C 8 480
FID C 10 1019
FID C 11 2390
FID H 12 216
SNT VIA
FID C 3 571
FID C 6 216
FID C 8 401
FID C 10 940
FID C 11 2311
FID H 12 137
#NET 101
NET GPS2_RST
SNT TOP B 0 5
FID C 1 23
FID C 6 58
FID C 8 247
SNT TOP T 77 38
FID C 9 486
FID C 10 530
FID C 11 1899
SNT TRC
FID C 2 390
SNT TRC
FID C 2 389
SNT TRC
FID C 3 203
SNT TRC
FID C 3 199
SNT TRC
FID C 3 249
SNT TRC
FID C 3 391
SNT TRC
FID C 3 392
SNT TRC
FID C 8 58
SNT TRC
FID C 8 75
SNT TRC
FID C 11 608
SNT TRC
FID C 11 607
SNT TRC
FID C 11 618
SNT VIA
FID C 3 596
FID C 6 287
FID C 8 472
FID C 10 1011
FID C 11 2382
FID H 12 208
SNT VIA
FID C 2 589
FID C 3 649
FID C 6 414
FID C 8 599
FID C 10 1138
FID C 11 2509
FID H 12 335
SNT VIA
FID C 2 588
FID C 6 413
FID C 8 598
FID C 10 1137
FID C 11 2508
FID H 12 334
#NET 102
NET DCXO1
SNT TOP T 77 117
FID C 9 278
FID C 10 318
FID C 11 1687
SNT TOP T 38 5
FID C 9 509
FID C 10 553
FID C 11 1922
SNT TRC
FID C 11 768
SNT TRC
FID C 11 386
SNT TRC
FID C 11 410
SNT TRC
FID C 11 385
SNT TRC
FID C 11 746
SNT TRC
FID C 11 770
SNT TRC
FID C 11 748
SNT TRC
FID C 11 778
#NET 103
NET DCXO2
SNT TOP T 77 99
FID C 9 225
FID C 10 260
FID C 11 1634
SNT TOP T 39 5
FID C 9 445
FID C 10 489
FID C 11 1858
SNT TRC
FID C 3 400
SNT TRC
FID C 3 389
SNT TRC
FID C 3 401
SNT TRC
FID C 3 191
SNT TRC
FID C 3 290
SNT TRC
FID C 3 307
SNT TRC
FID C 3 192
SNT TRC
FID C 3 308
SNT TRC
FID C 11 635
SNT TRC
FID C 11 636
SNT TRC
FID C 11 638
SNT TRC
FID C 11 648
SNT TRC
FID C 11 321
SNT TRC
FID C 11 322
SNT TRC
FID C 3 1
SNT TRC
FID C 3 47
SNT TRC
FID C 3 41
SNT VIA
FID C 3 653
FID C 6 422
FID C 8 607
FID C 10 1146
FID C 11 2517
FID H 12 343
SNT VIA
FID C 3 591
FID C 6 276
FID C 8 461
FID C 10 1000
FID C 11 2371
FID H 12 197
#NET 104
NET CSN
SNT TOP T 77 30
FID C 9 490
FID C 10 534
FID C 11 1903
SNT TOP T 42 17
FID C 9 736
FID C 10 808
FID C 11 2175
SNT TRC
FID C 2 399
SNT TRC
FID C 2 411
SNT TRC
FID C 2 398
SNT TRC
FID C 2 400
SNT TRC
FID C 3 547
SNT TRC
FID C 3 548
SNT TRC
FID C 3 530
SNT TRC
FID C 3 438
SNT TRC
FID C 3 529
SNT TRC
FID C 3 430
SNT TRC
FID C 11 1252
SNT TRC
FID C 11 1250
SNT TRC
FID C 11 682
SNT TRC
FID C 11 674
SNT TRC
FID C 11 645
SNT VIA
FID C 3 712
FID C 6 567
FID C 8 752
FID C 10 1291
FID C 11 2662
FID H 12 488
SNT VIA
FID C 2 603
FID C 3 661
FID C 6 437
FID C 8 622
FID C 10 1161
FID C 11 2532
FID H 12 358
SNT VIA
FID C 2 596
FID C 6 426
FID C 8 611
FID C 10 1150
FID C 11 2521
FID H 12 347
#NET 105
NET ANT4
SNT TOP T 143 0
FID C 6 17
FID C 8 207
FID C 10 17
FID C 11 1392
FID H 12 8
SNT TOP T 77 110
FID C 9 258
FID C 10 298
FID C 11 1667
SNT TOP T 86 0
FID C 9 33
FID C 10 55
FID C 11 1430
SNT TOP T 1 1
FID C 9 30
FID C 10 52
FID C 11 1427
SNT TOP T 139 0
FID C 9 9
FID C 10 31
FID C 11 1406
SNT TRC
FID C 2 235
SNT TRC
FID C 2 231
SNT TRC
FID C 3 209
SNT TRC
FID C 3 219
SNT TRC
FID C 3 99
SNT TRC
FID C 3 145
SNT TRC
FID C 3 108
SNT TRC
FID C 3 113
SNT TRC
FID C 3 139
SNT TRC
FID C 11 49
SNT TRC
FID C 11 56
SNT TRC
FID C 11 90
SNT TRC
FID C 11 85
SNT TRC
FID C 11 84
SNT TRC
FID C 11 360
SNT TRC
FID C 11 363
SNT TRC
FID C 11 359
SNT VIA
FID C 3 556
FID C 6 172
FID C 8 357
FID C 10 896
FID C 11 2267
FID H 12 93
SNT VIA
FID C 2 539
FID C 3 602
FID C 6 300
FID C 8 485
FID C 10 1024
FID C 11 2395
FID H 12 221
SNT VIA
FID C 2 538
FID C 6 298
FID C 8 483
FID C 10 1022
FID C 11 2393
FID H 12 219
#NET 106
NET ANT3
SNT TOP T 144 0
FID C 6 18
FID C 8 208
FID C 10 18
FID C 11 1393
FID H 12 9
SNT TOP T 4 1
FID C 9 31
FID C 10 53
FID C 11 1428
SNT TOP T 87 0
FID C 9 34
FID C 10 56
FID C 11 1431
SNT TOP T 140 0
FID C 9 10
FID C 10 32
FID C 11 1407
SNT TOP T 77 108
FID C 9 252
FID C 10 292
FID C 11 1661
SNT TRC
FID C 2 211
SNT TRC
FID C 2 217
SNT TRC
FID C 2 212
SNT TRC
FID C 3 102
SNT TRC
FID C 3 103
SNT TRC
FID C 3 100
SNT TRC
FID C 11 50
SNT TRC
FID C 11 57
SNT TRC
FID C 11 108
SNT TRC
FID C 11 91
SNT TRC
FID C 11 87
SNT TRC
FID C 11 86
SNT TRC
FID C 11 352
SNT TRC
FID C 11 349
SNT TRC
FID C 11 348
SNT VIA
FID C 3 557
FID C 6 173
FID C 8 358
FID C 10 897
FID C 11 2268
FID H 12 94
SNT VIA
FID C 2 534
FID C 3 600
FID C 6 292
FID C 8 477
FID C 10 1016
FID C 11 2387
FID H 12 213
SNT VIA
FID C 2 535
FID C 6 294
FID C 8 479
FID C 10 1018
FID C 11 2389
FID H 12 215
#NET 107
NET ANT2
SNT TOP T 145 0
FID C 6 19
FID C 8 209
FID C 10 19
FID C 11 1394
FID H 12 10
SNT TOP T 5 1
FID C 9 29
FID C 10 51
FID C 11 1426
SNT TOP T 89 0
FID C 9 35
FID C 10 57
FID C 11 1432
SNT TOP T 142 0
FID C 9 11
FID C 10 33
FID C 11 1408
SNT TOP T 77 106
FID C 9 247
FID C 10 286
FID C 11 1656
SNT TRC
FID C 2 197
SNT TRC
FID C 3 104
SNT TRC
FID C 3 101
SNT TRC
FID C 11 51
SNT TRC
FID C 11 58
SNT TRC
FID C 11 92
SNT TRC
FID C 11 83
SNT TRC
FID C 11 82
SNT TRC
FID C 11 342
SNT TRC
FID C 11 340
SNT TRC
FID C 11 343
SNT TRC
FID C 11 344
SNT TRC
FID C 11 345
SNT VIA
FID C 3 558
FID C 6 174
FID C 8 359
FID C 10 898
FID C 11 2269
FID H 12 95
SNT VIA
FID C 2 530
FID C 3 592
FID C 6 280
FID C 8 465
FID C 10 1004
FID C 11 2375
FID H 12 201
SNT VIA
FID C 2 531
FID C 6 281
FID C 8 466
FID C 10 1005
FID C 11 2376
FID H 12 202
#NET 108
NET ANT1
SNT TOP T 146 0
FID C 6 20
FID C 8 210
FID C 10 20
FID C 11 1395
FID H 12 11
SNT TOP T 6 1
FID C 9 32
FID C 10 54
FID C 11 1429
SNT TOP T 88 0
FID C 9 36
FID C 10 58
FID C 11 1433
SNT TOP T 141 0
FID C 9 12
FID C 10 34
FID C 11 1409
SNT TOP T 77 104
FID C 9 242
FID C 10 277
FID C 11 1651
SNT TRC
FID C 3 105
SNT TRC
FID C 3 106
SNT TRC
FID C 11 52
SNT TRC
FID C 11 59
SNT TRC
FID C 11 93
SNT TRC
FID C 11 89
SNT TRC
FID C 11 88
SNT TRC
FID C 11 337
SNT TRC
FID C 11 336
SNT VIA
FID C 3 559
FID C 6 175
FID C 8 360
FID C 10 899
FID C 11 2270
FID H 12 96
SNT VIA
FID C 3 593
FID C 6 282
FID C 8 467
FID C 10 1006
FID C 11 2377
FID H 12 203
#NET 109
NET +3.3V_CLEAN
SNT TOP T 13 4
FID C 6 140
FID C 8 322
FID C 10 736
FID C 11 2103
FID H 12 61
SNT TOP T 17 1
FID C 9 600
FID C 10 650
FID C 11 2017
SNT TOP T 18 1
FID C 9 614
FID C 10 667
FID C 11 2034
SNT TOP T 21 1
FID C 9 633
FID C 10 686
FID C 11 2053
SNT TOP T 22 1
FID C 9 640
FID C 10 694
FID C 11 2061
SNT TOP T 23 1
FID C 9 644
FID C 10 698
FID C 11 2065
SNT TOP T 24 1
FID C 9 649
FID C 10 706
FID C 11 2073
SNT TOP T 25 1
FID C 9 653
FID C 10 710
FID C 11 2077
SNT TOP T 26 1
FID C 9 658
FID C 10 715
FID C 11 2082
SNT TOP T 27 1
FID C 9 647
FID C 10 701
FID C 11 2068
SNT TOP T 104 1
FID C 9 564
FID C 10 612
FID C 11 1979
SNT TOP T 105 1
FID C 9 575
FID C 10 623
FID C 11 1990
SNT TOP T 106 1
FID C 9 567
FID C 10 615
FID C 11 1982
SNT TOP T 0 0
FID C 9 440
FID C 10 483
FID C 11 1852
SNT TOP T 0 5
FID C 9 434
FID C 10 477
FID C 11 1846
SNT TOP T 0 9
FID C 9 443
FID C 10 486
FID C 11 1855
SNT TOP T 20 1
FID C 9 627
FID C 10 680
FID C 11 2047
SNT TOP T 19 1
FID C 9 609
FID C 10 661
FID C 11 2028
SNT TOP T 83 1
FID C 9 631
FID C 10 684
FID C 11 2051
SNT TOP T 32 1
FID C 9 511
FID C 10 555
FID C 11 1924
SNT TOP T 38 8
FID C 9 510
FID C 10 554
FID C 11 1923
SNT TOP T 39 9
FID C 9 512
FID C 10 556
FID C 11 1925
SNT TOP T 12 1
FID C 9 344
FID C 10 384
FID C 11 1753
SNT TRC
FID C 11 909
SNT TRC
FID C 11 933
SNT TRC
FID C 11 910
SNT TRC
FID C 11 908
SNT TRC
FID C 11 967
SNT TRC
FID C 11 960
SNT TRC
FID C 11 935
SNT TRC
FID C 11 1026
SNT TRC
FID C 11 1047
SNT TRC
FID C 11 1052
SNT TRC
FID C 11 1051
SNT TRC
FID C 11 1048
SNT TRC
FID C 11 916
SNT TRC
FID C 11 934
SNT TRC
FID C 11 829
SNT TRC
FID C 11 847
SNT TRC
FID C 11 928
SNT TRC
FID C 11 927
SNT TRC
FID C 11 917
SNT TRC
FID C 11 877
SNT TRC
FID C 11 1015
SNT TRC
FID C 11 1039
SNT TRC
FID C 11 948
SNT TRC
FID C 11 957
SNT TRC
FID C 11 968
SNT TRC
FID C 11 995
SNT TRC
FID C 11 1025
SNT TRC
FID C 11 1033
SNT TRC
FID C 11 1057
SNT TRC
FID C 11 1055
SNT TRC
FID C 11 1056
SNT TRC
FID C 11 1068
SNT TRC
FID C 11 1082
#NET 110
NET LED4
SNT TOP T 54 0
FID C 9 49
FID C 10 71
FID C 11 1446
SNT TOP T 77 74
FID C 9 468
FID C 10 512
FID C 11 1881
SNT TRC
FID C 2 151
SNT TRC
FID C 2 150
SNT TRC
FID C 2 149
SNT TRC
FID C 3 432
SNT TRC
FID C 3 170
SNT TRC
FID C 3 169
SNT TRC
FID C 11 124
SNT TRC
FID C 11 125
SNT TRC
FID C 11 140
SNT TRC
FID C 11 707
SNT TRC
FID C 11 700
SNT TRC
FID C 11 677
SNT TRC
FID C 11 725
SNT VIA
FID C 2 512
FID C 3 581
FID C 6 241
FID C 8 426
FID C 10 965
FID C 11 2336
FID H 12 162
SNT VIA
FID C 2 513
FID C 6 242
FID C 8 427
FID C 10 966
FID C 11 2337
FID H 12 163
SNT VIA
FID C 3 663
FID C 6 441
FID C 8 626
FID C 10 1165
FID C 11 2536
FID H 12 362
#NET 111
NET LED3
SNT TOP T 55 0
FID C 9 41
FID C 10 63
FID C 11 1438
SNT TOP T 77 76
FID C 9 467
FID C 10 511
FID C 11 1880
SNT TRC
FID C 2 148
SNT TRC
FID C 3 167
SNT TRC
FID C 11 110
SNT TRC
FID C 11 111
SNT TRC
FID C 11 120
SNT TRC
FID C 11 663
SNT TRC
FID C 11 698
SNT TRC
FID C 11 691
SNT TRC
FID C 11 664
SNT VIA
FID C 2 511
FID C 6 238
FID C 8 423
FID C 10 962
FID C 11 2333
FID H 12 159
SNT VIA
FID C 2 510
FID C 3 580
FID C 6 237
FID C 8 422
FID C 10 961
FID C 11 2332
FID H 12 158
SNT VIA
FID C 3 660
FID C 6 435
FID C 8 620
FID C 10 1159
FID C 11 2530
FID H 12 356
#NET 112
NET +12V_PCIE
SNT PLN S C 0.00
FID C 8 228
SNT PLN S C 0.00
FID C 11 1553
SNT TOP T 76 2
FID C 1 11
FID C 6 41
FID C 8 229
SNT TOP T 76 1
FID C 1 10
FID C 6 40
FID C 8 227
SNT TOP T 76 34
FID C 9 161
FID C 10 191
FID C 11 1564
SNT TOP T 76 33
FID C 9 151
FID C 10 181
FID C 11 1554
SNT TOP T 76 32
FID C 9 149
FID C 10 179
FID C 11 1551
SNT TOP T 101 1
FID C 9 708
FID C 10 780
FID C 11 2147
SNT TRC
FID C 2 137
SNT TRC
FID C 3 144
SNT TRC
FID C 8 42
SNT TRC
FID C 8 41
SNT TRC
FID C 8 44
SNT TRC
FID C 8 43
SNT TRC
FID C 11 1187
SNT TRC
FID C 11 229
SNT TRC
FID C 11 231
SNT TRC
FID C 11 225
SNT TRC
FID C 11 224
SNT TRC
FID C 11 230
SNT TRC
FID C 11 235
SNT TRC
FID C 11 241
SNT TRC
FID C 11 227
SNT VIA
FID C 3 703
FID C 6 550
FID C 8 735
FID C 10 1274
FID C 11 2645
FID H 12 471
SNT VIA
FID C 2 501
FID C 3 573
FID C 6 220
FID C 8 405
FID C 10 944
FID C 11 2315
FID H 12 141
SNT VIA
FID C 6 224
FID C 8 409
FID C 10 948
FID C 11 2319
FID H 12 145
SNT VIA
FID C 2 503
FID C 6 222
FID C 8 407
FID C 10 946
FID C 11 2317
FID H 12 143
SNT VIA
FID C 2 500
FID C 6 219
FID C 8 404
FID C 10 943
FID C 11 2314
FID H 12 140
SNT VIA
FID C 6 223
FID C 8 408
FID C 10 947
FID C 11 2318
FID H 12 144
SNT VIA
FID C 2 502
FID C 6 221
FID C 8 406
FID C 10 945
FID C 11 2316
FID H 12 142
SNT VIA
FID C 6 218
FID C 8 403
FID C 10 942
FID C 11 2313
FID H 12 139
#NET 113
NET +3.3V_PCIE
SNT PLN S C 0.00
FID C 8 239
SNT PLN S C 0.00
FID C 11 1576
SNT TOP T 76 9
FID C 1 18
FID C 6 51
FID C 8 240
SNT TOP T 76 8
FID C 1 17
FID C 6 50
FID C 8 238
SNT TOP T 76 39
FID C 9 168
FID C 10 201
FID C 11 1574
SNT TRC
FID C 8 54
SNT TRC
FID C 8 53
SNT TRC
FID C 8 50
SNT TRC
FID C 8 49
SNT TRC
FID C 8 51
SNT TRC
FID C 11 260
SNT TRC
FID C 11 261
SNT TRC
FID C 11 263
SNT TRC
FID C 11 262
SNT VIA
FID C 6 249
FID C 8 434
FID C 10 973
FID C 11 2344
FID H 12 170
SNT VIA
FID C 6 243
FID C 8 428
FID C 10 967
FID C 11 2338
FID H 12 164
SNT VIA
FID C 6 250
FID C 8 435
FID C 10 974
FID C 11 2345
FID H 12 171
SNT VIA
FID C 6 244
FID C 8 429
FID C 10 968
FID C 11 2339
FID H 12 165
SNT VIA
FID C 6 240
FID C 8 425
FID C 10 964
FID C 11 2335
FID H 12 161
SNT VIA
FID C 6 239
FID C 8 424
FID C 10 963
FID C 11 2334
FID H 12 160
#NET 114
NET PRSNT
SNT TOP T 76 0
FID C 1 9
FID C 6 39
FID C 8 226
SNT TOP T 61 0
FID C 9 415
FID C 10 458
FID C 11 1827
SNT TOP T 62 0
FID C 9 267
FID C 10 307
FID C 11 1676
SNT TRC
FID C 8 40
SNT TRC
FID C 11 374
SNT TRC
FID C 11 223
SNT TRC
FID C 11 259
SNT VIA
FID C 6 215
FID C 8 400
FID C 10 939
FID C 11 2310
FID H 12 136
#NET 115
NET PCIE_TX3_N
SNT TOP B 5 1
FID C 1 74
FID C 6 117
FID C 8 301
SNT TOP T 77 262
FID C 9 358
FID C 10 398
FID C 11 1767
SNT TRC
FID C 2 317
SNT TRC
FID C 2 318
SNT TRC
FID C 2 323
SNT TRC
FID C 2 361
SNT TRC
FID C 2 352
SNT TRC
FID C 2 373
SNT TRC
FID C 2 362
SNT TRC
FID C 2 374
SNT TRC
FID C 8 155
SNT TRC
FID C 8 156
SNT TRC
FID C 11 509
SNT TRC
FID C 11 510
SNT TRC
FID C 2 57
SNT TRC
FID C 2 58
SNT TRC
FID C 2 80
SNT TRC
FID C 2 91
SNT TRC
FID C 2 86
SNT TRC
FID C 2 95
SNT TRC
FID C 2 96
SNT TRC
FID C 2 81
SNT TRC
FID C 2 87
SNT TRC
FID C 2 92
SNT TRC
FID C 2 85
SNT TRC
FID C 11 37
SNT VIA
FID C 2 570
FID C 6 373
FID C 8 558
FID C 10 1097
FID C 11 2468
FID H 12 294
SNT VIA
FID C 2 585
FID C 6 407
FID C 8 592
FID C 10 1131
FID C 11 2502
FID H 12 328
#NET 116
NET PCIE_TX3_P
SNT TOP B 6 1
FID C 1 71
FID C 6 111
FID C 8 295
SNT TOP T 77 260
FID C 9 364
FID C 10 404
FID C 11 1773
SNT TRC
FID C 2 334
SNT TRC
FID C 2 332
SNT TRC
FID C 2 333
SNT TRC
FID C 2 354
SNT TRC
FID C 2 355
SNT TRC
FID C 2 358
SNT TRC
FID C 2 360
SNT TRC
FID C 2 359
SNT TRC
FID C 2 367
SNT TRC
FID C 2 364
SNT TRC
FID C 2 365
SNT TRC
FID C 2 366
SNT TRC
FID C 2 372
SNT TRC
FID C 2 356
SNT TRC
FID C 2 353
SNT TRC
FID C 8 149
SNT TRC
FID C 8 151
SNT TRC
FID C 8 150
SNT TRC
FID C 11 518
SNT TRC
FID C 2 82
SNT TRC
FID C 2 61
SNT TRC
FID C 2 62
SNT TRC
FID C 2 83
SNT TRC
FID C 2 88
SNT TRC
FID C 2 84
SNT TRC
FID C 2 90
SNT TRC
FID C 2 93
SNT TRC
FID C 2 89
SNT TRC
FID C 2 94
SNT TRC
FID C 11 39
SNT TRC
FID C 8 28
SNT TRC
FID C 8 29
SNT VIA
FID C 2 572
FID C 6 380
FID C 8 565
FID C 10 1104
FID C 11 2475
FID H 12 301
SNT VIA
FID C 2 581
FID C 6 403
FID C 8 588
FID C 10 1127
FID C 11 2498
FID H 12 324
#NET 117
NET PCIE_TX2_N
SNT TOP B 7 1
FID C 1 65
FID C 6 105
FID C 8 289
SNT TOP T 77 257
FID C 9 374
FID C 10 414
FID C 11 1783
SNT TRC
FID C 2 335
SNT TRC
FID C 2 337
SNT TRC
FID C 2 340
SNT TRC
FID C 2 320
SNT TRC
FID C 2 321
SNT TRC
FID C 2 322
SNT TRC
FID C 2 319
SNT TRC
FID C 8 136
SNT TRC
FID C 11 535
SNT TRC
FID C 2 63
SNT TRC
FID C 2 64
SNT TRC
FID C 2 66
SNT TRC
FID C 2 67
SNT TRC
FID C 2 73
SNT TRC
FID C 2 59
SNT TRC
FID C 2 72
SNT TRC
FID C 2 60
SNT TRC
FID C 2 56
SNT TRC
FID C 11 40
SNT TRC
FID C 8 20
SNT VIA
FID C 2 574
FID C 6 385
FID C 8 570
FID C 10 1109
FID C 11 2480
FID H 12 306
SNT VIA
FID C 2 573
FID C 6 383
FID C 8 568
FID C 10 1107
FID C 11 2478
FID H 12 304
#NET 118
NET PCIE_TX2_P
SNT TOP B 8 1
FID C 1 62
FID C 6 102
FID C 8 286
SNT TOP T 77 255
FID C 9 378
FID C 10 418
FID C 11 1787
SNT TRC
FID C 2 348
SNT TRC
FID C 2 347
SNT TRC
FID C 2 346
SNT TRC
FID C 2 345
SNT TRC
FID C 2 326
SNT TRC
FID C 2 329
SNT TRC
FID C 2 330
SNT TRC
FID C 2 331
SNT TRC
FID C 2 344
SNT TRC
FID C 2 343
SNT TRC
FID C 2 342
SNT TRC
FID C 2 341
SNT TRC
FID C 2 339
SNT TRC
FID C 2 338
SNT TRC
FID C 2 336
SNT TRC
FID C 2 327
SNT TRC
FID C 2 325
SNT TRC
FID C 2 324
SNT TRC
FID C 2 328
SNT TRC
FID C 8 134
SNT TRC
FID C 11 540
SNT TRC
FID C 2 79
SNT TRC
FID C 2 77
SNT TRC
FID C 2 76
SNT TRC
FID C 2 75
SNT TRC
FID C 2 78
SNT TRC
FID C 2 74
SNT TRC
FID C 2 71
SNT TRC
FID C 2 69
SNT TRC
FID C 2 70
SNT TRC
FID C 2 68
SNT TRC
FID C 2 65
SNT TRC
FID C 11 41
SNT TRC
FID C 8 16
SNT TRC
FID C 8 19
SNT VIA
FID C 2 575
FID C 6 390
FID C 8 575
FID C 10 1114
FID C 11 2485
FID H 12 311
SNT VIA
FID C 2 571
FID C 6 378
FID C 8 563
FID C 10 1102
FID C 11 2473
FID H 12 299
#NET 119
NET PCIE_TX1_N
SNT TOP B 9 1
FID C 1 56
FID C 6 96
FID C 8 280
SNT TOP T 77 269
FID C 9 335
FID C 10 375
FID C 11 1744
SNT TRC
FID C 2 305
SNT TRC
FID C 2 295
SNT TRC
FID C 2 312
SNT TRC
FID C 2 311
SNT TRC
FID C 2 302
SNT TRC
FID C 2 301
SNT TRC
FID C 2 304
SNT TRC
FID C 2 303
SNT TRC
FID C 2 307
SNT TRC
FID C 2 306
SNT TRC
FID C 2 310
SNT TRC
FID C 2 309
SNT TRC
FID C 2 308
SNT TRC
FID C 8 116
SNT TRC
FID C 8 117
SNT TRC
FID C 11 479
SNT TRC
FID C 11 485
SNT TRC
FID C 11 478
SNT TRC
FID C 2 54
SNT TRC
FID C 2 42
SNT TRC
FID C 2 47
SNT TRC
FID C 2 44
SNT TRC
FID C 2 50
SNT TRC
FID C 2 45
SNT TRC
FID C 2 49
SNT TRC
FID C 2 46
SNT TRC
FID C 2 53
SNT TRC
FID C 2 52
SNT TRC
FID C 2 48
SNT TRC
FID C 11 27
SNT TRC
FID C 11 26
SNT VIA
FID C 2 568
FID C 6 362
FID C 8 547
FID C 10 1086
FID C 11 2457
FID H 12 283
SNT VIA
FID C 2 564
FID C 6 354
FID C 8 539
FID C 10 1078
FID C 11 2449
FID H 12 275
#NET 120
NET PCIE_TX1_P
SNT TOP B 10 1
FID C 1 53
FID C 6 93
FID C 8 277
SNT TOP T 77 267
FID C 9 348
FID C 10 388
FID C 11 1757
SNT TRC
FID C 2 315
SNT TRC
FID C 2 316
SNT TRC
FID C 2 313
SNT TRC
FID C 2 287
SNT TRC
FID C 2 282
SNT TRC
FID C 2 314
SNT TRC
FID C 8 113
SNT TRC
FID C 11 495
SNT TRC
FID C 2 55
SNT TRC
FID C 2 37
SNT TRC
FID C 2 51
SNT TRC
FID C 11 31
SNT TRC
FID C 8 13
SNT VIA
FID C 2 569
FID C 6 365
FID C 8 550
FID C 10 1089
FID C 11 2460
FID H 12 286
SNT VIA
FID C 2 557
FID C 6 340
FID C 8 525
FID C 10 1064
FID C 11 2435
FID H 12 261
#NET 121
NET PCIE_TX0_N
SNT TOP B 11 1
FID C 1 45
FID C 6 85
FID C 8 269
SNT TOP T 77 274
FID C 9 318
FID C 10 358
FID C 11 1727
SNT TRC
FID C 2 288
SNT TRC
FID C 2 289
SNT TRC
FID C 2 291
SNT TRC
FID C 2 225
SNT TRC
FID C 2 224
SNT TRC
FID C 2 232
SNT TRC
FID C 2 229
SNT TRC
FID C 2 200
SNT TRC
FID C 2 233
SNT TRC
FID C 2 234
SNT TRC
FID C 8 95
SNT TRC
FID C 8 94
SNT TRC
FID C 11 448
SNT TRC
FID C 2 38
SNT TRC
FID C 2 40
SNT TRC
FID C 2 14
SNT TRC
FID C 2 25
SNT TRC
FID C 2 27
SNT TRC
FID C 11 20
SNT VIA
FID C 2 560
FID C 6 347
FID C 8 532
FID C 10 1071
FID C 11 2442
FID H 12 268
SNT VIA
FID C 2 542
FID C 6 308
FID C 8 493
FID C 10 1032
FID C 11 2403
FID H 12 229
#NET 122
NET PCIE_TX0_P
SNT TOP B 12 1
FID C 1 38
FID C 6 78
FID C 8 262
SNT TOP T 77 272
FID C 9 324
FID C 10 364
FID C 11 1733
SNT TRC
FID C 2 297
SNT TRC
FID C 2 296
SNT TRC
FID C 2 230
SNT TRC
FID C 2 228
SNT TRC
FID C 2 227
SNT TRC
FID C 2 220
SNT TRC
FID C 2 237
SNT TRC
FID C 2 210
SNT TRC
FID C 2 206
SNT TRC
FID C 2 209
SNT TRC
FID C 2 207
SNT TRC
FID C 2 218
SNT TRC
FID C 2 203
SNT TRC
FID C 2 204
SNT TRC
FID C 2 219
SNT TRC
FID C 2 208
SNT TRC
FID C 8 89
SNT TRC
FID C 8 86
SNT TRC
FID C 8 88
SNT TRC
FID C 8 85
SNT TRC
FID C 8 84
SNT TRC
FID C 11 464
SNT TRC
FID C 2 41
SNT TRC
FID C 2 43
SNT TRC
FID C 2 22
SNT TRC
FID C 2 21
SNT TRC
FID C 2 26
SNT TRC
FID C 2 19
SNT TRC
FID C 2 20
SNT TRC
FID C 2 24
SNT TRC
FID C 2 15
SNT TRC
FID C 2 23
SNT TRC
FID C 2 18
SNT TRC
FID C 11 24
SNT TRC
FID C 8 9
SNT VIA
FID C 2 565
FID C 6 355
FID C 8 540
FID C 10 1079
FID C 11 2450
FID H 12 276
SNT VIA
FID C 2 537
FID C 6 296
FID C 8 481
FID C 10 1020
FID C 11 2391
FID H 12 217
#NET 123
NET PCIE_CLK_P
SNT TOP B 14 1
FID C 1 28
FID C 6 63
FID C 8 252
SNT TOP T 77 279
FID C 9 308
FID C 10 348
FID C 11 1717
SNT TRC
FID C 2 184
SNT TRC
FID C 2 266
SNT TRC
FID C 2 267
SNT TRC
FID C 2 268
SNT TRC
FID C 2 251
SNT TRC
FID C 2 183
SNT TRC
FID C 2 179
SNT TRC
FID C 2 261
SNT TRC
FID C 2 215
SNT TRC
FID C 8 64
SNT TRC
FID C 11 429
SNT TRC
FID C 11 414
SNT TRC
FID C 2 35
SNT TRC
FID C 2 33
SNT TRC
FID C 2 29
SNT TRC
FID C 2 10
SNT TRC
FID C 2 4
SNT TRC
FID C 2 5
SNT TRC
FID C 2 3
SNT TRC
FID C 2 2
SNT TRC
FID C 11 14
SNT TRC
FID C 11 15
SNT TRC
FID C 8 3
SNT VIA
FID C 2 552
FID C 6 332
FID C 8 517
FID C 10 1056
FID C 11 2427
FID H 12 253
SNT VIA
FID C 2 526
FID C 6 271
FID C 8 456
FID C 10 995
FID C 11 2366
FID H 12 192
#NET 124
NET PCIE_CLK_N
SNT TOP B 13 1
FID C 1 33
FID C 6 68
FID C 8 257
SNT TOP T 77 281
FID C 9 302
FID C 10 342
FID C 11 1711
SNT TRC
FID C 2 258
SNT TRC
FID C 2 250
SNT TRC
FID C 2 186
SNT TRC
FID C 2 185
SNT TRC
FID C 2 187
SNT TRC
FID C 2 260
SNT TRC
FID C 2 226
SNT TRC
FID C 2 222
SNT TRC
FID C 2 216
SNT TRC
FID C 2 214
SNT TRC
FID C 2 213
SNT TRC
FID C 2 205
SNT TRC
FID C 2 201
SNT TRC
FID C 2 199
SNT TRC
FID C 2 198
SNT TRC
FID C 8 67
SNT TRC
FID C 8 68
SNT TRC
FID C 11 416
SNT TRC
FID C 11 408
SNT TRC
FID C 2 34
SNT TRC
FID C 2 31
SNT TRC
FID C 2 6
SNT TRC
FID C 2 7
SNT TRC
FID C 2 8
SNT TRC
FID C 2 9
SNT TRC
FID C 2 11
SNT TRC
FID C 2 16
SNT TRC
FID C 2 17
SNT TRC
FID C 2 13
SNT TRC
FID C 2 12
SNT TRC
FID C 11 8
SNT TRC
FID C 11 11
SNT VIA
FID C 2 548
FID C 6 324
FID C 8 509
FID C 10 1048
FID C 11 2419
FID H 12 245
SNT VIA
FID C 2 528
FID C 6 274
FID C 8 459
FID C 10 998
FID C 11 2369
FID H 12 195
#NET 125
NET PCIE_PERST
SNT TOP T 76 10
FID C 1 19
FID C 6 52
FID C 8 241
SNT TOP T 63 0
FID C 9 172
FID C 10 205
FID C 11 1579
SNT TOP T 77 184
FID C 9 119
FID C 10 149
FID C 11 1521
SNT TRC
FID C 8 55
SNT TRC
FID C 8 45
SNT TRC
FID C 8 47
SNT TRC
FID C 8 56
SNT TRC
FID C 8 46
SNT TRC
FID C 11 272
SNT TRC
FID C 11 248
SNT TRC
FID C 11 265
SNT TRC
FID C 11 266
SNT TRC
FID C 11 275
SNT TRC
FID C 11 213
SNT VIA
FID C 6 229
FID C 8 414
FID C 10 953
FID C 11 2324
FID H 12 150
#NET 126
NET PCIE_RX3_N
SNT TOP T 77 268
FID C 9 336
FID C 10 376
FID C 11 1745
SNT TOP T 76 59
FID C 9 389
FID C 10 429
FID C 11 1798
SNT TRC
FID C 3 339
SNT TRC
FID C 3 325
SNT TRC
FID C 3 335
SNT TRC
FID C 3 351
SNT TRC
FID C 3 353
SNT TRC
FID C 3 379
SNT TRC
FID C 3 355
SNT TRC
FID C 3 354
SNT TRC
FID C 3 371
SNT TRC
FID C 3 372
SNT TRC
FID C 3 368
SNT TRC
FID C 3 367
SNT TRC
FID C 3 374
SNT TRC
FID C 11 560
SNT TRC
FID C 11 486
SNT TRC
FID C 11 561
SNT TRC
FID C 3 59
SNT TRC
FID C 3 58
SNT TRC
FID C 3 65
SNT TRC
FID C 3 76
SNT TRC
FID C 3 84
SNT TRC
FID C 3 87
SNT TRC
FID C 3 71
SNT TRC
FID C 3 80
SNT TRC
FID C 3 78
SNT TRC
FID C 3 79
SNT TRC
FID C 3 72
SNT TRC
FID C 11 25
SNT TRC
FID C 11 44
SNT TRC
FID C 11 45
SNT VIA
FID C 3 628
FID C 6 363
FID C 8 548
FID C 10 1087
FID C 11 2458
FID H 12 284
SNT VIA
FID C 3 641
FID C 6 398
FID C 8 583
FID C 10 1122
FID C 11 2493
FID H 12 319
#NET 127
NET PCIE_RX3_P
SNT TOP T 77 266
FID C 9 349
FID C 10 389
FID C 11 1758
SNT TOP T 76 58
FID C 9 380
FID C 10 420
FID C 11 1789
SNT TRC
FID C 3 360
SNT TRC
FID C 3 352
SNT TRC
FID C 3 341
SNT TRC
FID C 3 338
SNT TRC
FID C 3 340
SNT TRC
FID C 3 359
SNT TRC
FID C 3 369
SNT TRC
FID C 3 378
SNT TRC
FID C 3 377
SNT TRC
FID C 3 358
SNT TRC
FID C 3 357
SNT TRC
FID C 3 363
SNT TRC
FID C 3 361
SNT TRC
FID C 3 362
SNT TRC
FID C 3 370
SNT TRC
FID C 3 364
SNT TRC
FID C 3 365
SNT TRC
FID C 3 366
SNT TRC
FID C 3 376
SNT TRC
FID C 11 547
SNT TRC
FID C 11 545
SNT TRC
FID C 11 496
SNT TRC
FID C 11 546
SNT TRC
FID C 11 555
SNT TRC
FID C 3 67
SNT TRC
FID C 3 82
SNT TRC
FID C 3 63
SNT TRC
FID C 3 62
SNT TRC
FID C 3 73
SNT TRC
FID C 3 86
SNT TRC
FID C 3 85
SNT TRC
FID C 3 75
SNT TRC
FID C 3 81
SNT TRC
FID C 3 74
SNT TRC
FID C 3 83
SNT TRC
FID C 3 77
SNT TRC
FID C 11 32
SNT TRC
FID C 11 42
SNT TRC
FID C 11 43
SNT VIA
FID C 3 630
FID C 6 366
FID C 8 551
FID C 10 1090
FID C 11 2461
FID H 12 287
SNT VIA
FID C 3 639
FID C 6 394
FID C 8 579
FID C 10 1118
FID C 11 2489
FID H 12 315
#NET 128
NET PCIE_RX2_N
SNT TOP T 77 263
FID C 9 357
FID C 10 397
FID C 11 1766
SNT TOP T 76 55
FID C 9 350
FID C 10 390
FID C 11 1759
SNT TRC
FID C 3 343
SNT TRC
FID C 3 342
SNT TRC
FID C 3 345
SNT TRC
FID C 3 324
SNT TRC
FID C 3 323
SNT TRC
FID C 11 508
SNT TRC
FID C 11 498
SNT TRC
FID C 3 66
SNT TRC
FID C 3 69
SNT TRC
FID C 3 64
SNT TRC
FID C 3 50
SNT TRC
FID C 3 54
SNT TRC
FID C 3 53
SNT TRC
FID C 11 33
SNT TRC
FID C 11 35
SNT TRC
FID C 11 36
SNT TRC
FID C 11 34
SNT VIA
FID C 3 632
FID C 6 372
FID C 8 557
FID C 10 1096
FID C 11 2467
FID H 12 293
SNT VIA
FID C 3 631
FID C 6 368
FID C 8 553
FID C 10 1092
FID C 11 2463
FID H 12 289
#NET 129
NET PCIE_RX2_P
SNT TOP T 77 261
FID C 9 363
FID C 10 403
FID C 11 1772
SNT TOP T 76 54
FID C 9 332
FID C 10 372
FID C 11 1741
SNT TRC
FID C 3 348
SNT TRC
FID C 3 346
SNT TRC
FID C 3 337
SNT TRC
FID C 3 334
SNT TRC
FID C 3 328
SNT TRC
FID C 3 329
SNT TRC
FID C 3 330
SNT TRC
FID C 3 319
SNT TRC
FID C 3 320
SNT TRC
FID C 3 321
SNT TRC
FID C 3 322
SNT TRC
FID C 3 331
SNT TRC
FID C 3 332
SNT TRC
FID C 3 333
SNT TRC
FID C 3 327
SNT TRC
FID C 3 326
SNT TRC
FID C 3 336
SNT TRC
FID C 11 482
SNT TRC
FID C 11 484
SNT TRC
FID C 11 517
SNT TRC
FID C 11 483
SNT TRC
FID C 11 491
SNT TRC
FID C 11 490
SNT TRC
FID C 11 489
SNT TRC
FID C 11 488
SNT TRC
FID C 3 70
SNT TRC
FID C 3 68
SNT TRC
FID C 3 60
SNT TRC
FID C 3 57
SNT TRC
FID C 3 51
SNT TRC
FID C 3 61
SNT TRC
FID C 3 52
SNT TRC
FID C 3 55
SNT TRC
FID C 3 56
SNT TRC
FID C 11 38
SNT TRC
FID C 11 30
SNT TRC
FID C 11 29
SNT TRC
FID C 11 28
SNT VIA
FID C 3 636
FID C 6 379
FID C 8 564
FID C 10 1103
FID C 11 2474
FID H 12 300
SNT VIA
FID C 3 629
FID C 6 364
FID C 8 549
FID C 10 1088
FID C 11 2459
FID H 12 285
#NET 130
NET PCIE_RX1_N
SNT TOP T 77 275
FID C 9 317
FID C 10 357
FID C 11 1726
SNT TOP T 76 51
FID C 9 299
FID C 10 339
FID C 11 1708
SNT TRC
FID C 3 285
SNT TRC
FID C 3 304
SNT TRC
FID C 3 309
SNT TRC
FID C 3 278
SNT TRC
FID C 3 258
SNT TRC
FID C 3 267
SNT TRC
FID C 3 272
SNT TRC
FID C 3 263
SNT TRC
FID C 3 257
SNT TRC
FID C 3 247
SNT TRC
FID C 3 254
SNT TRC
FID C 11 439
SNT TRC
FID C 11 440
SNT TRC
FID C 11 447
SNT TRC
FID C 11 411
SNT TRC
FID C 11 409
SNT TRC
FID C 3 44
SNT TRC
FID C 3 48
SNT TRC
FID C 3 40
SNT TRC
FID C 3 28
SNT TRC
FID C 3 36
SNT TRC
FID C 3 33
SNT TRC
FID C 3 26
SNT TRC
FID C 3 21
SNT TRC
FID C 3 30
SNT TRC
FID C 3 24
SNT TRC
FID C 3 20
SNT TRC
FID C 3 25
SNT TRC
FID C 3 27
SNT TRC
FID C 11 10
SNT TRC
FID C 11 17
SNT TRC
FID C 11 18
SNT TRC
FID C 11 19
SNT TRC
FID C 11 13
SNT TRC
FID C 11 9
SNT VIA
FID C 3 622
FID C 6 341
FID C 8 526
FID C 10 1065
FID C 11 2436
FID H 12 262
SNT VIA
FID C 3 616
FID C 6 329
FID C 8 514
FID C 10 1053
FID C 11 2424
FID H 12 250
#NET 131
NET PCIE_RX1_P
SNT TOP T 77 273
FID C 9 323
FID C 10 363
FID C 11 1732
SNT TOP T 76 50
FID C 9 290
FID C 10 330
FID C 11 1699
SNT TRC
FID C 3 313
SNT TRC
FID C 3 312
SNT TRC
FID C 3 292
SNT TRC
FID C 3 293
SNT TRC
FID C 3 271
SNT TRC
FID C 3 261
SNT TRC
FID C 3 264
SNT TRC
FID C 3 274
SNT TRC
FID C 3 275
SNT TRC
FID C 3 276
SNT TRC
FID C 3 279
SNT TRC
FID C 3 268
SNT TRC
FID C 3 269
SNT TRC
FID C 3 270
SNT TRC
FID C 11 451
SNT TRC
FID C 11 463
SNT TRC
FID C 11 396
SNT TRC
FID C 3 46
SNT TRC
FID C 3 49
SNT TRC
FID C 3 43
SNT TRC
FID C 3 29
SNT TRC
FID C 3 34
SNT TRC
FID C 3 39
SNT TRC
FID C 3 35
SNT TRC
FID C 3 38
SNT TRC
FID C 3 32
SNT TRC
FID C 3 23
SNT TRC
FID C 11 6
SNT TRC
FID C 11 22
SNT TRC
FID C 11 23
SNT TRC
FID C 11 7
SNT VIA
FID C 3 625
FID C 6 350
FID C 8 535
FID C 10 1074
FID C 11 2445
FID H 12 271
SNT VIA
FID C 3 611
FID C 6 316
FID C 8 501
FID C 10 1040
FID C 11 2411
FID H 12 237
#NET 132
NET PCIE_RX0_N
SNT TOP T 77 280
FID C 9 303
FID C 10 343
FID C 11 1712
SNT TOP T 76 46
FID C 9 246
FID C 10 285
FID C 11 1655
SNT TRC
FID C 3 284
SNT TRC
FID C 3 289
SNT TRC
FID C 3 245
SNT TRC
FID C 3 240
SNT TRC
FID C 3 241
SNT TRC
FID C 3 208
SNT TRC
FID C 3 237
SNT TRC
FID C 3 212
SNT TRC
FID C 3 211
SNT TRC
FID C 3 217
SNT TRC
FID C 3 220
SNT TRC
FID C 3 221
SNT TRC
FID C 3 228
SNT TRC
FID C 3 230
SNT TRC
FID C 3 231
SNT TRC
FID C 3 234
SNT TRC
FID C 11 417
SNT TRC
FID C 11 341
SNT TRC
FID C 3 42
SNT TRC
FID C 3 31
SNT TRC
FID C 3 19
SNT TRC
FID C 3 17
SNT TRC
FID C 3 5
SNT TRC
FID C 3 4
SNT TRC
FID C 3 7
SNT TRC
FID C 3 8
SNT TRC
FID C 3 10
SNT TRC
FID C 3 9
SNT TRC
FID C 3 11
SNT TRC
FID C 3 12
SNT TRC
FID C 3 14
SNT TRC
FID C 3 13
SNT TRC
FID C 3 15
SNT TRC
FID C 3 16
SNT TRC
FID C 11 2
SNT TRC
FID C 11 12
SNT TRC
FID C 11 3
SNT VIA
FID C 3 617
FID C 6 330
FID C 8 515
FID C 10 1054
FID C 11 2425
FID H 12 251
SNT VIA
FID C 3 599
FID C 6 291
FID C 8 476
FID C 10 1015
FID C 11 2386
FID H 12 212
#NET 133
NET PCIE_RX0_P
SNT TOP T 77 278
FID C 9 309
FID C 10 349
FID C 11 1718
SNT TOP T 76 45
FID C 9 235
FID C 10 270
FID C 11 1644
SNT TRC
FID C 3 300
SNT TRC
FID C 3 301
SNT TRC
FID C 3 296
SNT TRC
FID C 3 196
SNT TRC
FID C 3 200
SNT TRC
FID C 3 250
SNT TRC
FID C 3 215
SNT TRC
FID C 3 251
SNT TRC
FID C 3 243
SNT TRC
FID C 3 216
SNT TRC
FID C 11 430
SNT TRC
FID C 11 328
SNT TRC
FID C 3 45
SNT TRC
FID C 3 37
SNT TRC
FID C 3 3
SNT TRC
FID C 3 2
SNT TRC
FID C 3 22
SNT TRC
FID C 3 6
SNT TRC
FID C 3 18
SNT TRC
FID C 11 16
SNT TRC
FID C 11 1
SNT VIA
FID C 3 621
FID C 6 339
FID C 8 524
FID C 10 1063
FID C 11 2434
FID H 12 260
SNT VIA
FID C 3 594
FID C 6 284
FID C 8 469
FID C 10 1008
FID C 11 2379
FID H 12 205
#NET 134
NET LED1
SNT TOP T 57 0
FID C 9 13
FID C 10 35
FID C 11 1410
SNT TOP T 77 80
FID C 9 465
FID C 10 509
FID C 11 1878
SNT TRC
FID C 2 144
SNT TRC
FID C 3 161
SNT TRC
FID C 11 60
SNT TRC
FID C 11 61
SNT TRC
FID C 11 76
SNT TRC
FID C 11 662
SNT TRC
FID C 11 665
SNT VIA
FID C 2 507
FID C 6 233
FID C 8 418
FID C 10 957
FID C 11 2328
FID H 12 154
SNT VIA
FID C 2 506
FID C 3 578
FID C 6 232
FID C 8 417
FID C 10 956
FID C 11 2327
FID H 12 153
SNT VIA
FID C 3 659
FID C 6 434
FID C 8 619
FID C 10 1158
FID C 11 2529
FID H 12 355
#NET 135
NET LED2
SNT TOP T 56 0
FID C 9 25
FID C 10 47
FID C 11 1422
SNT TOP T 77 78
FID C 9 466
FID C 10 510
FID C 11 1879
SNT TRC
FID C 2 146
SNT TRC
FID C 2 145
SNT TRC
FID C 3 166
SNT TRC
FID C 3 431
SNT TRC
FID C 3 165
SNT TRC
FID C 11 77
SNT TRC
FID C 11 78
SNT TRC
FID C 11 109
SNT TRC
FID C 11 684
SNT TRC
FID C 11 673
SNT TRC
FID C 11 678
SNT VIA
FID C 2 509
FID C 6 235
FID C 8 420
FID C 10 959
FID C 11 2330
FID H 12 156
SNT VIA
FID C 2 508
FID C 3 579
FID C 6 234
FID C 8 419
FID C 10 958
FID C 11 2329
FID H 12 155
SNT VIA
FID C 3 662
FID C 6 439
FID C 8 624
FID C 10 1163
FID C 11 2534
FID H 12 360
#NET 136
NET GND
SNT TOP B 1 1
FID C 1 34
FID C 6 69
FID C 8 258
SNT TOP B 2 1
FID C 1 30
FID C 6 65
FID C 8 254
SNT TOP B 3 1
FID C 1 49
FID C 6 89
FID C 8 273
SNT TOP B 4 1
FID C 1 57
FID C 6 97
FID C 8 281
SNT TOP T 76 14
FID C 1 35
FID C 6 74
FID C 8 259
SNT TOP T 76 11
FID C 1 20
FID C 6 55
FID C 8 244
SNT TOP T 76 23
FID C 1 60
FID C 6 100
FID C 8 284
SNT TOP T 76 27
FID C 1 68
FID C 6 108
FID C 8 292
SNT TOP T 76 22
FID C 1 59
FID C 6 99
FID C 8 283
SNT TOP T 76 30
FID C 1 75
FID C 6 118
FID C 8 302
SNT TOP T 76 26
FID C 1 67
FID C 6 107
FID C 8 291
SNT TOP T 76 19
FID C 1 48
FID C 6 88
FID C 8 272
SNT TOP T 76 17
FID C 1 46
FID C 6 86
FID C 8 270
SNT TOP T 76 3
FID C 1 12
FID C 6 42
FID C 8 230
SNT TOP B 0 9
FID C 1 25
FID C 6 60
FID C 8 249
SNT TOP T 144 4
FID C 4 12
FID C 5 12
FID C 6 12
FID C 8 202
FID C 10 12
FID C 11 1387
FID H 12 3
SNT TOP T 144 3
FID C 4 11
FID C 5 11
FID C 6 11
FID C 8 201
FID C 10 11
FID C 11 1386
FID H 12 2
SNT TOP T 144 2
FID C 4 19
FID C 5 19
FID C 6 25
FID C 8 215
FID C 10 25
FID C 11 1400
FID H 12 16
SNT TOP T 144 1
FID C 4 20
FID C 5 20
FID C 6 26
FID C 8 216
FID C 10 26
FID C 11 1401
FID H 12 17
SNT TOP T 145 4
FID C 4 14
FID C 5 14
FID C 6 14
FID C 8 204
FID C 10 14
FID C 11 1389
FID H 12 5
SNT TOP T 145 3
FID C 4 13
FID C 5 13
FID C 6 13
FID C 8 203
FID C 10 13
FID C 11 1388
FID H 12 4
SNT TOP T 145 2
FID C 4 21
FID C 5 21
FID C 6 27
FID C 8 217
FID C 10 27
FID C 11 1402
FID H 12 18
SNT TOP T 145 1
FID C 4 22
FID C 5 22
FID C 6 28
FID C 8 218
FID C 10 28
FID C 11 1403
FID H 12 19
SNT TOP T 146 4
FID C 4 16
FID C 5 16
FID C 6 16
FID C 8 206
FID C 10 16
FID C 11 1391
FID H 12 7
SNT TOP T 146 3
FID C 4 15
FID C 5 15
FID C 6 15
FID C 8 205
FID C 10 15
FID C 11 1390
FID H 12 6
SNT TOP T 146 2
FID C 4 23
FID C 5 23
FID C 6 29
FID C 8 219
FID C 10 29
FID C 11 1404
FID H 12 20
SNT TOP T 146 1
FID C 4 24
FID C 5 24
FID C 6 30
FID C 8 220
FID C 10 30
FID C 11 1405
FID H 12 21
SNT TOP T 81 5
FID C 4 30
FID C 5 30
FID C 6 149
FID C 8 331
FID C 10 827
FID C 11 2194
FID H 12 70
SNT TOP T 81 6
FID C 4 31
FID C 5 31
FID C 6 152
FID C 8 334
FID C 10 859
FID C 11 2226
FID H 12 73
SNT TOP T 81 7
FID C 4 32
FID C 5 32
FID C 6 154
FID C 8 336
FID C 10 871
FID C 11 2238
FID H 12 75
SNT TOP T 143 4
FID C 4 10
FID C 5 10
FID C 6 10
FID C 8 200
FID C 10 10
FID C 11 1385
FID H 12 1
SNT TOP T 143 3
FID C 4 9
FID C 5 9
FID C 6 9
FID C 8 199
FID C 10 9
FID C 11 1384
FID H 12 0
SNT TOP T 143 2
FID C 4 17
FID C 5 17
FID C 6 23
FID C 8 213
FID C 10 23
FID C 11 1398
FID H 12 14
SNT TOP T 143 1
FID C 4 18
FID C 5 18
FID C 6 24
FID C 8 214
FID C 10 24
FID C 11 1399
FID H 12 15
SNT TOP T 82 1
FID C 4 29
FID C 5 29
FID C 6 148
FID C 8 330
FID C 10 757
FID C 11 2124
FID H 12 69
SNT TOP T 82 2
FID C 4 28
FID C 5 28
FID C 6 146
FID C 8 328
FID C 10 747
FID C 11 2114
FID H 12 67
SNT TOP T 40 23
FID C 4 25
FID C 5 25
FID C 6 128
FID C 8 310
FID C 10 652
FID C 11 2019
FID H 12 49
SNT TOP T 40 21
FID C 4 27
FID C 5 27
FID C 6 142
FID C 8 324
FID C 10 738
FID C 11 2105
FID H 12 63
SNT TOP T 13 5
FID C 4 26
FID C 5 26
FID C 6 138
FID C 8 320
FID C 10 730
FID C 11 2097
FID H 12 59
SNT TOP T 16 0
FID C 9 642
FID C 10 696
FID C 11 2063
SNT TOP T 17 0
FID C 9 599
FID C 10 649
FID C 11 2016
SNT TOP T 18 0
FID C 9 613
FID C 10 666
FID C 11 2033
SNT TOP T 21 0
FID C 9 634
FID C 10 687
FID C 11 2054
SNT TOP T 22 0
FID C 9 641
FID C 10 695
FID C 11 2062
SNT TOP T 23 0
FID C 9 645
FID C 10 699
FID C 11 2066
SNT TOP T 24 0
FID C 9 650
FID C 10 707
FID C 11 2074
SNT TOP T 25 0
FID C 9 654
FID C 10 711
FID C 11 2078
SNT TOP T 26 0
FID C 9 659
FID C 10 716
FID C 11 2083
SNT TOP T 27 0
FID C 9 639
FID C 10 693
FID C 11 2060
SNT TOP T 28 0
FID C 9 757
FID C 10 832
FID C 11 2199
SNT TOP T 29 0
FID C 9 760
FID C 10 835
FID C 11 2202
SNT TOP T 30 0
FID C 9 150
FID C 10 180
FID C 11 1552
SNT TOP T 31 0
FID C 9 108
FID C 10 138
FID C 11 1510
SNT TOP T 41 9
FID C 9 219
FID C 10 254
FID C 11 1628
SNT TOP T 43 4
FID C 9 579
FID C 10 627
FID C 11 1994
SNT TOP T 43 12
FID C 9 605
FID C 10 657
FID C 11 2024
SNT TOP T 46 3
FID C 9 763
FID C 10 838
FID C 11 2205
SNT TOP T 49 0
FID C 9 655
FID C 10 712
FID C 11 2079
SNT TOP T 68 0
FID C 9 679
FID C 10 749
FID C 11 2116
SNT TOP T 69 0
FID C 9 800
FID C 10 880
FID C 11 2247
SNT TOP T 70 0
FID C 9 718
FID C 10 790
FID C 11 2157
SNT TOP T 71 0
FID C 9 783
FID C 10 858
FID C 11 2225
SNT TOP T 75 0
FID C 9 632
FID C 10 685
FID C 11 2052
SNT TOP T 87 1
FID C 9 46
FID C 10 68
FID C 11 1443
SNT TOP T 88 1
FID C 9 48
FID C 10 70
FID C 11 1445
SNT TOP T 89 1
FID C 9 47
FID C 10 69
FID C 11 1444
SNT TOP T 97 0
FID C 9 444
FID C 10 487
FID C 11 1856
SNT TOP T 98 0
FID C 9 337
FID C 10 377
FID C 11 1746
SNT TOP T 99 0
FID C 9 371
FID C 10 411
FID C 11 1780
SNT TOP T 104 0
FID C 9 565
FID C 10 613
FID C 11 1980
SNT TOP T 105 0
FID C 9 574
FID C 10 622
FID C 11 1989
SNT TOP T 106 0
FID C 9 566
FID C 10 614
FID C 11 1981
SNT TOP T 107 1
FID C 9 563
FID C 10 611
FID C 11 1978
SNT TOP T 108 1
FID C 9 560
FID C 10 608
FID C 11 1975
SNT TOP T 109 1
FID C 9 330
FID C 10 370
FID C 11 1739
SNT TOP T 110 1
FID C 9 304
FID C 10 344
FID C 11 1713
SNT TOP T 111 1
FID C 9 171
FID C 10 204
FID C 11 1578
SNT TOP T 112 1
FID C 9 182
FID C 10 217
FID C 11 1591
SNT TOP T 113 1
FID C 9 755
FID C 10 830
FID C 11 2197
SNT TOP T 114 1
FID C 9 733
FID C 10 805
FID C 11 2172
SNT TOP T 115 0
FID C 9 637
FID C 10 691
FID C 11 2058
SNT TOP T 116 0
FID C 9 626
FID C 10 679
FID C 11 2046
SNT TOP T 118 0
FID C 9 685
FID C 10 755
FID C 11 2122
SNT TOP T 120 0
FID C 9 794
FID C 10 874
FID C 11 2241
SNT TOP T 121 1
FID C 9 770
FID C 10 845
FID C 11 2212
SNT TOP T 122 1
FID C 9 769
FID C 10 844
FID C 11 2211
SNT TOP T 123 1
FID C 9 768
FID C 10 843
FID C 11 2210
SNT TOP T 124 1
FID C 9 767
FID C 10 842
FID C 11 2209
SNT TOP T 125 1
FID C 9 762
FID C 10 837
FID C 11 2204
SNT TOP T 126 1
FID C 9 761
FID C 10 836
FID C 11 2203
SNT TOP T 127 1
FID C 9 716
FID C 10 788
FID C 11 2155
SNT TOP T 128 1
FID C 9 715
FID C 10 787
FID C 11 2154
SNT TOP T 129 1
FID C 9 714
FID C 10 786
FID C 11 2153
SNT TOP T 130 1
FID C 9 717
FID C 10 789
FID C 11 2156
SNT TOP T 131 1
FID C 9 720
FID C 10 792
FID C 11 2159
SNT TOP T 132 1
FID C 9 698
FID C 10 770
FID C 11 2137
SNT TOP T 133 1
FID C 9 772
FID C 10 847
FID C 11 2214
SNT TOP T 134 1
FID C 9 706
FID C 10 778
FID C 11 2145
SNT TOP T 137 1
FID C 9 674
FID C 10 741
FID C 11 2108
SNT TOP T 138 1
FID C 9 675
FID C 10 744
FID C 11 2111
SNT TOP T 140 2
FID C 9 19
FID C 10 41
FID C 11 1416
SNT TOP T 140 1
FID C 9 20
FID C 10 42
FID C 11 1417
SNT TOP T 141 1
FID C 9 24
FID C 10 46
FID C 11 1421
SNT TOP T 141 2
FID C 9 23
FID C 10 45
FID C 11 1420
SNT TOP T 142 1
FID C 9 22
FID C 10 44
FID C 11 1419
SNT TOP T 142 2
FID C 9 21
FID C 10 43
FID C 11 1418
SNT TOP T 77 313
FID C 9 212
FID C 10 247
FID C 11 1621
SNT TOP T 77 303
FID C 9 244
FID C 10 279
FID C 11 1653
SNT TOP T 77 293
FID C 9 271
FID C 10 311
FID C 11 1680
SNT TOP T 77 283
FID C 9 297
FID C 10 337
FID C 11 1706
SNT TOP T 77 253
FID C 9 383
FID C 10 423
FID C 11 1792
SNT TOP T 77 312
FID C 9 213
FID C 10 248
FID C 11 1622
SNT TOP T 77 302
FID C 9 245
FID C 10 280
FID C 11 1654
SNT TOP T 77 292
FID C 9 272
FID C 10 312
FID C 11 1681
SNT TOP T 77 282
FID C 9 298
FID C 10 338
FID C 11 1707
SNT TOP T 77 276
FID C 9 314
FID C 10 354
FID C 11 1723
SNT TOP T 77 270
FID C 9 329
FID C 10 369
FID C 11 1738
SNT TOP T 77 264
FID C 9 354
FID C 10 394
FID C 11 1763
SNT TOP T 77 258
FID C 9 369
FID C 10 409
FID C 11 1778
SNT TOP T 77 252
FID C 9 384
FID C 10 424
FID C 11 1793
SNT TOP T 77 233
FID C 9 91
FID C 10 117
FID C 11 1491
SNT TOP T 77 223
FID C 9 86
FID C 10 112
FID C 11 1486
SNT TOP T 77 213
FID C 9 81
FID C 10 107
FID C 11 1481
SNT TOP T 77 203
FID C 9 76
FID C 10 102
FID C 11 1476
SNT TOP T 77 193
FID C 9 71
FID C 10 97
FID C 11 1471
SNT TOP T 77 183
FID C 9 66
FID C 10 92
FID C 11 1466
SNT TOP T 77 173
FID C 9 61
FID C 10 87
FID C 11 1461
SNT TOP T 77 232
FID C 9 143
FID C 10 173
FID C 11 1545
SNT TOP T 77 222
FID C 9 138
FID C 10 168
FID C 11 1540
SNT TOP T 77 212
FID C 9 133
FID C 10 163
FID C 11 1535
SNT TOP T 77 202
FID C 9 128
FID C 10 158
FID C 11 1530
SNT TOP T 77 192
FID C 9 123
FID C 10 153
FID C 11 1525
SNT TOP T 77 182
FID C 9 118
FID C 10 148
FID C 11 1520
SNT TOP T 77 172
FID C 9 113
FID C 10 143
FID C 11 1515
SNT TOP T 77 92
FID C 9 204
FID C 10 239
FID C 11 1613
SNT TOP T 77 102
FID C 9 238
FID C 10 273
FID C 11 1647
SNT TOP T 77 112
FID C 9 262
FID C 10 302
FID C 11 1671
SNT TOP T 77 122
FID C 9 291
FID C 10 331
FID C 11 1700
SNT TOP T 77 132
FID C 9 315
FID C 10 355
FID C 11 1724
SNT TOP T 77 142
FID C 9 351
FID C 10 391
FID C 11 1760
SNT TOP T 77 152
FID C 9 376
FID C 10 416
FID C 11 1785
SNT TOP T 77 93
FID C 9 205
FID C 10 240
FID C 11 1614
SNT TOP T 77 103
FID C 9 239
FID C 10 274
FID C 11 1648
SNT TOP T 77 113
FID C 9 263
FID C 10 303
FID C 11 1672
SNT TOP T 77 123
FID C 9 292
FID C 10 332
FID C 11 1701
SNT TOP T 77 133
FID C 9 316
FID C 10 356
FID C 11 1725
SNT TOP T 77 143
FID C 9 352
FID C 10 392
FID C 11 1761
SNT TOP T 77 153
FID C 9 377
FID C 10 417
FID C 11 1786
SNT TOP T 77 73
FID C 9 525
FID C 10 573
FID C 11 1940
SNT TOP T 77 63
FID C 9 530
FID C 10 578
FID C 11 1945
SNT TOP T 77 53
FID C 9 535
FID C 10 583
FID C 11 1950
SNT TOP T 77 43
FID C 9 540
FID C 10 588
FID C 11 1955
SNT TOP T 77 33
FID C 9 545
FID C 10 593
FID C 11 1960
SNT TOP T 77 23
FID C 9 550
FID C 10 598
FID C 11 1965
SNT TOP T 77 13
FID C 9 555
FID C 10 603
FID C 11 1970
SNT TOP T 77 72
FID C 9 469
FID C 10 513
FID C 11 1882
SNT TOP T 77 62
FID C 9 474
FID C 10 518
FID C 11 1887
SNT TOP T 77 52
FID C 9 479
FID C 10 523
FID C 11 1892
SNT TOP T 77 42
FID C 9 484
FID C 10 528
FID C 11 1897
SNT TOP T 77 32
FID C 9 489
FID C 10 533
FID C 11 1902
SNT TOP T 77 22
FID C 9 494
FID C 10 538
FID C 11 1907
SNT TOP T 77 12
FID C 9 499
FID C 10 543
FID C 11 1912
SNT TOP T 0 2
FID C 9 432
FID C 10 475
FID C 11 1844
SNT TOP T 0 7
FID C 9 441
FID C 10 484
FID C 11 1853
SNT TOP T 0 8
FID C 9 442
FID C 10 485
FID C 11 1854
SNT TOP T 20 0
FID C 9 628
FID C 10 681
FID C 11 2048
SNT TOP T 19 0
FID C 9 610
FID C 10 662
FID C 11 2029
SNT TOP T 15 0
FID C 9 651
FID C 10 708
FID C 11 2075
SNT TOP T 86 1
FID C 9 45
FID C 10 67
FID C 11 1442
SNT TOP T 14 0
FID C 9 666
FID C 10 724
FID C 11 2091
SNT TOP T 42 1
FID C 9 740
FID C 10 812
FID C 11 2179
SNT TOP T 42 24
FID C 9 747
FID C 10 819
FID C 11 2186
SNT TOP T 40 14
FID C 9 622
FID C 10 675
FID C 11 2042
SNT TOP T 40 8
FID C 9 619
FID C 10 672
FID C 11 2039
SNT TOP T 40 7
FID C 9 591
FID C 10 640
FID C 11 2007
SNT TOP T 48 0
FID C 9 667
FID C 10 727
FID C 11 2094
SNT TOP T 76 63
FID C 9 417
FID C 10 460
FID C 11 1829
SNT TOP T 76 60
FID C 9 402
FID C 10 442
FID C 11 1811
SNT TOP T 76 57
FID C 9 370
FID C 10 410
FID C 11 1779
SNT TOP T 76 53
FID C 9 320
FID C 10 360
FID C 11 1729
SNT TOP T 76 52
FID C 9 310
FID C 10 350
FID C 11 1719
SNT TOP T 76 38
FID C 9 167
FID C 10 197
FID C 11 1570
SNT TOP T 76 35
FID C 9 162
FID C 10 192
FID C 11 1565
SNT TOP T 76 56
FID C 9 360
FID C 10 400
FID C 11 1769
SNT TOP T 76 44
FID C 9 223
FID C 10 258
FID C 11 1632
SNT TOP T 76 47
FID C 9 257
FID C 10 297
FID C 11 1666
SNT TOP T 76 49
FID C 9 281
FID C 10 321
FID C 11 1690
SNT TOP T 44 1
FID C 9 397
FID C 10 437
FID C 11 1806
SNT TOP T 44 9
FID C 9 448
FID C 10 492
FID C 11 1861
SNT TOP T 38 3
FID C 9 453
FID C 10 497
FID C 11 1866
SNT TOP T 39 4
FID C 9 446
FID C 10 490
FID C 11 1859
SNT TOP T 45 3
FID C 9 713
FID C 10 785
FID C 11 2152
SNT TOP T 34 4
FID C 9 100
FID C 10 126
FID C 11 1500
SNT TOP T 34 12
FID C 9 156
FID C 10 186
FID C 11 1559
SNT TOP T 96 0
FID C 9 504
FID C 10 548
FID C 11 1917
SNT TOP T 139 2
FID C 9 17
FID C 10 39
FID C 11 1414
SNT TOP T 139 1
FID C 9 18
FID C 10 40
FID C 11 1415
SNT TOP T 80 10
FID C 9 584
FID C 10 633
FID C 11 2000
SNT TOP T 35 10
FID C 9 203
FID C 10 238
FID C 11 1612
SNT TOP T 12 12
FID C 9 422
FID C 10 465
FID C 11 1834
SNT TRC
FID C 3 428
SNT TRC
FID C 3 424
SNT TRC
FID C 3 411
SNT TRC
FID C 3 393
SNT TRC
FID C 3 405
SNT TRC
FID C 3 398
SNT TRC
FID C 3 412
SNT TRC
FID C 3 419
SNT TRC
FID C 3 408
SNT TRC
FID C 3 406
SNT TRC
FID C 3 407
SNT TRC
FID C 3 409
SNT TRC
FID C 3 410
SNT TRC
FID C 8 70
SNT TRC
FID C 8 66
SNT TRC
FID C 8 65
SNT TRC
FID C 8 60
SNT TRC
FID C 8 73
SNT TRC
FID C 8 78
SNT TRC
FID C 8 74
SNT TRC
FID C 8 79
SNT TRC
FID C 8 81
SNT TRC
FID C 8 108
SNT TRC
FID C 8 106
SNT TRC
FID C 8 72
SNT TRC
FID C 8 71
SNT TRC
FID C 8 77
SNT TRC
FID C 8 76
SNT TRC
FID C 8 109
SNT TRC
FID C 8 114
SNT TRC
FID C 8 119
SNT TRC
FID C 8 158
SNT TRC
FID C 8 147
SNT TRC
FID C 8 129
SNT TRC
FID C 8 57
SNT TRC
FID C 8 130
SNT TRC
FID C 8 159
SNT TRC
FID C 8 162
SNT TRC
FID C 8 160
SNT TRC
FID C 8 143
SNT TRC
FID C 8 141
SNT TRC
FID C 8 142
SNT TRC
FID C 8 125
SNT TRC
FID C 8 123
SNT TRC
FID C 8 146
SNT TRC
FID C 8 161
SNT TRC
FID C 8 104
SNT TRC
FID C 8 144
SNT TRC
FID C 8 124
SNT TRC
FID C 8 131
SNT TRC
FID C 8 145
SNT TRC
FID C 8 48
SNT TRC
FID C 8 164
SNT TRC
FID C 8 163
SNT TRC
FID C 8 98
SNT TRC
FID C 8 133
SNT TRC
FID C 8 105
SNT TRC
FID C 8 82
SNT TRC
FID C 8 80
SNT TRC
FID C 8 140
SNT TRC
FID C 8 139
SNT TRC
FID C 8 138
SNT TRC
FID C 11 66
SNT TRC
FID C 11 75
SNT TRC
FID C 11 74
SNT TRC
FID C 11 73
SNT TRC
FID C 11 72
SNT TRC
FID C 11 65
SNT TRC
FID C 11 71
SNT TRC
FID C 11 70
SNT TRC
FID C 11 69
SNT TRC
FID C 11 68
SNT TRC
FID C 11 67
SNT TRC
FID C 11 121
SNT TRC
FID C 11 115
SNT TRC
FID C 11 122
SNT TRC
FID C 11 116
SNT TRC
FID C 11 631
SNT TRC
FID C 11 632
SNT TRC
FID C 11 739
SNT TRC
FID C 11 747
SNT TRC
FID C 11 740
SNT TRC
FID C 11 474
SNT TRC
FID C 11 475
SNT TRC
FID C 11 480
SNT TRC
FID C 11 481
SNT TRC
FID C 11 487
SNT TRC
FID C 11 533
SNT TRC
FID C 11 532
SNT TRC
FID C 11 1045
SNT TRC
FID C 11 1044
SNT TRC
FID C 11 1043
SNT TRC
FID C 11 1041
SNT TRC
FID C 11 1040
SNT TRC
FID C 11 1007
SNT TRC
FID C 11 959
SNT TRC
FID C 11 962
SNT TRC
FID C 11 963
SNT TRC
FID C 11 868
SNT TRC
FID C 11 864
SNT TRC
FID C 11 866
SNT TRC
FID C 11 1037
SNT TRC
FID C 11 1080
SNT TRC
FID C 11 1085
SNT TRC
FID C 11 1232
SNT TRC
FID C 11 1218
SNT TRC
FID C 11 1230
SNT TRC
FID C 11 1217
SNT TRC
FID C 11 1216
SNT TRC
FID C 11 1215
SNT TRC
FID C 11 1222
SNT TRC
FID C 11 1221
SNT TRC
FID C 11 1179
SNT TRC
FID C 11 1127
SNT TRC
FID C 11 1131
SNT TRC
FID C 11 1229
SNT TRC
FID C 11 1200
SNT TRC
FID C 11 1314
SNT TRC
FID C 11 1323
SNT TRC
FID C 11 1379
SNT TRC
FID C 11 1376
SNT TRC
FID C 11 1382
SNT TRC
FID C 11 1319
SNT TRC
FID C 11 1336
SNT TRC
FID C 11 1348
SNT TRC
FID C 11 1352
SNT TRC
FID C 11 1299
SNT TRC
FID C 11 1303
SNT TRC
FID C 11 1302
SNT TRC
FID C 11 1306
SNT TRC
FID C 11 1301
SNT TRC
FID C 11 1305
SNT TRC
FID C 11 1300
SNT TRC
FID C 11 1304
SNT TRC
FID C 11 1290
SNT TRC
FID C 11 814
SNT TRC
FID C 11 1111
SNT TRC
FID C 11 1110
SNT TRC
FID C 11 1115
SNT TRC
FID C 11 841
SNT TRC
FID C 11 840
SNT TRC
FID C 11 839
SNT TRC
FID C 11 821
SNT TRC
FID C 11 818
SNT TRC
FID C 11 824
SNT TRC
FID C 11 817
SNT TRC
FID C 11 882
SNT TRC
FID C 11 865
SNT TRC
FID C 11 863
SNT TRC
FID C 11 853
SNT TRC
FID C 11 852
SNT TRC
FID C 11 298
SNT TRC
FID C 11 297
SNT TRC
FID C 11 205
SNT TRC
FID C 11 209
SNT TRC
FID C 11 1035
SNT TRC
FID C 11 289
SNT TRC
FID C 11 284
SNT TRC
FID C 11 281
SNT TRC
FID C 11 288
SNT TRC
FID C 11 287
SNT TRC
FID C 11 657
SNT TRC
FID C 11 701
SNT TRC
FID C 11 541
SNT TRC
FID C 11 542
SNT TRC
FID C 11 1315
SNT TRC
FID C 11 1312
SNT TRC
FID C 11 974
SNT TRC
FID C 11 973
SNT TRC
FID C 11 970
SNT TRC
FID C 11 969
SNT TRC
FID C 11 129
SNT TRC
FID C 11 119
SNT TRC
FID C 11 1049
SNT TRC
FID C 11 1032
SNT TRC
FID C 11 1034
SNT TRC
FID C 11 1262
SNT TRC
FID C 11 1263
SNT TRC
FID C 11 798
SNT TRC
FID C 11 181
SNT TRC
FID C 11 168
SNT TRC
FID C 11 1018
SNT TRC
FID C 11 424
SNT TRC
FID C 11 422
SNT TRC
FID C 11 438
SNT TRC
FID C 11 1264
SNT TRC
FID C 11 1292
SNT TRC
FID C 11 1294
SNT TRC
FID C 11 939
SNT TRC
FID C 11 938
SNT TRC
FID C 11 936
SNT TRC
FID C 11 123
SNT TRC
FID C 11 118
SNT TRC
FID C 11 117
SNT TRC
FID C 11 472
SNT TRC
FID C 11 992
SNT TRC
FID C 11 993
SNT TRC
FID C 11 994
SNT TRC
FID C 11 996
SNT TRC
FID C 11 1016
SNT TRC
FID C 11 1011
SNT TRC
FID C 11 1013
SNT TRC
FID C 11 1014
SNT TRC
FID C 11 1010
SNT TRC
FID C 11 1012
SNT TRC
FID C 11 271
SNT TRC
FID C 11 1023
SNT TRC
FID C 11 1024
SNT TRC
FID C 11 671
SNT TRC
FID C 11 651
SNT TRC
FID C 11 880
SNT TRC
FID C 11 878
SNT TRC
FID C 11 858
SNT TRC
FID C 11 221
SNT TRC
FID C 11 1267
SNT TRC
FID C 11 1268
SNT TRC
FID C 11 1270
SNT TRC
FID C 11 1308
SNT TRC
FID C 11 1313
SNT TRC
FID C 11 1297
SNT TRC
FID C 11 1316
SNT TRC
FID C 11 1246
SNT TRC
FID C 11 1245
SNT TRC
FID C 11 1175
SNT TRC
FID C 11 1225
SNT TRC
FID C 11 792
SNT TRC
FID C 11 793
SNT TRC
FID C 11 797
SNT TRC
FID C 11 906
SNT TRC
FID C 11 907
SNT TRC
FID C 11 890
SNT TRC
FID C 11 979
SNT TRC
FID C 11 926
SNT TRC
FID C 11 925
SNT TRC
FID C 11 955
SNT TRC
FID C 11 982
SNT TRC
FID C 11 904
SNT TRC
FID C 11 1380
SNT TRC
FID C 11 1383
SNT TRC
FID C 11 1318
SNT TRC
FID C 11 1317
SNT TRC
FID C 11 947
SNT TRC
FID C 11 1050
SNT TRC
FID C 11 1054
SNT TRC
FID C 11 1053
SNT TRC
FID C 11 220
SNT TRC
FID C 11 204
SNT TRC
FID C 11 203
SNT TRC
FID C 11 310
SNT TRC
FID C 11 311
SNT TRC
FID C 11 640
SNT TRC
FID C 11 630
SNT TRC
FID C 11 629
SNT TRC
FID C 11 613
SNT TRC
FID C 11 612
SNT TRC
FID C 11 1079
SNT TRC
FID C 11 587
SNT TRC
FID C 11 592
SNT TRC
FID C 11 1077
SNT TRC
FID C 11 1078
SNT TRC
FID C 11 977
SNT TRC
FID C 11 987
SNT TRC
FID C 11 647
SNT TRC
FID C 11 646
SNT TRC
FID C 11 252
SNT TRC
FID C 11 251
SNT TRC
FID C 11 504
SNT TRC
FID C 11 456
SNT TRC
FID C 11 505
SNT TRC
FID C 11 530
SNT TRC
FID C 11 531
SNT TRC
FID C 11 303
SNT TRC
FID C 11 257
SNT TRC
FID C 11 433
SNT TRC
FID C 11 454
SNT TRC
FID C 11 455
SNT TRC
FID C 11 431
SNT TRC
FID C 11 318
SNT TRC
FID C 11 513
SNT TRC
FID C 11 514
SNT TRC
FID C 11 256
SNT TRC
FID C 11 319
SNT TRC
FID C 11 522
SNT TRC
FID C 11 320
SNT TRC
FID C 11 529
SNT TRC
FID C 11 730
SNT TRC
FID C 11 189
SNT TRC
FID C 11 155
SNT TRC
FID C 11 158
SNT TRC
FID C 11 164
SNT TRC
FID C 11 757
SNT TRC
FID C 11 193
SNT TRC
FID C 11 179
SNT TRC
FID C 11 703
SNT TRC
FID C 11 709
SNT TRC
FID C 11 444
SNT TRC
FID C 11 197
SNT TRC
FID C 11 686
SNT TRC
FID C 11 732
SNT TRC
FID C 11 397
SNT TRC
FID C 11 186
SNT TRC
FID C 11 749
SNT TRC
FID C 11 156
SNT TRC
FID C 11 789
SNT TRC
FID C 11 194
SNT TRC
FID C 11 333
SNT TRC
FID C 11 301
SNT TRC
FID C 11 554
SNT TRC
FID C 11 690
SNT TRC
FID C 11 681
SNT TRC
FID C 11 446
SNT TRC
FID C 11 536
SNT TRC
FID C 11 182
SNT TRC
FID C 11 833
SNT TRC
FID C 11 785
SNT TRC
FID C 11 395
SNT TRC
FID C 11 157
SNT TRC
FID C 11 163
SNT TRC
FID C 11 171
SNT TRC
FID C 11 759
SNT TRC
FID C 11 192
SNT TRC
FID C 11 708
SNT TRC
FID C 11 406
SNT TRC
FID C 11 307
SNT TRC
FID C 11 381
SNT TRC
FID C 11 675
SNT TRC
FID C 11 807
SNT TRC
FID C 11 437
SNT TRC
FID C 11 159
SNT TRC
FID C 11 552
SNT TRC
FID C 11 154
SNT TRC
FID C 11 332
SNT TRC
FID C 11 834
SNT TRC
FID C 11 776
SNT TRC
FID C 11 382
SNT TRC
FID C 11 198
SNT TRC
FID C 11 685
SNT TRC
FID C 11 810
SNT TRC
FID C 11 744
SNT TRC
FID C 11 199
SNT TRC
FID C 11 187
SNT TRC
FID C 11 676
SNT TRC
FID C 11 436
SNT TRC
FID C 11 183
SNT TRC
FID C 11 786
SNT TRC
FID C 11 293
SNT TRC
FID C 11 331
SNT TRC
FID C 11 713
SNT TRC
FID C 11 538
SNT TRC
FID C 11 338
SNT TRC
FID C 11 160
SNT TRC
FID C 11 811
SNT TRC
FID C 11 795
SNT TRC
FID C 11 445
SNT TRC
FID C 11 335
SNT TRC
FID C 11 729
SNT TRC
FID C 11 784
SNT TRC
FID C 11 305
SNT TRC
FID C 11 178
SNT TRC
FID C 11 202
SNT TRC
FID C 11 842
SNT TRC
FID C 11 190
SNT TRC
FID C 11 800
SNT TRC
FID C 11 553
SNT TRC
FID C 11 180
SNT TRC
FID C 11 761
SNT TRC
FID C 11 383
SNT TRC
FID C 11 680
SNT TRC
FID C 11 407
SNT TRC
FID C 11 308
SNT TRC
FID C 11 366
SNT TRC
FID C 11 687
SNT TRC
FID C 11 500
SNT TRC
FID C 11 368
SNT TRC
FID C 11 172
SNT TRC
FID C 11 539
SNT TRC
FID C 11 399
SNT TRC
FID C 11 334
SNT TRC
FID C 11 548
SNT TRC
FID C 11 711
SNT TRC
FID C 11 443
SNT TRC
FID C 11 201
SNT TRC
FID C 11 679
SNT TRC
FID C 11 302
SNT TRC
FID C 11 367
SNT TRC
FID C 11 788
SNT TRC
FID C 11 191
SNT TRC
FID C 11 299
SNT TRC
FID C 11 300
SNT TRC
FID C 11 200
SNT TRC
FID C 11 537
SNT TRC
FID C 11 398
SNT TRC
FID C 11 733
SNT TRC
FID C 11 364
SNT TRC
FID C 11 714
SNT TRC
FID C 11 499
SNT TRC
FID C 11 306
SNT TRC
FID C 11 388
SNT TRC
FID C 11 389
SNT TRC
FID C 11 571
SNT TRC
FID C 11 572
SNT TRC
FID C 11 528
SNT TRC
FID C 11 527
SNT TRC
FID C 11 502
SNT TRC
FID C 11 501
SNT TRC
FID C 11 471
SNT TRC
FID C 11 468
SNT TRC
FID C 11 339
SNT TRC
FID C 11 460
SNT TRC
FID C 11 450
SNT TRC
FID C 11 457
SNT TRC
FID C 11 419
SNT TRC
FID C 11 421
SNT TRC
FID C 11 420
SNT TRC
FID C 11 404
SNT TRC
FID C 11 405
SNT TRC
FID C 11 586
SNT TRC
FID C 11 585
SNT TRC
FID C 11 347
SNT TRC
FID C 11 357
SNT TRC
FID C 11 358
SNT TRC
FID C 11 569
SNT TRC
FID C 11 570
SNT TRC
FID C 11 565
SNT TRC
FID C 11 932
SNT TRC
FID C 11 923
SNT TRC
FID C 11 5
SNT TRC
FID C 11 46
SNT TRC
FID C 8 5
SNT TRC
FID C 8 24
SNT VIA
FID C 4 37
FID C 5 37
FID C 6 160
FID C 8 345
FID C 10 884
FID C 11 2255
FID H 12 81
SNT VIA
FID C 4 42
FID C 5 42
FID C 6 165
FID C 8 350
FID C 10 889
FID C 11 2260
FID H 12 86
SNT VIA
FID C 4 41
FID C 5 41
FID C 6 164
FID C 8 349
FID C 10 888
FID C 11 2259
FID H 12 85
SNT VIA
FID C 4 40
FID C 5 40
FID C 6 163
FID C 8 348
FID C 10 887
FID C 11 2258
FID H 12 84
SNT VIA
FID C 4 36
FID C 5 36
FID C 6 159
FID C 8 344
FID C 10 883
FID C 11 2254
FID H 12 80
SNT VIA
FID C 4 39
FID C 5 39
FID C 6 162
FID C 8 347
FID C 10 886
FID C 11 2257
FID H 12 83
SNT VIA
FID C 4 43
FID C 5 43
FID C 6 166
FID C 8 351
FID C 10 890
FID C 11 2261
FID H 12 87
SNT VIA
FID C 4 38
FID C 5 38
FID C 6 161
FID C 8 346
FID C 10 885
FID C 11 2256
FID H 12 82
SNT VIA
FID C 4 47
FID C 5 47
FID C 6 178
FID C 8 363
FID C 10 902
FID C 11 2273
FID H 12 99
SNT VIA
FID C 4 45
FID C 5 45
FID C 6 176
FID C 8 361
FID C 10 900
FID C 11 2271
FID H 12 97
SNT VIA
FID C 4 121
FID C 5 121
FID C 6 421
FID C 8 606
FID C 10 1145
FID C 11 2516
FID H 12 342
SNT VIA
FID C 4 130
FID C 5 130
FID C 6 454
FID C 8 639
FID C 10 1178
FID C 11 2549
FID H 12 375
SNT VIA
FID C 4 105
FID C 5 105
FID C 6 360
FID C 8 545
FID C 10 1084
FID C 11 2455
FID H 12 281
SNT VIA
FID C 4 111
FID C 5 111
FID C 6 384
FID C 8 569
FID C 10 1108
FID C 11 2479
FID H 12 305
SNT VIA
FID C 4 166
FID C 5 166
FID C 6 531
FID C 8 716
FID C 10 1255
FID C 11 2626
FID H 12 452
SNT VIA
FID C 4 159
FID C 5 159
FID C 6 523
FID C 8 708
FID C 10 1247
FID C 11 2618
FID H 12 444
SNT VIA
FID C 4 154
FID C 5 154
FID C 6 514
FID C 8 699
FID C 10 1238
FID C 11 2609
FID H 12 435
SNT VIA
FID C 4 145
FID C 5 145
FID C 6 485
FID C 8 670
FID C 10 1209
FID C 11 2580
FID H 12 406
SNT VIA
FID C 4 165
FID C 5 165
FID C 6 530
FID C 8 715
FID C 10 1254
FID C 11 2625
FID H 12 451
SNT VIA
FID C 4 168
FID C 5 168
FID C 6 536
FID C 8 721
FID C 10 1260
FID C 11 2631
FID H 12 457
SNT VIA
FID C 4 175
FID C 5 175
FID C 6 556
FID C 8 741
FID C 10 1280
FID C 11 2651
FID H 12 477
SNT VIA
FID C 4 181
FID C 5 181
FID C 6 562
FID C 8 747
FID C 10 1286
FID C 11 2657
FID H 12 483
SNT VIA
FID C 4 179
FID C 5 179
FID C 6 560
FID C 8 745
FID C 10 1284
FID C 11 2655
FID H 12 481
SNT VIA
FID C 4 177
FID C 5 177
FID C 6 558
FID C 8 743
FID C 10 1282
FID C 11 2653
FID H 12 479
SNT VIA
FID C 4 178
FID C 5 178
FID C 6 559
FID C 8 744
FID C 10 1283
FID C 11 2654
FID H 12 480
SNT VIA
FID C 4 180
FID C 5 180
FID C 6 561
FID C 8 746
FID C 10 1285
FID C 11 2656
FID H 12 482
SNT VIA
FID C 4 174
FID C 5 174
FID C 6 547
FID C 8 732
FID C 10 1271
FID C 11 2642
FID H 12 468
SNT VIA
FID C 4 171
FID C 5 171
FID C 6 544
FID C 8 729
FID C 10 1268
FID C 11 2639
FID H 12 465
SNT VIA
FID C 4 172
FID C 5 172
FID C 6 545
FID C 8 730
FID C 10 1269
FID C 11 2640
FID H 12 466
SNT VIA
FID C 4 176
FID C 5 176
FID C 6 557
FID C 8 742
FID C 10 1281
FID C 11 2652
FID H 12 478
SNT VIA
FID C 4 189
FID C 5 189
FID C 6 577
FID C 8 762
FID C 10 1301
FID C 11 2672
FID H 12 498
SNT VIA
FID C 4 196
FID C 5 196
FID C 6 585
FID C 8 770
FID C 10 1309
FID C 11 2680
FID H 12 506
SNT VIA
FID C 4 195
FID C 5 195
FID C 6 583
FID C 8 768
FID C 10 1307
FID C 11 2678
FID H 12 504
SNT VIA
FID C 4 194
FID C 5 194
FID C 6 582
FID C 8 767
FID C 10 1306
FID C 11 2677
FID H 12 503
SNT VIA
FID C 4 185
FID C 5 185
FID C 6 573
FID C 8 758
FID C 10 1297
FID C 11 2668
FID H 12 494
SNT VIA
FID C 4 188
FID C 5 188
FID C 6 576
FID C 8 761
FID C 10 1300
FID C 11 2671
FID H 12 497
SNT VIA
FID C 4 187
FID C 5 187
FID C 6 575
FID C 8 760
FID C 10 1299
FID C 11 2670
FID H 12 496
SNT VIA
FID C 4 186
FID C 5 186
FID C 6 574
FID C 8 759
FID C 10 1298
FID C 11 2669
FID H 12 495
SNT VIA
FID C 4 184
FID C 5 184
FID C 6 572
FID C 8 757
FID C 10 1296
FID C 11 2667
FID H 12 493
SNT VIA
FID C 4 137
FID C 5 137
FID C 6 468
FID C 8 653
FID C 10 1192
FID C 11 2563
FID H 12 389
SNT VIA
FID C 4 169
FID C 5 169
FID C 6 541
FID C 8 726
FID C 10 1265
FID C 11 2636
FID H 12 462
SNT VIA
FID C 4 170
FID C 5 170
FID C 6 542
FID C 8 727
FID C 10 1266
FID C 11 2637
FID H 12 463
SNT VIA
FID C 4 139
FID C 5 139
FID C 6 475
FID C 8 660
FID C 10 1199
FID C 11 2570
FID H 12 396
SNT VIA
FID C 4 144
FID C 5 144
FID C 6 483
FID C 8 668
FID C 10 1207
FID C 11 2578
FID H 12 404
SNT VIA
FID C 4 147
FID C 5 147
FID C 6 496
FID C 8 681
FID C 10 1220
FID C 11 2591
FID H 12 417
SNT VIA
FID C 4 72
FID C 5 72
FID C 6 263
FID C 8 448
FID C 10 987
FID C 11 2358
FID H 12 184
SNT VIA
FID C 4 65
FID C 5 65
FID C 6 210
FID C 8 395
FID C 10 934
FID C 11 2305
FID H 12 131
SNT VIA
FID C 4 71
FID C 5 71
FID C 6 259
FID C 8 444
FID C 10 983
FID C 11 2354
FID H 12 180
SNT VIA
FID C 3 657
FID C 4 124
FID C 5 124
FID C 6 432
FID C 8 617
FID C 10 1156
FID C 11 2527
FID H 12 353
SNT VIA
FID C 4 115
FID C 5 115
FID C 6 389
FID C 8 574
FID C 10 1113
FID C 11 2484
FID H 12 310
SNT VIA
FID C 4 193
FID C 5 193
FID C 6 581
FID C 8 766
FID C 10 1305
FID C 11 2676
FID H 12 502
SNT VIA
FID C 4 155
FID C 5 155
FID C 6 515
FID C 8 700
FID C 10 1239
FID C 11 2610
FID H 12 436
SNT VIA
FID C 4 48
FID C 5 48
FID C 6 179
FID C 8 364
FID C 10 903
FID C 11 2274
FID H 12 100
SNT VIA
FID C 4 163
FID C 5 163
FID C 6 528
FID C 8 713
FID C 10 1252
FID C 11 2623
FID H 12 449
SNT VIA
FID C 4 183
FID C 5 183
FID C 6 569
FID C 8 754
FID C 10 1293
FID C 11 2664
FID H 12 490
SNT VIA
FID C 4 138
FID C 5 138
FID C 6 471
FID C 8 656
FID C 10 1195
FID C 11 2566
FID H 12 392
SNT VIA
FID C 4 56
FID C 5 56
FID C 6 200
FID C 8 385
FID C 10 924
FID C 11 2295
FID H 12 121
SNT VIA
FID C 4 182
FID C 5 182
FID C 6 568
FID C 8 753
FID C 10 1292
FID C 11 2663
FID H 12 489
SNT VIA
FID C 4 161
FID C 5 161
FID C 6 525
FID C 8 710
FID C 10 1249
FID C 11 2620
FID H 12 446
SNT VIA
FID C 4 100
FID C 5 100
FID C 6 345
FID C 8 530
FID C 10 1069
FID C 11 2440
FID H 12 266
SNT VIA
FID C 4 153
FID C 5 153
FID C 6 513
FID C 8 698
FID C 10 1237
FID C 11 2608
FID H 12 434
SNT VIA
FID C 4 46
FID C 5 46
FID C 6 177
FID C 8 362
FID C 10 901
FID C 11 2272
FID H 12 98
SNT VIA
FID C 4 104
FID C 5 104
FID C 6 359
FID C 8 544
FID C 10 1083
FID C 11 2454
FID H 12 280
SNT VIA
FID C 4 158
FID C 5 158
FID C 6 521
FID C 8 706
FID C 10 1245
FID C 11 2616
FID H 12 442
SNT VIA
FID C 4 190
FID C 5 190
FID C 6 578
FID C 8 763
FID C 10 1302
FID C 11 2673
FID H 12 499
SNT VIA
FID C 4 160
FID C 5 160
FID C 6 524
FID C 8 709
FID C 10 1248
FID C 11 2619
FID H 12 445
SNT VIA
FID C 4 69
FID C 5 69
FID C 6 246
FID C 8 431
FID C 10 970
FID C 11 2341
FID H 12 167
SNT VIA
FID C 4 162
FID C 5 162
FID C 6 527
FID C 8 712
FID C 10 1251
FID C 11 2622
FID H 12 448
SNT VIA
FID C 4 125
FID C 5 125
FID C 6 438
FID C 8 623
FID C 10 1162
FID C 11 2533
FID H 12 359
SNT VIA
FID C 4 146
FID C 5 146
FID C 6 492
FID C 8 677
FID C 10 1216
FID C 11 2587
FID H 12 413
SNT VIA
FID C 4 164
FID C 5 164
FID C 6 529
FID C 8 714
FID C 10 1253
FID C 11 2624
FID H 12 450
SNT VIA
FID C 4 192
FID C 5 192
FID C 6 580
FID C 8 765
FID C 10 1304
FID C 11 2675
FID H 12 501
SNT VIA
FID C 4 173
FID C 5 173
FID C 6 546
FID C 8 731
FID C 10 1270
FID C 11 2641
FID H 12 467
SNT VIA
FID C 4 148
FID C 5 148
FID C 6 501
FID C 8 686
FID C 10 1225
FID C 11 2596
FID H 12 422
SNT VIA
FID C 4 150
FID C 5 150
FID C 6 505
FID C 8 690
FID C 10 1229
FID C 11 2600
FID H 12 426
SNT VIA
FID C 4 157
FID C 5 157
FID C 6 517
FID C 8 702
FID C 10 1241
FID C 11 2612
FID H 12 438
SNT VIA
FID C 4 149
FID C 5 149
FID C 6 502
FID C 8 687
FID C 10 1226
FID C 11 2597
FID H 12 423
SNT VIA
FID C 4 197
FID C 5 197
FID C 6 586
FID C 8 771
FID C 10 1310
FID C 11 2681
FID H 12 507
SNT VIA
FID C 4 191
FID C 5 191
FID C 6 579
FID C 8 764
FID C 10 1303
FID C 11 2674
FID H 12 500
SNT VIA
FID C 4 152
FID C 5 152
FID C 6 512
FID C 8 697
FID C 10 1236
FID C 11 2607
FID H 12 433
SNT VIA
FID C 4 167
FID C 5 167
FID C 6 532
FID C 8 717
FID C 10 1256
FID C 11 2627
FID H 12 453
SNT VIA
FID C 4 66
FID C 5 66
FID C 6 214
FID C 8 399
FID C 10 938
FID C 11 2309
FID H 12 135
SNT VIA
FID C 4 64
FID C 5 64
FID C 6 209
FID C 8 394
FID C 10 933
FID C 11 2304
FID H 12 130
SNT VIA
FID C 4 44
FID C 5 44
FID C 6 167
FID C 8 352
FID C 10 891
FID C 11 2262
FID H 12 88
SNT VIA
FID C 4 85
FID C 5 85
FID C 6 297
FID C 8 482
FID C 10 1021
FID C 11 2392
FID H 12 218
SNT VIA
FID C 4 97
FID C 5 97
FID C 6 334
FID C 8 519
FID C 10 1058
FID C 11 2429
FID H 12 255
SNT VIA
FID C 4 77
FID C 5 77
FID C 6 269
FID C 8 454
FID C 10 993
FID C 11 2364
FID H 12 190
SNT VIA
FID C 4 82
FID C 5 82
FID C 6 285
FID C 8 470
FID C 10 1009
FID C 11 2380
FID H 12 206
SNT VIA
FID C 4 83
FID C 5 83
FID C 6 288
FID C 8 473
FID C 10 1012
FID C 11 2383
FID H 12 209
SNT VIA
FID C 3 654
FID C 4 122
FID C 5 122
FID C 6 423
FID C 8 608
FID C 10 1147
FID C 11 2518
FID H 12 344
SNT VIA
FID C 3 647
FID C 4 120
FID C 5 120
FID C 6 411
FID C 8 596
FID C 10 1135
FID C 11 2506
FID H 12 332
SNT VIA
FID C 4 156
FID C 5 156
FID C 6 516
FID C 8 701
FID C 10 1240
FID C 11 2611
FID H 12 437
SNT VIA
FID C 4 123
FID C 5 123
FID C 6 427
FID C 8 612
FID C 10 1151
FID C 11 2522
FID H 12 348
SNT VIA
FID C 4 73
FID C 5 73
FID C 6 265
FID C 8 450
FID C 10 989
FID C 11 2360
FID H 12 186
SNT VIA
FID C 4 67
FID C 5 67
FID C 6 231
FID C 8 416
FID C 10 955
FID C 11 2326
FID H 12 152
SNT VIA
FID C 4 68
FID C 5 68
FID C 6 236
FID C 8 421
FID C 10 960
FID C 11 2331
FID H 12 157
SNT VIA
FID C 4 76
FID C 5 76
FID C 6 268
FID C 8 453
FID C 10 992
FID C 11 2363
FID H 12 189
SNT VIA
FID C 4 52
FID C 5 52
FID C 6 196
FID C 8 381
FID C 10 920
FID C 11 2291
FID H 12 117
SNT VIA
FID C 4 57
FID C 5 57
FID C 6 201
FID C 8 386
FID C 10 925
FID C 11 2296
FID H 12 122
SNT VIA
FID C 4 59
FID C 5 59
FID C 6 203
FID C 8 388
FID C 10 927
FID C 11 2298
FID H 12 124
SNT VIA
FID C 4 93
FID C 5 93
FID C 6 320
FID C 8 505
FID C 10 1044
FID C 11 2415
FID H 12 241
SNT VIA
FID C 4 51
FID C 5 51
FID C 6 195
FID C 8 380
FID C 10 919
FID C 11 2290
FID H 12 116
SNT VIA
FID C 4 61
FID C 5 61
FID C 6 206
FID C 8 391
FID C 10 930
FID C 11 2301
FID H 12 127
SNT VIA
FID C 4 140
FID C 5 140
FID C 6 476
FID C 8 661
FID C 10 1200
FID C 11 2571
FID H 12 397
SNT VIA
FID C 4 107
FID C 5 107
FID C 6 370
FID C 8 555
FID C 10 1094
FID C 11 2465
FID H 12 291
SNT VIA
FID C 4 133
FID C 5 133
FID C 6 461
FID C 8 646
FID C 10 1185
FID C 11 2556
FID H 12 382
SNT VIA
FID C 4 102
FID C 5 102
FID C 6 349
FID C 8 534
FID C 10 1073
FID C 11 2444
FID H 12 270
SNT VIA
FID C 4 112
FID C 5 112
FID C 6 386
FID C 8 571
FID C 10 1110
FID C 11 2481
FID H 12 307
SNT VIA
FID C 4 117
FID C 5 117
FID C 6 397
FID C 8 582
FID C 10 1121
FID C 11 2492
FID H 12 318
SNT VIA
FID C 4 127
FID C 5 127
FID C 6 442
FID C 8 627
FID C 10 1166
FID C 11 2537
FID H 12 363
SNT VIA
FID C 4 126
FID C 5 126
FID C 6 440
FID C 8 625
FID C 10 1164
FID C 11 2535
FID H 12 361
SNT VIA
FID C 4 136
FID C 5 136
FID C 6 467
FID C 8 652
FID C 10 1191
FID C 11 2562
FID H 12 388
SNT VIA
FID C 4 116
FID C 5 116
FID C 6 393
FID C 8 578
FID C 10 1117
FID C 11 2488
FID H 12 314
SNT VIA
FID C 4 50
FID C 5 50
FID C 6 194
FID C 8 379
FID C 10 918
FID C 11 2289
FID H 12 115
SNT VIA
FID C 4 87
FID C 5 87
FID C 6 301
FID C 8 486
FID C 10 1025
FID C 11 2396
FID H 12 222
SNT VIA
FID C 4 131
FID C 5 131
FID C 6 457
FID C 8 642
FID C 10 1181
FID C 11 2552
FID H 12 378
SNT VIA
FID C 4 63
FID C 5 63
FID C 6 208
FID C 8 393
FID C 10 932
FID C 11 2303
FID H 12 129
SNT VIA
FID C 4 58
FID C 5 58
FID C 6 202
FID C 8 387
FID C 10 926
FID C 11 2297
FID H 12 123
SNT VIA
FID C 4 78
FID C 5 78
FID C 6 277
FID C 8 462
FID C 10 1001
FID C 11 2372
FID H 12 198
SNT VIA
FID C 4 135
FID C 5 135
FID C 6 466
FID C 8 651
FID C 10 1190
FID C 11 2561
FID H 12 387
SNT VIA
FID C 4 101
FID C 5 101
FID C 6 348
FID C 8 533
FID C 10 1072
FID C 11 2443
FID H 12 269
SNT VIA
FID C 4 129
FID C 5 129
FID C 6 444
FID C 8 629
FID C 10 1168
FID C 11 2539
FID H 12 365
SNT VIA
FID C 4 86
FID C 5 86
FID C 6 299
FID C 8 484
FID C 10 1023
FID C 11 2394
FID H 12 220
SNT VIA
FID C 4 99
FID C 5 99
FID C 6 342
FID C 8 527
FID C 10 1066
FID C 11 2437
FID H 12 263
SNT VIA
FID C 4 141
FID C 5 141
FID C 6 478
FID C 8 663
FID C 10 1202
FID C 11 2573
FID H 12 399
SNT VIA
FID C 4 106
FID C 5 106
FID C 6 369
FID C 8 554
FID C 10 1093
FID C 11 2464
FID H 12 290
SNT VIA
FID C 4 55
FID C 5 55
FID C 6 199
FID C 8 384
FID C 10 923
FID C 11 2294
FID H 12 120
SNT VIA
FID C 4 134
FID C 5 134
FID C 6 462
FID C 8 647
FID C 10 1186
FID C 11 2557
FID H 12 383
SNT VIA
FID C 4 75
FID C 5 75
FID C 6 267
FID C 8 452
FID C 10 991
FID C 11 2362
FID H 12 188
SNT VIA
FID C 4 70
FID C 5 70
FID C 6 256
FID C 8 441
FID C 10 980
FID C 11 2351
FID H 12 177
SNT VIA
FID C 4 143
FID C 5 143
FID C 6 481
FID C 8 666
FID C 10 1205
FID C 11 2576
FID H 12 402
SNT VIA
FID C 4 114
FID C 5 114
FID C 6 388
FID C 8 573
FID C 10 1112
FID C 11 2483
FID H 12 309
SNT VIA
FID C 4 60
FID C 5 60
FID C 6 204
FID C 8 389
FID C 10 928
FID C 11 2299
FID H 12 125
SNT VIA
FID C 4 94
FID C 5 94
FID C 6 321
FID C 8 506
FID C 10 1045
FID C 11 2416
FID H 12 242
SNT VIA
FID C 4 81
FID C 5 81
FID C 6 283
FID C 8 468
FID C 10 1007
FID C 11 2378
FID H 12 204
SNT VIA
FID C 4 49
FID C 5 49
FID C 6 193
FID C 8 378
FID C 10 917
FID C 11 2288
FID H 12 114
SNT VIA
FID C 4 128
FID C 5 128
FID C 6 443
FID C 8 628
FID C 10 1167
FID C 11 2538
FID H 12 364
SNT VIA
FID C 4 89
FID C 5 89
FID C 6 307
FID C 8 492
FID C 10 1031
FID C 11 2402
FID H 12 228
SNT VIA
FID C 4 54
FID C 5 54
FID C 6 198
FID C 8 383
FID C 10 922
FID C 11 2293
FID H 12 119
SNT VIA
FID C 4 53
FID C 5 53
FID C 6 197
FID C 8 382
FID C 10 921
FID C 11 2292
FID H 12 118
SNT VIA
FID C 4 62
FID C 5 62
FID C 6 207
FID C 8 392
FID C 10 931
FID C 11 2302
FID H 12 128
SNT VIA
FID C 4 142
FID C 5 142
FID C 6 479
FID C 8 664
FID C 10 1203
FID C 11 2574
FID H 12 400
SNT VIA
FID C 4 132
FID C 5 132
FID C 6 459
FID C 8 644
FID C 10 1183
FID C 11 2554
FID H 12 380
SNT VIA
FID C 4 96
FID C 5 96
FID C 6 328
FID C 8 513
FID C 10 1052
FID C 11 2423
FID H 12 249
SNT VIA
FID C 4 119
FID C 5 119
FID C 6 410
FID C 8 595
FID C 10 1134
FID C 11 2505
FID H 12 331
SNT VIA
FID C 4 92
FID C 5 92
FID C 6 312
FID C 8 497
FID C 10 1036
FID C 11 2407
FID H 12 233
SNT VIA
FID C 4 110
FID C 5 110
FID C 6 382
FID C 8 567
FID C 10 1106
FID C 11 2477
FID H 12 303
SNT VIA
FID C 4 108
FID C 5 108
FID C 6 371
FID C 8 556
FID C 10 1095
FID C 11 2466
FID H 12 292
SNT VIA
FID C 4 103
FID C 5 103
FID C 6 358
FID C 8 543
FID C 10 1082
FID C 11 2453
FID H 12 279
SNT VIA
FID C 4 79
FID C 5 79
FID C 6 278
FID C 8 463
FID C 10 1002
FID C 11 2373
FID H 12 199
SNT VIA
FID C 4 88
FID C 5 88
FID C 6 306
FID C 8 491
FID C 10 1030
FID C 11 2401
FID H 12 227
SNT VIA
FID C 4 74
FID C 5 74
FID C 6 266
FID C 8 451
FID C 10 990
FID C 11 2361
FID H 12 187
SNT VIA
FID C 4 80
FID C 5 80
FID C 6 279
FID C 8 464
FID C 10 1003
FID C 11 2374
FID H 12 200
SNT VIA
FID C 4 109
FID C 5 109
FID C 6 375
FID C 8 560
FID C 10 1099
FID C 11 2470
FID H 12 296
SNT VIA
FID C 4 98
FID C 5 98
FID C 6 336
FID C 8 521
FID C 10 1060
FID C 11 2431
FID H 12 257
SNT VIA
FID C 4 95
FID C 5 95
FID C 6 327
FID C 8 512
FID C 10 1051
FID C 11 2422
FID H 12 248
SNT VIA
FID C 4 84
FID C 5 84
FID C 6 293
FID C 8 478
FID C 10 1017
FID C 11 2388
FID H 12 214
SNT VIA
FID C 4 118
FID C 5 118
FID C 6 401
FID C 8 586
FID C 10 1125
FID C 11 2496
FID H 12 322
SNT VIA
FID C 4 113
FID C 5 113
FID C 6 387
FID C 8 572
FID C 10 1111
FID C 11 2482
FID H 12 308
SNT VIA
FID C 4 35
FID C 5 35
FID C 6 158
FID C 8 343
FID C 10 882
FID C 11 2253
FID H 12 79
SNT VIA
FID C 4 34
FID C 5 34
FID C 6 157
FID C 8 342
FID C 10 881
FID C 11 2252
FID H 12 78
SNT VIA
FID C 4 90
FID C 5 90
FID C 6 310
FID C 8 495
FID C 10 1034
FID C 11 2405
FID H 12 231
SNT VIA
FID C 4 91
FID C 5 91
FID C 6 311
FID C 8 496
FID C 10 1035
FID C 11 2406
FID H 12 232
SNT VIA
FID C 4 151
FID C 5 151
FID C 6 508
FID C 8 693
FID C 10 1232
FID C 11 2603
FID H 12 429
#NET 137
NET FPGA_TMS
SNT TOP T 65 0
FID C 9 426
FID C 10 469
FID C 11 1838
SNT TOP T 97 2
FID C 9 436
FID C 10 479
FID C 11 1848
SNT TOP T 77 243
FID C 9 96
FID C 10 122
FID C 11 1496
SNT TRC
FID C 2 124
SNT TRC
FID C 2 127
SNT TRC
FID C 2 125
SNT TRC
FID C 3 129
SNT TRC
FID C 3 295
SNT TRC
FID C 3 172
SNT TRC
FID C 3 131
SNT TRC
FID C 3 280
SNT TRC
FID C 3 174
SNT TRC
FID C 11 620
SNT TRC
FID C 11 596
SNT TRC
FID C 11 619
SNT TRC
FID C 11 621
SNT TRC
FID C 11 622
SNT TRC
FID C 11 162
SNT TRC
FID C 11 161
SNT VIA
FID C 2 494
FID C 3 568
FID C 6 191
FID C 8 376
FID C 10 915
FID C 11 2286
FID H 12 112
SNT VIA
FID C 3 651
FID C 6 418
FID C 8 603
FID C 10 1142
FID C 11 2513
FID H 12 339
SNT VIA
FID C 2 495
FID C 6 192
FID C 8 377
FID C 10 916
FID C 11 2287
FID H 12 113
#NET 138
NET +3.3V
SNT TOP B 1 0
FID C 1 21
FID C 6 56
FID C 8 245
SNT TOP B 2 0
FID C 1 29
FID C 6 64
FID C 8 253
SNT TOP B 0 3
FID C 1 22
FID C 6 57
FID C 8 246
SNT TOP T 36 1
FID C 9 687
FID C 10 759
FID C 11 2126
SNT TOP T 41 3
FID C 9 222
FID C 10 257
FID C 11 1631
SNT TOP T 52 1
FID C 9 671
FID C 10 733
FID C 11 2100
SNT TOP T 53 1
FID C 9 663
FID C 10 720
FID C 11 2087
SNT TOP T 63 1
FID C 9 173
FID C 10 206
FID C 11 1580
SNT TOP T 84 0
FID C 9 656
FID C 10 713
FID C 11 2080
SNT TOP T 91 1
FID C 9 44
FID C 10 66
FID C 11 1441
SNT TOP T 92 1
FID C 9 28
FID C 10 50
FID C 11 1425
SNT TOP T 93 1
FID C 9 16
FID C 10 38
FID C 11 1413
SNT TOP T 94 1
FID C 9 517
FID C 10 563
FID C 11 1932
SNT TOP T 95 1
FID C 9 518
FID C 10 564
FID C 11 1933
SNT TOP T 97 1
FID C 9 433
FID C 10 476
FID C 11 1845
SNT TOP T 98 1
FID C 9 319
FID C 10 359
FID C 11 1728
SNT TOP T 99 1
FID C 9 359
FID C 10 399
FID C 11 1768
SNT TOP T 100 1
FID C 9 648
FID C 10 705
FID C 11 2072
SNT TOP T 111 0
FID C 9 170
FID C 10 203
FID C 11 1577
SNT TOP T 112 0
FID C 9 181
FID C 10 216
FID C 11 1590
SNT TOP T 113 0
FID C 9 756
FID C 10 831
FID C 11 2198
SNT TOP T 114 0
FID C 9 742
FID C 10 814
FID C 11 2181
SNT TOP T 127 0
FID C 9 704
FID C 10 776
FID C 11 2143
SNT TOP T 128 0
FID C 9 703
FID C 10 775
FID C 11 2142
SNT TOP T 129 0
FID C 9 702
FID C 10 774
FID C 11 2141
SNT TOP T 130 0
FID C 9 705
FID C 10 777
FID C 11 2144
SNT TOP T 131 0
FID C 9 719
FID C 10 791
FID C 11 2158
SNT TOP T 132 0
FID C 9 697
FID C 10 769
FID C 11 2136
SNT TOP T 90 1
FID C 9 52
FID C 10 74
FID C 11 1449
SNT TOP T 78 0
FID C 9 778
FID C 10 853
FID C 11 2220
SNT TOP T 42 2
FID C 9 737
FID C 10 809
FID C 11 2176
SNT TOP T 42 27
FID C 9 744
FID C 10 816
FID C 11 2183
SNT TOP T 44 3
FID C 9 413
FID C 10 456
FID C 11 1825
SNT TOP T 44 5
FID C 9 429
FID C 10 472
FID C 11 1841
SNT TOP T 96 1
FID C 9 455
FID C 10 499
FID C 11 1868
SNT TRC
FID C 3 107
SNT TRC
FID C 3 111
SNT TRC
FID C 3 120
SNT TRC
FID C 3 177
SNT TRC
FID C 3 157
SNT TRC
FID C 3 176
SNT TRC
FID C 3 130
SNT TRC
FID C 3 123
SNT TRC
FID C 3 156
SNT TRC
FID C 8 192
SNT TRC
FID C 8 190
SNT TRC
FID C 8 171
SNT TRC
FID C 8 132
SNT TRC
FID C 8 153
SNT TRC
FID C 8 152
SNT TRC
FID C 8 121
SNT TRC
FID C 8 122
SNT TRC
FID C 8 167
SNT TRC
FID C 8 168
SNT TRC
FID C 8 188
SNT TRC
FID C 8 189
SNT TRC
FID C 8 191
SNT TRC
FID C 8 120
SNT TRC
FID C 8 52
SNT TRC
FID C 11 1253
SNT TRC
FID C 11 1255
SNT TRC
FID C 11 1256
SNT TRC
FID C 11 1278
SNT TRC
FID C 11 1279
SNT TRC
FID C 11 1283
SNT TRC
FID C 11 1260
SNT TRC
FID C 11 1258
SNT TRC
FID C 11 1257
SNT TRC
FID C 11 1254
SNT TRC
FID C 11 1196
SNT TRC
FID C 11 1197
SNT TRC
FID C 11 1198
SNT TRC
FID C 11 578
SNT TRC
FID C 11 512
SNT TRC
FID C 11 497
SNT TRC
FID C 11 467
SNT TRC
FID C 11 453
SNT TRC
FID C 11 452
SNT TRC
FID C 11 599
SNT TRC
FID C 11 598
SNT TRC
FID C 11 603
SNT TRC
FID C 11 602
SNT TRC
FID C 11 64
SNT TRC
FID C 11 81
SNT TRC
FID C 11 114
SNT TRC
FID C 11 270
SNT TRC
FID C 11 1185
SNT TRC
FID C 11 1067
SNT TRC
FID C 11 1065
SNT TRC
FID C 11 1063
SNT TRC
FID C 11 1062
SNT TRC
FID C 11 1099
SNT TRC
FID C 11 1100
SNT TRC
FID C 11 1046
SNT TRC
FID C 11 130
SNT TRC
FID C 11 128
SNT TRC
FID C 11 279
SNT TRC
FID C 11 269
SNT TRC
FID C 11 312
SNT TRC
FID C 11 282
SNT TRC
FID C 11 280
SNT TRC
FID C 11 267
SNT TRC
FID C 11 268
SNT TRC
FID C 11 1070
SNT TRC
FID C 11 1094
SNT TRC
FID C 11 1095
SNT TRC
FID C 11 1096
SNT TRC
FID C 11 1101
SNT TRC
FID C 11 1102
SNT TRC
FID C 11 1271
SNT TRC
FID C 11 1274
SNT TRC
FID C 11 1321
SNT TRC
FID C 11 1335
SNT TRC
FID C 11 1276
SNT TRC
FID C 11 1277
SNT TRC
FID C 11 1291
SNT TRC
FID C 11 1142
SNT TRC
FID C 11 1157
SNT TRC
FID C 11 1162
SNT TRC
FID C 11 1173
SNT TRC
FID C 11 1178
SNT TRC
FID C 11 1172
SNT TRC
FID C 11 1174
SNT TRC
FID C 11 1327
SNT TRC
FID C 11 1224
SNT TRC
FID C 11 1251
SNT TRC
FID C 11 1272
SNT TRC
FID C 11 1098
SNT TRC
FID C 11 276
SNT TRC
FID C 11 1069
SNT TRC
FID C 11 1061
SNT TRC
FID C 11 1031
SNT TRC
FID C 11 813
SNT TRC
FID C 11 966
SNT TRC
FID C 11 941
SNT TRC
FID C 11 1028
SNT TRC
FID C 11 1029
SNT TRC
FID C 11 1030
SNT TRC
FID C 11 753
SNT TRC
FID C 11 614
SNT TRC
FID C 11 752
SNT TRC
FID C 11 751
SNT TRC
FID C 11 754
SNT TRC
FID C 11 782
SNT TRC
FID C 11 769
SNT TRC
FID C 11 755
SNT TRC
FID C 11 781
SNT TRC
FID C 11 706
SNT TRC
FID C 11 705
SNT TRC
FID C 11 717
SNT VIA
FID C 6 549
FID C 8 734
FID C 10 1273
FID C 11 2644
FID H 12 470
SNT VIA
FID C 6 538
FID C 8 723
FID C 10 1262
FID C 11 2633
FID H 12 459
SNT VIA
FID C 3 560
FID C 6 180
FID C 8 365
FID C 10 904
FID C 11 2275
FID H 12 101
SNT VIA
FID C 6 245
FID C 8 430
FID C 10 969
FID C 11 2340
FID H 12 166
SNT VIA
FID C 6 357
FID C 8 542
FID C 10 1081
FID C 11 2452
FID H 12 278
SNT VIA
FID C 6 415
FID C 8 600
FID C 10 1139
FID C 11 2510
FID H 12 336
SNT VIA
FID C 6 455
FID C 8 640
FID C 10 1179
FID C 11 2550
FID H 12 376
SNT VIA
FID C 3 609
FID C 6 314
FID C 8 499
FID C 10 1038
FID C 11 2409
FID H 12 235
SNT VIA
FID C 6 533
FID C 8 718
FID C 10 1257
FID C 11 2628
FID H 12 454
SNT VIA
FID C 6 248
FID C 8 433
FID C 10 972
FID C 11 2343
FID H 12 169
#NET 139
NET UART1_RXD
SNT TOP T 43 0
FID C 9 583
FID C 10 631
FID C 11 1998
SNT TOP T 60 0
FID C 9 571
FID C 10 619
FID C 11 1986
SNT TOP T 77 160
FID C 9 398
FID C 10 438
FID C 11 1807
SNT TRC
FID C 2 375
SNT TRC
FID C 2 381
SNT TRC
FID C 2 380
SNT TRC
FID C 2 382
SNT TRC
FID C 2 378
SNT TRC
FID C 2 379
SNT TRC
FID C 2 383
SNT TRC
FID C 2 377
SNT TRC
FID C 3 383
SNT TRC
FID C 3 384
SNT TRC
FID C 3 385
SNT TRC
FID C 11 856
SNT TRC
FID C 11 831
SNT TRC
FID C 11 828
SNT TRC
FID C 11 823
SNT TRC
FID C 11 827
SNT TRC
FID C 11 567
SNT TRC
FID C 11 568
SNT VIA
FID C 3 676
FID C 6 474
FID C 8 659
FID C 10 1198
FID C 11 2569
FID H 12 395
SNT VIA
FID C 2 584
FID C 3 645
FID C 6 406
FID C 8 591
FID C 10 1130
FID C 11 2501
FID H 12 327
SNT VIA
FID C 2 582
FID C 6 404
FID C 8 589
FID C 10 1128
FID C 11 2499
FID H 12 325
#NET 140
NET UART1_TXD
SNT TOP T 43 3
FID C 9 580
FID C 10 628
FID C 11 1995
SNT TOP T 77 154
FID C 9 381
FID C 10 421
FID C 11 1790
SNT TOP T 59 0
FID C 9 570
FID C 10 618
FID C 11 1985
SNT TRC
FID C 2 368
SNT TRC
FID C 2 363
SNT TRC
FID C 2 357
SNT TRC
FID C 2 369
SNT TRC
FID C 2 370
SNT TRC
FID C 2 371
SNT TRC
FID C 2 376
SNT TRC
FID C 3 381
SNT TRC
FID C 11 855
SNT TRC
FID C 11 830
SNT TRC
FID C 11 826
SNT TRC
FID C 11 822
SNT TRC
FID C 11 825
SNT TRC
FID C 11 549
SNT TRC
FID C 11 559
SNT TRC
FID C 11 550
SNT VIA
FID C 3 675
FID C 6 473
FID C 8 658
FID C 10 1197
FID C 11 2568
FID H 12 394
SNT VIA
FID C 2 583
FID C 3 644
FID C 6 405
FID C 8 590
FID C 10 1129
FID C 11 2500
FID H 12 326
SNT VIA
FID C 2 580
FID C 6 399
FID C 8 584
FID C 10 1123
FID C 11 2494
FID H 12 320
#NET 141
NET FPGA_TDO
SNT TOP T 66 0
FID C 9 410
FID C 10 453
FID C 11 1822
SNT TOP T 98 2
FID C 9 325
FID C 10 365
FID C 11 1734
SNT TOP T 77 242
FID C 9 148
FID C 10 178
FID C 11 1550
SNT TRC
FID C 2 134
SNT TRC
FID C 3 310
SNT TRC
FID C 3 138
SNT TRC
FID C 3 137
SNT TRC
FID C 11 576
SNT TRC
FID C 11 575
SNT TRC
FID C 11 441
SNT TRC
FID C 11 442
SNT TRC
FID C 11 503
SNT TRC
FID C 11 466
SNT TRC
FID C 11 494
SNT TRC
FID C 11 206
SNT TRC
FID C 11 208
SNT TRC
FID C 11 207
SNT VIA
FID C 3 624
FID C 6 346
FID C 8 531
FID C 10 1070
FID C 11 2441
FID H 12 267
SNT VIA
FID C 2 498
FID C 3 569
FID C 6 212
FID C 8 397
FID C 10 936
FID C 11 2307
FID H 12 133
SNT VIA
FID C 2 497
FID C 6 211
FID C 8 396
FID C 10 935
FID C 11 2306
FID H 12 132
#NET 142
NET FPGA_TCK
SNT TOP T 67 0
FID C 9 394
FID C 10 434
FID C 11 1803
SNT TOP T 99 2
FID C 9 365
FID C 10 405
FID C 11 1774
SNT TOP T 77 240
FID C 9 147
FID C 10 177
FID C 11 1549
SNT TRC
FID C 2 139
SNT TRC
FID C 3 150
SNT TRC
FID C 3 171
SNT TRC
FID C 3 236
SNT TRC
FID C 3 186
SNT TRC
FID C 3 182
SNT TRC
FID C 3 175
SNT TRC
FID C 3 242
SNT TRC
FID C 11 521
SNT TRC
FID C 11 523
SNT TRC
FID C 11 506
SNT TRC
FID C 11 519
SNT TRC
FID C 11 520
SNT TRC
FID C 11 245
SNT TRC
FID C 11 219
SNT VIA
FID C 2 505
FID C 3 575
FID C 6 227
FID C 8 412
FID C 10 951
FID C 11 2322
FID H 12 148
SNT VIA
FID C 3 633
FID C 6 374
FID C 8 559
FID C 10 1098
FID C 11 2469
FID H 12 295
SNT VIA
FID C 2 504
FID C 6 226
FID C 8 411
FID C 10 950
FID C 11 2321
FID H 12 147
#NET 143
NET +12V
SNT TOP T 46 1
FID C 9 765
FID C 10 840
FID C 11 2207
SNT TOP T 73 1
FID C 9 695
FID C 10 767
FID C 11 2134
SNT TOP T 74 1
FID C 9 785
FID C 10 862
FID C 11 2229
SNT TOP T 133 0
FID C 9 771
FID C 10 846
FID C 11 2213
SNT TOP T 134 0
FID C 9 707
FID C 10 779
FID C 11 2146
SNT TOP T 137 0
FID C 9 673
FID C 10 740
FID C 11 2107
SNT TOP T 138 0
FID C 9 676
FID C 10 745
FID C 11 2112
SNT TOP T 85 1
FID C 9 681
FID C 10 751
FID C 11 2118
SNT TOP T 45 1
FID C 9 711
FID C 10 783
FID C 11 2150
SNT TRC
FID C 8 195
SNT TRC
FID C 8 193
SNT TRC
FID C 8 196
SNT TRC
FID C 8 197
SNT TRC
FID C 8 198
SNT TRC
FID C 11 1241
SNT TRC
FID C 11 1242
SNT TRC
FID C 11 1124
SNT TRC
FID C 11 1125
SNT TRC
FID C 11 1188
SNT TRC
FID C 11 1183
SNT TRC
FID C 11 1181
SNT TRC
FID C 11 1182
SNT TRC
FID C 11 1168
SNT TRC
FID C 11 1170
SNT TRC
FID C 11 1177
SNT TRC
FID C 11 1180
SNT TRC
FID C 11 1289
SNT TRC
FID C 11 1298
SNT TRC
FID C 11 1358
SNT TRC
FID C 11 1344
SNT TRC
FID C 11 1354
SNT TRC
FID C 11 1349
SNT TRC
FID C 11 1324
SNT TRC
FID C 11 1325
SNT TRC
FID C 11 1341
SNT TRC
FID C 11 1346
SNT TRC
FID C 11 1347
SNT TRC
FID C 11 1320
SNT TRC
FID C 11 1337
SNT TRC
FID C 11 1345
SNT TRC
FID C 11 1120
SNT TRC
FID C 11 1123
SNT TRC
FID C 11 1186
SNT TRC
FID C 11 1355
SNT TRC
FID C 11 1106
SNT TRC
FID C 11 1108
SNT TRC
FID C 11 1107
SNT TRC
FID C 11 1117
SNT TRC
FID C 11 1109
SNT TRC
FID C 11 1118
SNT VIA
FID C 6 564
FID C 8 749
FID C 10 1288
FID C 11 2659
FID H 12 485
SNT VIA
FID C 6 543
FID C 8 728
FID C 10 1267
FID C 11 2638
FID H 12 464
#NET 144
NET KEY2
SNT TOP T 50 0
FID C 9 672
FID C 10 734
FID C 11 2101
SNT TOP T 77 70
FID C 9 470
FID C 10 514
FID C 11 1883
SNT TRC
FID C 2 424
SNT TRC
FID C 2 428
SNT TRC
FID C 2 427
SNT TRC
FID C 2 425
SNT TRC
FID C 2 430
SNT TRC
FID C 2 429
SNT TRC
FID C 2 426
SNT TRC
FID C 3 452
SNT TRC
FID C 3 453
SNT TRC
FID C 11 1097
SNT TRC
FID C 11 758
SNT TRC
FID C 11 731
SNT TRC
FID C 11 738
SNT VIA
FID C 2 610
FID C 3 668
FID C 6 452
FID C 8 637
FID C 10 1176
FID C 11 2547
FID H 12 373
SNT VIA
FID C 3 699
FID C 6 537
FID C 8 722
FID C 10 1261
FID C 11 2632
FID H 12 458
SNT VIA
FID C 2 612
FID C 6 458
FID C 8 643
FID C 10 1182
FID C 11 2553
FID H 12 379
#NET 145
NET KEY1
SNT TOP T 51 0
FID C 9 664
FID C 10 721
FID C 11 2088
SNT TOP T 77 186
FID C 9 120
FID C 10 150
FID C 11 1522
SNT TRC
FID C 2 135
SNT TRC
FID C 2 133
SNT TRC
FID C 3 518
SNT TRC
FID C 3 140
SNT TRC
FID C 3 511
SNT TRC
FID C 3 173
SNT TRC
FID C 3 164
SNT TRC
FID C 3 168
SNT TRC
FID C 3 158
SNT TRC
FID C 11 1066
SNT TRC
FID C 11 1064
SNT TRC
FID C 11 211
SNT TRC
FID C 11 195
SNT TRC
FID C 11 196
SNT VIA
FID C 2 499
FID C 3 570
FID C 6 213
FID C 8 398
FID C 10 937
FID C 11 2308
FID H 12 134
SNT VIA
FID C 3 697
FID C 6 534
FID C 8 719
FID C 10 1258
FID C 11 2629
FID H 12 455
SNT VIA
FID C 2 496
FID C 6 205
FID C 8 390
FID C 10 929
FID C 11 2300
FID H 12 126
#NET 146
NET +5.0V
SNT TOP B 3 0
FID C 1 50
FID C 6 90
FID C 8 274
SNT TOP B 4 0
FID C 1 58
FID C 6 98
FID C 8 282
SNT TOP B 0 2
FID C 1 40
FID C 6 80
FID C 8 264
SNT TOP T 40 24
FID C 6 127
FID C 8 309
FID C 10 651
FID C 11 2018
FID H 12 48
SNT TOP T 30 1
FID C 9 160
FID C 10 190
FID C 11 1563
SNT TOP T 31 1
FID C 9 105
FID C 10 133
FID C 11 1505
SNT TOP T 33 0
FID C 9 164
FID C 10 194
FID C 11 1567
SNT TOP T 41 2
FID C 9 276
FID C 10 316
FID C 11 1685
SNT TOP T 72 0
FID C 9 791
FID C 10 868
FID C 11 2235
SNT TOP T 79 0
FID C 9 700
FID C 10 772
FID C 11 2139
SNT TOP T 107 0
FID C 9 572
FID C 10 620
FID C 11 1987
SNT TOP T 108 0
FID C 9 573
FID C 10 621
FID C 11 1988
SNT TOP T 109 0
FID C 9 331
FID C 10 371
FID C 11 1740
SNT TOP T 110 0
FID C 9 305
FID C 10 345
FID C 11 1714
SNT TOP T 121 0
FID C 9 776
FID C 10 851
FID C 11 2218
SNT TOP T 122 0
FID C 9 775
FID C 10 850
FID C 11 2217
SNT TOP T 123 0
FID C 9 774
FID C 10 849
FID C 11 2216
SNT TOP T 124 0
FID C 9 773
FID C 10 848
FID C 11 2215
SNT TOP T 125 0
FID C 9 780
FID C 10 855
FID C 11 2222
SNT TOP T 126 0
FID C 9 779
FID C 10 854
FID C 11 2221
SNT TOP T 77 11
FID C 9 556
FID C 10 604
FID C 11 1971
SNT TOP T 77 9
FID C 9 557
FID C 10 605
FID C 11 1972
SNT TOP T 77 7
FID C 9 558
FID C 10 606
FID C 11 1973
SNT TOP T 77 5
FID C 9 559
FID C 10 607
FID C 11 1974
SNT TOP T 77 10
FID C 9 500
FID C 10 544
FID C 11 1913
SNT TOP T 77 8
FID C 9 501
FID C 10 545
FID C 11 1914
SNT TOP T 77 6
FID C 9 502
FID C 10 546
FID C 11 1915
SNT TOP T 77 4
FID C 9 503
FID C 10 547
FID C 11 1916
SNT TOP T 34 11
FID C 9 155
FID C 10 185
FID C 11 1558
SNT TRC
FID C 8 194
SNT TRC
FID C 8 187
SNT TRC
FID C 8 128
SNT TRC
FID C 8 185
SNT TRC
FID C 8 181
SNT TRC
FID C 8 172
SNT TRC
FID C 8 173
SNT TRC
FID C 8 180
SNT TRC
FID C 8 169
SNT TRC
FID C 8 170
SNT TRC
FID C 8 174
SNT TRC
FID C 8 176
SNT TRC
FID C 8 179
SNT TRC
FID C 8 178
SNT TRC
FID C 8 175
SNT TRC
FID C 8 111
SNT TRC
FID C 8 91
SNT TRC
FID C 8 107
SNT TRC
FID C 8 110
SNT TRC
FID C 8 177
SNT TRC
FID C 8 126
SNT TRC
FID C 8 183
SNT TRC
FID C 8 127
SNT TRC
FID C 8 166
SNT TRC
FID C 8 165
SNT TRC
FID C 11 1339
SNT TRC
FID C 11 1328
SNT TRC
FID C 11 1329
SNT TRC
FID C 11 1340
SNT TRC
FID C 11 1330
SNT TRC
FID C 11 1331
SNT TRC
FID C 11 1332
SNT TRC
FID C 11 1364
SNT TRC
FID C 11 1333
SNT TRC
FID C 11 1370
SNT TRC
FID C 11 1373
SNT TRC
FID C 11 1369
SNT TRC
FID C 11 1371
SNT TRC
FID C 11 1022
SNT TRC
FID C 11 423
SNT TRC
FID C 11 425
SNT TRC
FID C 11 432
SNT TRC
FID C 11 377
SNT TRC
FID C 11 400
SNT TRC
FID C 11 418
SNT TRC
FID C 11 492
SNT TRC
FID C 11 477
SNT TRC
FID C 11 473
SNT TRC
FID C 11 144
SNT TRC
FID C 11 153
SNT TRC
FID C 11 238
SNT TRC
FID C 11 845
SNT TRC
FID C 11 176
SNT TRC
FID C 11 177
SNT TRC
FID C 11 185
SNT TRC
FID C 11 236
SNT TRC
FID C 11 237
SNT TRC
FID C 11 243
SNT TRC
FID C 11 250
SNT TRC
FID C 11 234
SNT TRC
FID C 11 242
SNT TRC
FID C 11 249
SNT TRC
FID C 11 1326
SNT TRC
FID C 11 1338
SNT TRC
FID C 11 1193
SNT TRC
FID C 11 1194
SNT TRC
FID C 11 1220
SNT TRC
FID C 11 837
SNT TRC
FID C 11 838
SNT TRC
FID C 11 848
SNT TRC
FID C 11 884
SNT TRC
FID C 11 918
SNT TRC
FID C 11 846
SNT TRC
FID C 11 255
SNT TRC
FID C 11 239
SNT TRC
FID C 11 240
SNT TRC
FID C 11 254
SNT TRC
FID C 11 763
SNT TRC
FID C 11 756
SNT TRC
FID C 11 760
SNT TRC
FID C 11 735
SNT TRC
FID C 11 777
SNT TRC
FID C 11 734
SNT TRC
FID C 11 766
SNT TRC
FID C 11 736
SNT TRC
FID C 11 775
SNT TRC
FID C 11 774
SNT TRC
FID C 11 790
SNT TRC
FID C 11 773
SNT TRC
FID C 11 791
SNT TRC
FID C 11 737
SNT TRC
FID C 11 787
SNT TRC
FID C 11 771
SNT TRC
FID C 11 772
SNT TRC
FID C 11 765
SNT VIA
FID C 6 584
FID C 8 769
FID C 10 1308
FID C 11 2679
FID H 12 505
SNT VIA
FID C 6 526
FID C 8 711
FID C 10 1250
FID C 11 2621
FID H 12 447
SNT VIA
FID C 6 367
FID C 8 552
FID C 10 1091
FID C 11 2462
FID H 12 288
SNT VIA
FID C 6 187
FID C 8 372
FID C 10 911
FID C 11 2282
FID H 12 108
SNT VIA
FID C 6 464
FID C 8 649
FID C 10 1188
FID C 11 2559
FID H 12 385
SNT VIA
FID C 6 463
FID C 8 648
FID C 10 1187
FID C 11 2558
FID H 12 384
#NET 147
NET FPGA_TDI
SNT TOP T 77 241
FID C 9 95
FID C 10 121
FID C 11 1495
SNT TOP T 64 0
FID C 9 449
FID C 10 493
FID C 11 1862
SNT TOP T 96 2
FID C 9 460
FID C 10 504
FID C 11 1873
SNT TRC
FID C 2 120
SNT TRC
FID C 2 118
SNT TRC
FID C 2 122
SNT TRC
FID C 2 121
SNT TRC
FID C 2 119
SNT TRC
FID C 2 123
SNT TRC
FID C 3 303
SNT TRC
FID C 3 302
SNT TRC
FID C 3 153
SNT TRC
FID C 3 146
SNT TRC
FID C 3 125
SNT TRC
FID C 11 716
SNT TRC
FID C 11 718
SNT TRC
FID C 11 715
SNT TRC
FID C 11 695
SNT TRC
FID C 11 694
SNT TRC
FID C 11 653
SNT TRC
FID C 11 696
SNT TRC
FID C 11 147
SNT VIA
FID C 2 492
FID C 3 565
FID C 6 186
FID C 8 371
FID C 10 910
FID C 11 2281
FID H 12 107
SNT VIA
FID C 3 664
FID C 6 445
FID C 8 630
FID C 10 1169
FID C 11 2540
FID H 12 366
SNT VIA
FID C 2 493
FID C 6 189
FID C 8 374
FID C 10 913
FID C 11 2284
FID H 12 110
# PKG 0
PKG 39-30-1060 0.1653543 -0.434056 -0.7674208 0.125 0.0492126
CT
OB 0.125 -0.7674208 I
OS -0.434056 -0.7674208
OS -0.434056 0.0174208
OS 0.125 0.0174208
OS 0.125 -0.7674208
OE
CE
PIN 0 T 0 -0.503937 0 U U
CR 0 -0.503937 0.025
PIN 0 T -0.3307087 -0.503937 0 U U
CR -0.3307087 -0.503937 0.025
PIN 1 T 0 -0.2165354 0 U U
CR 0 -0.2165354 0.0492126
PIN 2 T -0.1653543 -0.2165354 0 U U
CR -0.1653543 -0.2165354 0.0492126
PIN 3 T -0.3307087 -0.2165354 0 U U
CR -0.3307087 -0.2165354 0.0492126
PIN 4 T 0 0 0 U U
CR 0 0 0.0492126
PIN 5 T -0.1653543 0 0 U U
CR -0.1653543 0 0.0492126
PIN 6 T -0.3307087 0 0 U U
CR -0.3307087 0 0.0492126
#
# PKG 1
PKG 3PINV-100 0.1 -0.0275 -0.0275 0.2275 0.0275
RC -0.0275 -0.0275 0.255 0.055
PIN 1 T 0 0 0 U U
CT
OB -0.0275 0.0275 I
OS 0.0275 0.0275
OS 0.0275 -0.0275
OS -0.0275 -0.0275
OS -0.0275 0.0275
OE
CE
PIN 2 T 0.1 0 0 U U
CR 0.1 0 0.0275
PIN 3 T 0.2 0 0 U U
CR 0.2 0 0.0275
#
# PKG 2
PKG ALINX_FPGA 0.01968 -1.02183 -0.85118 1.07354 0.84922
RC -1.02183 -0.85118 2.09537 1.7004
PIN 1 T 1.00951 -0.78325 0 U U
CT
OB 0.950455 -0.724195 I
OS 1.068565 -0.724195
OS 1.068565 -0.842305
OS 0.950455 -0.842305
OS 0.950455 -0.724195
OE
CE
PIN 1 T -0.95649 0.78675 0 U U
CT
OB -1.015545 0.845805 I
OS -0.897435 0.845805
OS -0.897435 0.727695
OS -1.015545 0.727695
OS -1.015545 0.845805
OE
CE
PIN 1 T -0.95549 -0.78325 0 U U
CT
OB -1.014545 -0.724195 I
OS -0.896435 -0.724195
OS -0.896435 -0.842305
OS -1.014545 -0.842305
OS -1.014545 -0.724195
OE
CE
PIN 1 T 1.00951 0.78675 0 U U
CT
OB 0.950455 0.845805 I
OS 1.068565 0.845805
OS 1.068565 0.727695
OS 0.950455 0.727695
OS 0.950455 0.845805
OE
CE
PIN 1-1 S 0.88359 0.38781 0 U U
CT
OB 0.85308 0.39273 I
OS 0.9141 0.39273
OS 0.9141 0.38289
OS 0.85308 0.38289
OS 0.85308 0.39273
OE
CE
PIN 1-2 S 1.04303 0.38781 0 U U
CT
OB 1.01252 0.39273 I
OS 1.07354 0.39273
OS 1.07354 0.38289
OS 1.01252 0.38289
OS 1.01252 0.39273
OE
CE
PIN 1-3 S 0.88359 0.36812 0 U U
CT
OB 0.85308 0.37304 I
OS 0.9141 0.37304
OS 0.9141 0.3632
OS 0.85308 0.3632
OS 0.85308 0.37304
OE
CE
PIN 1-4 S 1.04303 0.36812 0 U U
CT
OB 1.01252 0.37304 I
OS 1.07354 0.37304
OS 1.07354 0.3632
OS 1.01252 0.3632
OS 1.01252 0.37304
OE
CE
PIN 1-5 S 0.88359 0.34844 0 U U
CT
OB 0.85308 0.35336 I
OS 0.9141 0.35336
OS 0.9141 0.34352
OS 0.85308 0.34352
OS 0.85308 0.35336
OE
CE
PIN 1-6 S 1.04303 0.34844 0 U U
CT
OB 1.01252 0.35336 I
OS 1.07354 0.35336
OS 1.07354 0.34352
OS 1.01252 0.34352
OS 1.01252 0.35336
OE
CE
PIN 1-7 S 0.88359 0.32875 0 U U
CT
OB 0.85308 0.33367 I
OS 0.9141 0.33367
OS 0.9141 0.32383
OS 0.85308 0.32383
OS 0.85308 0.33367
OE
CE
PIN 1-8 S 1.04303 0.32875 0 U U
CT
OB 1.01252 0.33367 I
OS 1.07354 0.33367
OS 1.07354 0.32383
OS 1.01252 0.32383
OS 1.01252 0.33367
OE
CE
PIN 1-9 S 0.88359 0.30907 0 U U
CT
OB 0.85308 0.31399 I
OS 0.9141 0.31399
OS 0.9141 0.30415
OS 0.85308 0.30415
OS 0.85308 0.31399
OE
CE
PIN 1-10 S 1.04303 0.30907 0 U U
CT
OB 1.01252 0.31399 I
OS 1.07354 0.31399
OS 1.07354 0.30415
OS 1.01252 0.30415
OS 1.01252 0.31399
OE
CE
PIN 1-11 S 0.88359 0.28938 0 U U
CT
OB 0.85308 0.2943 I
OS 0.9141 0.2943
OS 0.9141 0.28446
OS 0.85308 0.28446
OS 0.85308 0.2943
OE
CE
PIN 1-12 S 1.04303 0.28938 0 U U
CT
OB 1.01252 0.2943 I
OS 1.07354 0.2943
OS 1.07354 0.28446
OS 1.01252 0.28446
OS 1.01252 0.2943
OE
CE
PIN 1-13 S 0.88359 0.2697 0 U U
CT
OB 0.85308 0.27462 I
OS 0.9141 0.27462
OS 0.9141 0.26478
OS 0.85308 0.26478
OS 0.85308 0.27462
OE
CE
PIN 1-14 S 1.04303 0.2697 0 U U
CT
OB 1.01252 0.27462 I
OS 1.07354 0.27462
OS 1.07354 0.26478
OS 1.01252 0.26478
OS 1.01252 0.27462
OE
CE
PIN 1-15 S 0.88359 0.25001 0 U U
CT
OB 0.85308 0.25493 I
OS 0.9141 0.25493
OS 0.9141 0.24509
OS 0.85308 0.24509
OS 0.85308 0.25493
OE
CE
PIN 1-16 S 1.04303 0.25001 0 U U
CT
OB 1.01252 0.25493 I
OS 1.07354 0.25493
OS 1.07354 0.24509
OS 1.01252 0.24509
OS 1.01252 0.25493
OE
CE
PIN 1-17 S 0.88359 0.23033 0 U U
CT
OB 0.85308 0.23525 I
OS 0.9141 0.23525
OS 0.9141 0.22541
OS 0.85308 0.22541
OS 0.85308 0.23525
OE
CE
PIN 1-18 S 1.04303 0.23033 0 U U
CT
OB 1.01252 0.23525 I
OS 1.07354 0.23525
OS 1.07354 0.22541
OS 1.01252 0.22541
OS 1.01252 0.23525
OE
CE
PIN 1-19 S 0.88359 0.21064 0 U U
CT
OB 0.85308 0.21556 I
OS 0.9141 0.21556
OS 0.9141 0.20572
OS 0.85308 0.20572
OS 0.85308 0.21556
OE
CE
PIN 1-20 S 1.04303 0.21064 0 U U
CT
OB 1.01252 0.21556 I
OS 1.07354 0.21556
OS 1.07354 0.20572
OS 1.01252 0.20572
OS 1.01252 0.21556
OE
CE
PIN 1-21 S 0.88359 0.19096 0 U U
CT
OB 0.85308 0.19588 I
OS 0.9141 0.19588
OS 0.9141 0.18604
OS 0.85308 0.18604
OS 0.85308 0.19588
OE
CE
PIN 1-22 S 1.04303 0.19096 0 U U
CT
OB 1.01252 0.19588 I
OS 1.07354 0.19588
OS 1.07354 0.18604
OS 1.01252 0.18604
OS 1.01252 0.19588
OE
CE
PIN 1-23 S 0.88359 0.17127 0 U U
CT
OB 0.85308 0.17619 I
OS 0.9141 0.17619
OS 0.9141 0.16635
OS 0.85308 0.16635
OS 0.85308 0.17619
OE
CE
PIN 1-24 S 1.04303 0.17127 0 U U
CT
OB 1.01252 0.17619 I
OS 1.07354 0.17619
OS 1.07354 0.16635
OS 1.01252 0.16635
OS 1.01252 0.17619
OE
CE
PIN 1-25 S 0.88359 0.15159 0 U U
CT
OB 0.85308 0.15651 I
OS 0.9141 0.15651
OS 0.9141 0.14667
OS 0.85308 0.14667
OS 0.85308 0.15651
OE
CE
PIN 1-26 S 1.04303 0.15159 0 U U
CT
OB 1.01252 0.15651 I
OS 1.07354 0.15651
OS 1.07354 0.14667
OS 1.01252 0.14667
OS 1.01252 0.15651
OE
CE
PIN 1-27 S 0.88359 0.1319 0 U U
CT
OB 0.85308 0.13682 I
OS 0.9141 0.13682
OS 0.9141 0.12698
OS 0.85308 0.12698
OS 0.85308 0.13682
OE
CE
PIN 1-28 S 1.04303 0.1319 0 U U
CT
OB 1.01252 0.13682 I
OS 1.07354 0.13682
OS 1.07354 0.12698
OS 1.01252 0.12698
OS 1.01252 0.13682
OE
CE
PIN 1-29 S 0.88359 0.11222 0 U U
CT
OB 0.85308 0.11714 I
OS 0.9141 0.11714
OS 0.9141 0.1073
OS 0.85308 0.1073
OS 0.85308 0.11714
OE
CE
PIN 1-30 S 1.04303 0.11222 0 U U
CT
OB 1.01252 0.11714 I
OS 1.07354 0.11714
OS 1.07354 0.1073
OS 1.01252 0.1073
OS 1.01252 0.11714
OE
CE
PIN 1-31 S 0.88359 0.09253 0 U U
CT
OB 0.85308 0.09745 I
OS 0.9141 0.09745
OS 0.9141 0.08761
OS 0.85308 0.08761
OS 0.85308 0.09745
OE
CE
PIN 1-32 S 1.04303 0.09253 0 U U
CT
OB 1.01252 0.09745 I
OS 1.07354 0.09745
OS 1.07354 0.08761
OS 1.01252 0.08761
OS 1.01252 0.09745
OE
CE
PIN 1-33 S 0.88359 0.07285 0 U U
CT
OB 0.85308 0.07777 I
OS 0.9141 0.07777
OS 0.9141 0.06793
OS 0.85308 0.06793
OS 0.85308 0.07777
OE
CE
PIN 1-34 S 1.04303 0.07285 0 U U
CT
OB 1.01252 0.07777 I
OS 1.07354 0.07777
OS 1.07354 0.06793
OS 1.01252 0.06793
OS 1.01252 0.07777
OE
CE
PIN 1-35 S 0.88359 0.05316 0 U U
CT
OB 0.85308 0.05808 I
OS 0.9141 0.05808
OS 0.9141 0.04824
OS 0.85308 0.04824
OS 0.85308 0.05808
OE
CE
PIN 1-36 S 1.04303 0.05316 0 U U
CT
OB 1.01252 0.05808 I
OS 1.07354 0.05808
OS 1.07354 0.04824
OS 1.01252 0.04824
OS 1.01252 0.05808
OE
CE
PIN 1-37 S 0.88359 0.03348 0 U U
CT
OB 0.85308 0.0384 I
OS 0.9141 0.0384
OS 0.9141 0.02856
OS 0.85308 0.02856
OS 0.85308 0.0384
OE
CE
PIN 1-38 S 1.04303 0.03348 0 U U
CT
OB 1.01252 0.0384 I
OS 1.07354 0.0384
OS 1.07354 0.02856
OS 1.01252 0.02856
OS 1.01252 0.0384
OE
CE
PIN 1-39 S 0.88359 0.01379 0 U U
CT
OB 0.85308 0.01871 I
OS 0.9141 0.01871
OS 0.9141 0.00887
OS 0.85308 0.00887
OS 0.85308 0.01871
OE
CE
PIN 1-40 S 1.04303 0.01379 0 U U
CT
OB 1.01252 0.01871 I
OS 1.07354 0.01871
OS 1.07354 0.00887
OS 1.01252 0.00887
OS 1.01252 0.01871
OE
CE
PIN 1-41 S 0.88359 -0.00589 0 U U
CT
OB 0.85308 -0.00097 I
OS 0.9141 -0.00097
OS 0.9141 -0.01081
OS 0.85308 -0.01081
OS 0.85308 -0.00097
OE
CE
PIN 1-42 S 1.04303 -0.00589 0 U U
CT
OB 1.01252 -0.00097 I
OS 1.07354 -0.00097
OS 1.07354 -0.01081
OS 1.01252 -0.01081
OS 1.01252 -0.00097
OE
CE
PIN 1-43 S 0.88359 -0.02558 0 U U
CT
OB 0.85308 -0.02066 I
OS 0.9141 -0.02066
OS 0.9141 -0.0305
OS 0.85308 -0.0305
OS 0.85308 -0.02066
OE
CE
PIN 1-44 S 1.04303 -0.02558 0 U U
CT
OB 1.01252 -0.02066 I
OS 1.07354 -0.02066
OS 1.07354 -0.0305
OS 1.01252 -0.0305
OS 1.01252 -0.02066
OE
CE
PIN 1-45 S 0.88359 -0.04526 0 U U
CT
OB 0.85308 -0.04034 I
OS 0.9141 -0.04034
OS 0.9141 -0.05018
OS 0.85308 -0.05018
OS 0.85308 -0.04034
OE
CE
PIN 1-46 S 1.04303 -0.04526 0 U U
CT
OB 1.01252 -0.04034 I
OS 1.07354 -0.04034
OS 1.07354 -0.05018
OS 1.01252 -0.05018
OS 1.01252 -0.04034
OE
CE
PIN 1-47 S 0.88359 -0.06495 0 U U
CT
OB 0.85308 -0.06003 I
OS 0.9141 -0.06003
OS 0.9141 -0.06987
OS 0.85308 -0.06987
OS 0.85308 -0.06003
OE
CE
PIN 1-48 S 1.04303 -0.06495 0 U U
CT
OB 1.01252 -0.06003 I
OS 1.07354 -0.06003
OS 1.07354 -0.06987
OS 1.01252 -0.06987
OS 1.01252 -0.06003
OE
CE
PIN 1-49 S 0.88359 -0.08463 0 U U
CT
OB 0.85308 -0.07971 I
OS 0.9141 -0.07971
OS 0.9141 -0.08955
OS 0.85308 -0.08955
OS 0.85308 -0.07971
OE
CE
PIN 1-50 S 1.04303 -0.08463 0 U U
CT
OB 1.01252 -0.07971 I
OS 1.07354 -0.07971
OS 1.07354 -0.08955
OS 1.01252 -0.08955
OS 1.01252 -0.07971
OE
CE
PIN 1-51 S 0.88359 -0.10432 0 U U
CT
OB 0.85308 -0.0994 I
OS 0.9141 -0.0994
OS 0.9141 -0.10924
OS 0.85308 -0.10924
OS 0.85308 -0.0994
OE
CE
PIN 1-52 S 1.04303 -0.10432 0 U U
CT
OB 1.01252 -0.0994 I
OS 1.07354 -0.0994
OS 1.07354 -0.10924
OS 1.01252 -0.10924
OS 1.01252 -0.0994
OE
CE
PIN 1-53 S 0.88359 -0.124 0 U U
CT
OB 0.85308 -0.11908 I
OS 0.9141 -0.11908
OS 0.9141 -0.12892
OS 0.85308 -0.12892
OS 0.85308 -0.11908
OE
CE
PIN 1-54 S 1.04303 -0.124 0 U U
CT
OB 1.01252 -0.11908 I
OS 1.07354 -0.11908
OS 1.07354 -0.12892
OS 1.01252 -0.12892
OS 1.01252 -0.11908
OE
CE
PIN 1-55 S 0.88359 -0.14369 0 U U
CT
OB 0.85308 -0.13877 I
OS 0.9141 -0.13877
OS 0.9141 -0.14861
OS 0.85308 -0.14861
OS 0.85308 -0.13877
OE
CE
PIN 1-56 S 1.04303 -0.14369 0 U U
CT
OB 1.01252 -0.13877 I
OS 1.07354 -0.13877
OS 1.07354 -0.14861
OS 1.01252 -0.14861
OS 1.01252 -0.13877
OE
CE
PIN 1-57 S 0.88359 -0.16337 0 U U
CT
OB 0.85308 -0.15845 I
OS 0.9141 -0.15845
OS 0.9141 -0.16829
OS 0.85308 -0.16829
OS 0.85308 -0.15845
OE
CE
PIN 1-58 S 1.04303 -0.16337 0 U U
CT
OB 1.01252 -0.15845 I
OS 1.07354 -0.15845
OS 1.07354 -0.16829
OS 1.01252 -0.16829
OS 1.01252 -0.15845
OE
CE
PIN 1-59 S 0.88359 -0.18306 0 U U
CT
OB 0.85308 -0.17814 I
OS 0.9141 -0.17814
OS 0.9141 -0.18798
OS 0.85308 -0.18798
OS 0.85308 -0.17814
OE
CE
PIN 1-60 S 1.04303 -0.18306 0 U U
CT
OB 1.01252 -0.17814 I
OS 1.07354 -0.17814
OS 1.07354 -0.18798
OS 1.01252 -0.18798
OS 1.01252 -0.17814
OE
CE
PIN 1-61 S 0.88359 -0.20274 0 U U
CT
OB 0.85308 -0.19782 I
OS 0.9141 -0.19782
OS 0.9141 -0.20766
OS 0.85308 -0.20766
OS 0.85308 -0.19782
OE
CE
PIN 1-62 S 1.04303 -0.20274 0 U U
CT
OB 1.01252 -0.19782 I
OS 1.07354 -0.19782
OS 1.07354 -0.20766
OS 1.01252 -0.20766
OS 1.01252 -0.19782
OE
CE
PIN 1-63 S 0.88359 -0.22243 0 U U
CT
OB 0.85308 -0.21751 I
OS 0.9141 -0.21751
OS 0.9141 -0.22735
OS 0.85308 -0.22735
OS 0.85308 -0.21751
OE
CE
PIN 1-64 S 1.04303 -0.22243 0 U U
CT
OB 1.01252 -0.21751 I
OS 1.07354 -0.21751
OS 1.07354 -0.22735
OS 1.01252 -0.22735
OS 1.01252 -0.21751
OE
CE
PIN 1-65 S 0.88359 -0.24211 0 U U
CT
OB 0.85308 -0.23719 I
OS 0.9141 -0.23719
OS 0.9141 -0.24703
OS 0.85308 -0.24703
OS 0.85308 -0.23719
OE
CE
PIN 1-66 S 1.04303 -0.24211 0 U U
CT
OB 1.01252 -0.23719 I
OS 1.07354 -0.23719
OS 1.07354 -0.24703
OS 1.01252 -0.24703
OS 1.01252 -0.23719
OE
CE
PIN 1-67 S 0.88359 -0.2618 0 U U
CT
OB 0.85308 -0.25688 I
OS 0.9141 -0.25688
OS 0.9141 -0.26672
OS 0.85308 -0.26672
OS 0.85308 -0.25688
OE
CE
PIN 1-68 S 1.04303 -0.2618 0 U U
CT
OB 1.01252 -0.25688 I
OS 1.07354 -0.25688
OS 1.07354 -0.26672
OS 1.01252 -0.26672
OS 1.01252 -0.25688
OE
CE
PIN 1-69 S 0.88359 -0.28148 0 U U
CT
OB 0.85308 -0.27656 I
OS 0.9141 -0.27656
OS 0.9141 -0.2864
OS 0.85308 -0.2864
OS 0.85308 -0.27656
OE
CE
PIN 1-70 S 1.04303 -0.28148 0 U U
CT
OB 1.01252 -0.27656 I
OS 1.07354 -0.27656
OS 1.07354 -0.2864
OS 1.01252 -0.2864
OS 1.01252 -0.27656
OE
CE
PIN 1-71 S 0.88359 -0.30117 0 U U
CT
OB 0.85308 -0.29625 I
OS 0.9141 -0.29625
OS 0.9141 -0.30609
OS 0.85308 -0.30609
OS 0.85308 -0.29625
OE
CE
PIN 1-72 S 1.04303 -0.30117 0 U U
CT
OB 1.01252 -0.29625 I
OS 1.07354 -0.29625
OS 1.07354 -0.30609
OS 1.01252 -0.30609
OS 1.01252 -0.29625
OE
CE
PIN 1-73 S 0.88359 -0.32085 0 U U
CT
OB 0.85308 -0.31593 I
OS 0.9141 -0.31593
OS 0.9141 -0.32577
OS 0.85308 -0.32577
OS 0.85308 -0.31593
OE
CE
PIN 1-74 S 1.04303 -0.32085 0 U U
CT
OB 1.01252 -0.31593 I
OS 1.07354 -0.31593
OS 1.07354 -0.32577
OS 1.01252 -0.32577
OS 1.01252 -0.31593
OE
CE
PIN 1-75 S 0.88359 -0.34054 0 U U
CT
OB 0.85308 -0.33562 I
OS 0.9141 -0.33562
OS 0.9141 -0.34546
OS 0.85308 -0.34546
OS 0.85308 -0.33562
OE
CE
PIN 1-76 S 1.04303 -0.34054 0 U U
CT
OB 1.01252 -0.33562 I
OS 1.07354 -0.33562
OS 1.07354 -0.34546
OS 1.01252 -0.34546
OS 1.01252 -0.33562
OE
CE
PIN 1-77 S 0.88359 -0.36022 0 U U
CT
OB 0.85308 -0.3553 I
OS 0.9141 -0.3553
OS 0.9141 -0.36514
OS 0.85308 -0.36514
OS 0.85308 -0.3553
OE
CE
PIN 1-78 S 1.04303 -0.36022 0 U U
CT
OB 1.01252 -0.3553 I
OS 1.07354 -0.3553
OS 1.07354 -0.36514
OS 1.01252 -0.36514
OS 1.01252 -0.3553
OE
CE
PIN 1-79 S 0.88359 -0.37991 0 U U
CT
OB 0.85308 -0.37499 I
OS 0.9141 -0.37499
OS 0.9141 -0.38483
OS 0.85308 -0.38483
OS 0.85308 -0.37499
OE
CE
PIN 1-80 S 1.04303 -0.37991 0 U U
CT
OB 1.01252 -0.37499 I
OS 1.07354 -0.37499
OS 1.07354 -0.38483
OS 1.01252 -0.38483
OS 1.01252 -0.37499
OE
CE
PIN 2-1 S -0.39546 0.65927 0 U U
CT
OB -0.40038 0.68978 I
OS -0.39054 0.68978
OS -0.39054 0.62876
OS -0.40038 0.62876
OS -0.40038 0.68978
OE
CE
PIN 2-2 S -0.39546 0.81871 0 U U
CT
OB -0.40038 0.84922 I
OS -0.39054 0.84922
OS -0.39054 0.7882
OS -0.40038 0.7882
OS -0.40038 0.84922
OE
CE
PIN 2-3 S -0.37577 0.65927 0 U U
CT
OB -0.38069 0.68978 I
OS -0.37085 0.68978
OS -0.37085 0.62876
OS -0.38069 0.62876
OS -0.38069 0.68978
OE
CE
PIN 2-4 S -0.37577 0.81871 0 U U
CT
OB -0.38069 0.84922 I
OS -0.37085 0.84922
OS -0.37085 0.7882
OS -0.38069 0.7882
OS -0.38069 0.84922
OE
CE
PIN 2-5 S -0.35609 0.65927 0 U U
CT
OB -0.36101 0.68978 I
OS -0.35117 0.68978
OS -0.35117 0.62876
OS -0.36101 0.62876
OS -0.36101 0.68978
OE
CE
PIN 2-6 S -0.35609 0.81871 0 U U
CT
OB -0.36101 0.84922 I
OS -0.35117 0.84922
OS -0.35117 0.7882
OS -0.36101 0.7882
OS -0.36101 0.84922
OE
CE
PIN 2-7 S -0.3364 0.65927 0 U U
CT
OB -0.34132 0.68978 I
OS -0.33148 0.68978
OS -0.33148 0.62876
OS -0.34132 0.62876
OS -0.34132 0.68978
OE
CE
PIN 2-8 S -0.3364 0.81871 0 U U
CT
OB -0.34132 0.84922 I
OS -0.33148 0.84922
OS -0.33148 0.7882
OS -0.34132 0.7882
OS -0.34132 0.84922
OE
CE
PIN 2-9 S -0.31672 0.65927 0 U U
CT
OB -0.32164 0.68978 I
OS -0.3118 0.68978
OS -0.3118 0.62876
OS -0.32164 0.62876
OS -0.32164 0.68978
OE
CE
PIN 2-10 S -0.31672 0.81871 0 U U
CT
OB -0.32164 0.84922 I
OS -0.3118 0.84922
OS -0.3118 0.7882
OS -0.32164 0.7882
OS -0.32164 0.84922
OE
CE
PIN 2-11 S -0.29703 0.65927 0 U U
CT
OB -0.30195 0.68978 I
OS -0.29211 0.68978
OS -0.29211 0.62876
OS -0.30195 0.62876
OS -0.30195 0.68978
OE
CE
PIN 2-12 S -0.29703 0.81871 0 U U
CT
OB -0.30195 0.84922 I
OS -0.29211 0.84922
OS -0.29211 0.7882
OS -0.30195 0.7882
OS -0.30195 0.84922
OE
CE
PIN 2-13 S -0.27735 0.65927 0 U U
CT
OB -0.28227 0.68978 I
OS -0.27243 0.68978
OS -0.27243 0.62876
OS -0.28227 0.62876
OS -0.28227 0.68978
OE
CE
PIN 2-14 S -0.27735 0.81871 0 U U
CT
OB -0.28227 0.84922 I
OS -0.27243 0.84922
OS -0.27243 0.7882
OS -0.28227 0.7882
OS -0.28227 0.84922
OE
CE
PIN 2-15 S -0.25766 0.65927 0 U U
CT
OB -0.26258 0.68978 I
OS -0.25274 0.68978
OS -0.25274 0.62876
OS -0.26258 0.62876
OS -0.26258 0.68978
OE
CE
PIN 2-16 S -0.25766 0.81871 0 U U
CT
OB -0.26258 0.84922 I
OS -0.25274 0.84922
OS -0.25274 0.7882
OS -0.26258 0.7882
OS -0.26258 0.84922
OE
CE
PIN 2-17 S -0.23798 0.65927 0 U U
CT
OB -0.2429 0.68978 I
OS -0.23306 0.68978
OS -0.23306 0.62876
OS -0.2429 0.62876
OS -0.2429 0.68978
OE
CE
PIN 2-18 S -0.23798 0.81871 0 U U
CT
OB -0.2429 0.84922 I
OS -0.23306 0.84922
OS -0.23306 0.7882
OS -0.2429 0.7882
OS -0.2429 0.84922
OE
CE
PIN 2-19 S -0.21829 0.65927 0 U U
CT
OB -0.22321 0.68978 I
OS -0.21337 0.68978
OS -0.21337 0.62876
OS -0.22321 0.62876
OS -0.22321 0.68978
OE
CE
PIN 2-20 S -0.21829 0.81871 0 U U
CT
OB -0.22321 0.84922 I
OS -0.21337 0.84922
OS -0.21337 0.7882
OS -0.22321 0.7882
OS -0.22321 0.84922
OE
CE
PIN 2-21 S -0.19861 0.65927 0 U U
CT
OB -0.20353 0.68978 I
OS -0.19369 0.68978
OS -0.19369 0.62876
OS -0.20353 0.62876
OS -0.20353 0.68978
OE
CE
PIN 2-22 S -0.19861 0.81871 0 U U
CT
OB -0.20353 0.84922 I
OS -0.19369 0.84922
OS -0.19369 0.7882
OS -0.20353 0.7882
OS -0.20353 0.84922
OE
CE
PIN 2-23 S -0.17892 0.65927 0 U U
CT
OB -0.18384 0.68978 I
OS -0.174 0.68978
OS -0.174 0.62876
OS -0.18384 0.62876
OS -0.18384 0.68978
OE
CE
PIN 2-24 S -0.17892 0.81871 0 U U
CT
OB -0.18384 0.84922 I
OS -0.174 0.84922
OS -0.174 0.7882
OS -0.18384 0.7882
OS -0.18384 0.84922
OE
CE
PIN 2-25 S -0.15924 0.65927 0 U U
CT
OB -0.16416 0.68978 I
OS -0.15432 0.68978
OS -0.15432 0.62876
OS -0.16416 0.62876
OS -0.16416 0.68978
OE
CE
PIN 2-26 S -0.15924 0.81871 0 U U
CT
OB -0.16416 0.84922 I
OS -0.15432 0.84922
OS -0.15432 0.7882
OS -0.16416 0.7882
OS -0.16416 0.84922
OE
CE
PIN 2-27 S -0.13955 0.65927 0 U U
CT
OB -0.14447 0.68978 I
OS -0.13463 0.68978
OS -0.13463 0.62876
OS -0.14447 0.62876
OS -0.14447 0.68978
OE
CE
PIN 2-28 S -0.13955 0.81871 0 U U
CT
OB -0.14447 0.84922 I
OS -0.13463 0.84922
OS -0.13463 0.7882
OS -0.14447 0.7882
OS -0.14447 0.84922
OE
CE
PIN 2-29 S -0.11987 0.65927 0 U U
CT
OB -0.12479 0.68978 I
OS -0.11495 0.68978
OS -0.11495 0.62876
OS -0.12479 0.62876
OS -0.12479 0.68978
OE
CE
PIN 2-30 S -0.11987 0.81871 0 U U
CT
OB -0.12479 0.84922 I
OS -0.11495 0.84922
OS -0.11495 0.7882
OS -0.12479 0.7882
OS -0.12479 0.84922
OE
CE
PIN 2-31 S -0.10018 0.65927 0 U U
CT
OB -0.1051 0.68978 I
OS -0.09526 0.68978
OS -0.09526 0.62876
OS -0.1051 0.62876
OS -0.1051 0.68978
OE
CE
PIN 2-32 S -0.10018 0.81871 0 U U
CT
OB -0.1051 0.84922 I
OS -0.09526 0.84922
OS -0.09526 0.7882
OS -0.1051 0.7882
OS -0.1051 0.84922
OE
CE
PIN 2-33 S -0.0805 0.65927 0 U U
CT
OB -0.08542 0.68978 I
OS -0.07558 0.68978
OS -0.07558 0.62876
OS -0.08542 0.62876
OS -0.08542 0.68978
OE
CE
PIN 2-34 S -0.0805 0.81871 0 U U
CT
OB -0.08542 0.84922 I
OS -0.07558 0.84922
OS -0.07558 0.7882
OS -0.08542 0.7882
OS -0.08542 0.84922
OE
CE
PIN 2-35 S -0.06081 0.65927 0 U U
CT
OB -0.06573 0.68978 I
OS -0.05589 0.68978
OS -0.05589 0.62876
OS -0.06573 0.62876
OS -0.06573 0.68978
OE
CE
PIN 2-36 S -0.06081 0.81871 0 U U
CT
OB -0.06573 0.84922 I
OS -0.05589 0.84922
OS -0.05589 0.7882
OS -0.06573 0.7882
OS -0.06573 0.84922
OE
CE
PIN 2-37 S -0.04113 0.65927 0 U U
CT
OB -0.04605 0.68978 I
OS -0.03621 0.68978
OS -0.03621 0.62876
OS -0.04605 0.62876
OS -0.04605 0.68978
OE
CE
PIN 2-38 S -0.04113 0.81871 0 U U
CT
OB -0.04605 0.84922 I
OS -0.03621 0.84922
OS -0.03621 0.7882
OS -0.04605 0.7882
OS -0.04605 0.84922
OE
CE
PIN 2-39 S -0.02144 0.65927 0 U U
CT
OB -0.02636 0.68978 I
OS -0.01652 0.68978
OS -0.01652 0.62876
OS -0.02636 0.62876
OS -0.02636 0.68978
OE
CE
PIN 2-40 S -0.02144 0.81871 0 U U
CT
OB -0.02636 0.84922 I
OS -0.01652 0.84922
OS -0.01652 0.7882
OS -0.02636 0.7882
OS -0.02636 0.84922
OE
CE
PIN 2-41 S -0.00176 0.65927 0 U U
CT
OB -0.00668 0.68978 I
OS 0.00316 0.68978
OS 0.00316 0.62876
OS -0.00668 0.62876
OS -0.00668 0.68978
OE
CE
PIN 2-42 S -0.00176 0.81871 0 U U
CT
OB -0.00668 0.84922 I
OS 0.00316 0.84922
OS 0.00316 0.7882
OS -0.00668 0.7882
OS -0.00668 0.84922
OE
CE
PIN 2-43 S 0.01793 0.65927 0 U U
CT
OB 0.01301 0.68978 I
OS 0.02285 0.68978
OS 0.02285 0.62876
OS 0.01301 0.62876
OS 0.01301 0.68978
OE
CE
PIN 2-44 S 0.01793 0.81871 0 U U
CT
OB 0.01301 0.84922 I
OS 0.02285 0.84922
OS 0.02285 0.7882
OS 0.01301 0.7882
OS 0.01301 0.84922
OE
CE
PIN 2-45 S 0.03761 0.65927 0 U U
CT
OB 0.03269 0.68978 I
OS 0.04253 0.68978
OS 0.04253 0.62876
OS 0.03269 0.62876
OS 0.03269 0.68978
OE
CE
PIN 2-46 S 0.03761 0.81871 0 U U
CT
OB 0.03269 0.84922 I
OS 0.04253 0.84922
OS 0.04253 0.7882
OS 0.03269 0.7882
OS 0.03269 0.84922
OE
CE
PIN 2-47 S 0.0573 0.65927 0 U U
CT
OB 0.05238 0.68978 I
OS 0.06222 0.68978
OS 0.06222 0.62876
OS 0.05238 0.62876
OS 0.05238 0.68978
OE
CE
PIN 2-48 S 0.0573 0.81871 0 U U
CT
OB 0.05238 0.84922 I
OS 0.06222 0.84922
OS 0.06222 0.7882
OS 0.05238 0.7882
OS 0.05238 0.84922
OE
CE
PIN 2-49 S 0.07698 0.65927 0 U U
CT
OB 0.07206 0.68978 I
OS 0.0819 0.68978
OS 0.0819 0.62876
OS 0.07206 0.62876
OS 0.07206 0.68978
OE
CE
PIN 2-50 S 0.07698 0.81871 0 U U
CT
OB 0.07206 0.84922 I
OS 0.0819 0.84922
OS 0.0819 0.7882
OS 0.07206 0.7882
OS 0.07206 0.84922
OE
CE
PIN 2-51 S 0.09667 0.65927 0 U U
CT
OB 0.09175 0.68978 I
OS 0.10159 0.68978
OS 0.10159 0.62876
OS 0.09175 0.62876
OS 0.09175 0.68978
OE
CE
PIN 2-52 S 0.09667 0.81871 0 U U
CT
OB 0.09175 0.84922 I
OS 0.10159 0.84922
OS 0.10159 0.7882
OS 0.09175 0.7882
OS 0.09175 0.84922
OE
CE
PIN 2-53 S 0.11635 0.65927 0 U U
CT
OB 0.11143 0.68978 I
OS 0.12127 0.68978
OS 0.12127 0.62876
OS 0.11143 0.62876
OS 0.11143 0.68978
OE
CE
PIN 2-54 S 0.11635 0.81871 0 U U
CT
OB 0.11143 0.84922 I
OS 0.12127 0.84922
OS 0.12127 0.7882
OS 0.11143 0.7882
OS 0.11143 0.84922
OE
CE
PIN 2-55 S 0.13604 0.65927 0 U U
CT
OB 0.13112 0.68978 I
OS 0.14096 0.68978
OS 0.14096 0.62876
OS 0.13112 0.62876
OS 0.13112 0.68978
OE
CE
PIN 2-56 S 0.13604 0.81871 0 U U
CT
OB 0.13112 0.84922 I
OS 0.14096 0.84922
OS 0.14096 0.7882
OS 0.13112 0.7882
OS 0.13112 0.84922
OE
CE
PIN 2-57 S 0.15572 0.65927 0 U U
CT
OB 0.1508 0.68978 I
OS 0.16064 0.68978
OS 0.16064 0.62876
OS 0.1508 0.62876
OS 0.1508 0.68978
OE
CE
PIN 2-58 S 0.15572 0.81871 0 U U
CT
OB 0.1508 0.84922 I
OS 0.16064 0.84922
OS 0.16064 0.7882
OS 0.1508 0.7882
OS 0.1508 0.84922
OE
CE
PIN 2-59 S 0.17541 0.65927 0 U U
CT
OB 0.17049 0.68978 I
OS 0.18033 0.68978
OS 0.18033 0.62876
OS 0.17049 0.62876
OS 0.17049 0.68978
OE
CE
PIN 2-60 S 0.17541 0.81871 0 U U
CT
OB 0.17049 0.84922 I
OS 0.18033 0.84922
OS 0.18033 0.7882
OS 0.17049 0.7882
OS 0.17049 0.84922
OE
CE
PIN 2-61 S 0.19509 0.65927 0 U U
CT
OB 0.19017 0.68978 I
OS 0.20001 0.68978
OS 0.20001 0.62876
OS 0.19017 0.62876
OS 0.19017 0.68978
OE
CE
PIN 2-62 S 0.19509 0.81871 0 U U
CT
OB 0.19017 0.84922 I
OS 0.20001 0.84922
OS 0.20001 0.7882
OS 0.19017 0.7882
OS 0.19017 0.84922
OE
CE
PIN 2-63 S 0.21478 0.65927 0 U U
CT
OB 0.20986 0.68978 I
OS 0.2197 0.68978
OS 0.2197 0.62876
OS 0.20986 0.62876
OS 0.20986 0.68978
OE
CE
PIN 2-64 S 0.21478 0.81871 0 U U
CT
OB 0.20986 0.84922 I
OS 0.2197 0.84922
OS 0.2197 0.7882
OS 0.20986 0.7882
OS 0.20986 0.84922
OE
CE
PIN 2-65 S 0.23446 0.65927 0 U U
CT
OB 0.22954 0.68978 I
OS 0.23938 0.68978
OS 0.23938 0.62876
OS 0.22954 0.62876
OS 0.22954 0.68978
OE
CE
PIN 2-66 S 0.23446 0.81871 0 U U
CT
OB 0.22954 0.84922 I
OS 0.23938 0.84922
OS 0.23938 0.7882
OS 0.22954 0.7882
OS 0.22954 0.84922
OE
CE
PIN 2-67 S 0.25415 0.65927 0 U U
CT
OB 0.24923 0.68978 I
OS 0.25907 0.68978
OS 0.25907 0.62876
OS 0.24923 0.62876
OS 0.24923 0.68978
OE
CE
PIN 2-68 S 0.25415 0.81871 0 U U
CT
OB 0.24923 0.84922 I
OS 0.25907 0.84922
OS 0.25907 0.7882
OS 0.24923 0.7882
OS 0.24923 0.84922
OE
CE
PIN 2-69 S 0.27383 0.65927 0 U U
CT
OB 0.26891 0.68978 I
OS 0.27875 0.68978
OS 0.27875 0.62876
OS 0.26891 0.62876
OS 0.26891 0.68978
OE
CE
PIN 2-70 S 0.27383 0.81871 0 U U
CT
OB 0.26891 0.84922 I
OS 0.27875 0.84922
OS 0.27875 0.7882
OS 0.26891 0.7882
OS 0.26891 0.84922
OE
CE
PIN 2-71 S 0.29352 0.65927 0 U U
CT
OB 0.2886 0.68978 I
OS 0.29844 0.68978
OS 0.29844 0.62876
OS 0.2886 0.62876
OS 0.2886 0.68978
OE
CE
PIN 2-72 S 0.29352 0.81871 0 U U
CT
OB 0.2886 0.84922 I
OS 0.29844 0.84922
OS 0.29844 0.7882
OS 0.2886 0.7882
OS 0.2886 0.84922
OE
CE
PIN 2-73 S 0.3132 0.65927 0 U U
CT
OB 0.30828 0.68978 I
OS 0.31812 0.68978
OS 0.31812 0.62876
OS 0.30828 0.62876
OS 0.30828 0.68978
OE
CE
PIN 2-74 S 0.3132 0.81871 0 U U
CT
OB 0.30828 0.84922 I
OS 0.31812 0.84922
OS 0.31812 0.7882
OS 0.30828 0.7882
OS 0.30828 0.84922
OE
CE
PIN 2-75 S 0.33289 0.65927 0 U U
CT
OB 0.32797 0.68978 I
OS 0.33781 0.68978
OS 0.33781 0.62876
OS 0.32797 0.62876
OS 0.32797 0.68978
OE
CE
PIN 2-76 S 0.33289 0.81871 0 U U
CT
OB 0.32797 0.84922 I
OS 0.33781 0.84922
OS 0.33781 0.7882
OS 0.32797 0.7882
OS 0.32797 0.84922
OE
CE
PIN 2-77 S 0.35257 0.65927 0 U U
CT
OB 0.34765 0.68978 I
OS 0.35749 0.68978
OS 0.35749 0.62876
OS 0.34765 0.62876
OS 0.34765 0.68978
OE
CE
PIN 2-78 S 0.35257 0.81871 0 U U
CT
OB 0.34765 0.84922 I
OS 0.35749 0.84922
OS 0.35749 0.7882
OS 0.34765 0.7882
OS 0.34765 0.84922
OE
CE
PIN 2-79 S 0.37226 0.65927 0 U U
CT
OB 0.36734 0.68978 I
OS 0.37718 0.68978
OS 0.37718 0.62876
OS 0.36734 0.62876
OS 0.36734 0.68978
OE
CE
PIN 2-80 S 0.37226 0.81871 0 U U
CT
OB 0.36734 0.84922 I
OS 0.37718 0.84922
OS 0.37718 0.7882
OS 0.36734 0.7882
OS 0.36734 0.84922
OE
CE
PIN 3-1 S -0.83188 -0.37987 0 U U
CT
OB -0.86239 -0.37495 I
OS -0.80137 -0.37495
OS -0.80137 -0.38479
OS -0.86239 -0.38479
OS -0.86239 -0.37495
OE
CE
PIN 3-2 S -0.99132 -0.37987 0 U U
CT
OB -1.02183 -0.37495 I
OS -0.96081 -0.37495
OS -0.96081 -0.38479
OS -1.02183 -0.38479
OS -1.02183 -0.37495
OE
CE
PIN 3-3 S -0.83188 -0.36018 0 U U
CT
OB -0.86239 -0.35526 I
OS -0.80137 -0.35526
OS -0.80137 -0.3651
OS -0.86239 -0.3651
OS -0.86239 -0.35526
OE
CE
PIN 3-4 S -0.99132 -0.36018 0 U U
CT
OB -1.02183 -0.35526 I
OS -0.96081 -0.35526
OS -0.96081 -0.3651
OS -1.02183 -0.3651
OS -1.02183 -0.35526
OE
CE
PIN 3-5 S -0.83188 -0.3405 0 U U
CT
OB -0.86239 -0.33558 I
OS -0.80137 -0.33558
OS -0.80137 -0.34542
OS -0.86239 -0.34542
OS -0.86239 -0.33558
OE
CE
PIN 3-6 S -0.99132 -0.3405 0 U U
CT
OB -1.02183 -0.33558 I
OS -0.96081 -0.33558
OS -0.96081 -0.34542
OS -1.02183 -0.34542
OS -1.02183 -0.33558
OE
CE
PIN 3-7 S -0.83188 -0.32081 0 U U
CT
OB -0.86239 -0.31589 I
OS -0.80137 -0.31589
OS -0.80137 -0.32573
OS -0.86239 -0.32573
OS -0.86239 -0.31589
OE
CE
PIN 3-8 S -0.99132 -0.32081 0 U U
CT
OB -1.02183 -0.31589 I
OS -0.96081 -0.31589
OS -0.96081 -0.32573
OS -1.02183 -0.32573
OS -1.02183 -0.31589
OE
CE
PIN 3-9 S -0.83188 -0.30113 0 U U
CT
OB -0.86239 -0.29621 I
OS -0.80137 -0.29621
OS -0.80137 -0.30605
OS -0.86239 -0.30605
OS -0.86239 -0.29621
OE
CE
PIN 3-10 S -0.99132 -0.30113 0 U U
CT
OB -1.02183 -0.29621 I
OS -0.96081 -0.29621
OS -0.96081 -0.30605
OS -1.02183 -0.30605
OS -1.02183 -0.29621
OE
CE
PIN 3-11 S -0.83188 -0.28144 0 U U
CT
OB -0.86239 -0.27652 I
OS -0.80137 -0.27652
OS -0.80137 -0.28636
OS -0.86239 -0.28636
OS -0.86239 -0.27652
OE
CE
PIN 3-12 S -0.99132 -0.28144 0 U U
CT
OB -1.02183 -0.27652 I
OS -0.96081 -0.27652
OS -0.96081 -0.28636
OS -1.02183 -0.28636
OS -1.02183 -0.27652
OE
CE
PIN 3-13 S -0.83188 -0.26176 0 U U
CT
OB -0.86239 -0.25684 I
OS -0.80137 -0.25684
OS -0.80137 -0.26668
OS -0.86239 -0.26668
OS -0.86239 -0.25684
OE
CE
PIN 3-14 S -0.99132 -0.26176 0 U U
CT
OB -1.02183 -0.25684 I
OS -0.96081 -0.25684
OS -0.96081 -0.26668
OS -1.02183 -0.26668
OS -1.02183 -0.25684
OE
CE
PIN 3-15 S -0.83188 -0.24207 0 U U
CT
OB -0.86239 -0.23715 I
OS -0.80137 -0.23715
OS -0.80137 -0.24699
OS -0.86239 -0.24699
OS -0.86239 -0.23715
OE
CE
PIN 3-16 S -0.99132 -0.24207 0 U U
CT
OB -1.02183 -0.23715 I
OS -0.96081 -0.23715
OS -0.96081 -0.24699
OS -1.02183 -0.24699
OS -1.02183 -0.23715
OE
CE
PIN 3-17 S -0.83188 -0.22239 0 U U
CT
OB -0.86239 -0.21747 I
OS -0.80137 -0.21747
OS -0.80137 -0.22731
OS -0.86239 -0.22731
OS -0.86239 -0.21747
OE
CE
PIN 3-18 S -0.99132 -0.22239 0 U U
CT
OB -1.02183 -0.21747 I
OS -0.96081 -0.21747
OS -0.96081 -0.22731
OS -1.02183 -0.22731
OS -1.02183 -0.21747
OE
CE
PIN 3-19 S -0.83188 -0.2027 0 U U
CT
OB -0.86239 -0.19778 I
OS -0.80137 -0.19778
OS -0.80137 -0.20762
OS -0.86239 -0.20762
OS -0.86239 -0.19778
OE
CE
PIN 3-20 S -0.99132 -0.2027 0 U U
CT
OB -1.02183 -0.19778 I
OS -0.96081 -0.19778
OS -0.96081 -0.20762
OS -1.02183 -0.20762
OS -1.02183 -0.19778
OE
CE
PIN 3-21 S -0.83188 -0.18302 0 U U
CT
OB -0.86239 -0.1781 I
OS -0.80137 -0.1781
OS -0.80137 -0.18794
OS -0.86239 -0.18794
OS -0.86239 -0.1781
OE
CE
PIN 3-22 S -0.99132 -0.18302 0 U U
CT
OB -1.02183 -0.1781 I
OS -0.96081 -0.1781
OS -0.96081 -0.18794
OS -1.02183 -0.18794
OS -1.02183 -0.1781
OE
CE
PIN 3-23 S -0.83188 -0.16333 0 U U
CT
OB -0.86239 -0.15841 I
OS -0.80137 -0.15841
OS -0.80137 -0.16825
OS -0.86239 -0.16825
OS -0.86239 -0.15841
OE
CE
PIN 3-24 S -0.99132 -0.16333 0 U U
CT
OB -1.02183 -0.15841 I
OS -0.96081 -0.15841
OS -0.96081 -0.16825
OS -1.02183 -0.16825
OS -1.02183 -0.15841
OE
CE
PIN 3-25 S -0.83188 -0.14365 0 U U
CT
OB -0.86239 -0.13873 I
OS -0.80137 -0.13873
OS -0.80137 -0.14857
OS -0.86239 -0.14857
OS -0.86239 -0.13873
OE
CE
PIN 3-26 S -0.99132 -0.14365 0 U U
CT
OB -1.02183 -0.13873 I
OS -0.96081 -0.13873
OS -0.96081 -0.14857
OS -1.02183 -0.14857
OS -1.02183 -0.13873
OE
CE
PIN 3-27 S -0.83188 -0.12396 0 U U
CT
OB -0.86239 -0.11904 I
OS -0.80137 -0.11904
OS -0.80137 -0.12888
OS -0.86239 -0.12888
OS -0.86239 -0.11904
OE
CE
PIN 3-28 S -0.99132 -0.12396 0 U U
CT
OB -1.02183 -0.11904 I
OS -0.96081 -0.11904
OS -0.96081 -0.12888
OS -1.02183 -0.12888
OS -1.02183 -0.11904
OE
CE
PIN 3-29 S -0.83188 -0.10428 0 U U
CT
OB -0.86239 -0.09936 I
OS -0.80137 -0.09936
OS -0.80137 -0.1092
OS -0.86239 -0.1092
OS -0.86239 -0.09936
OE
CE
PIN 3-30 S -0.99132 -0.10428 0 U U
CT
OB -1.02183 -0.09936 I
OS -0.96081 -0.09936
OS -0.96081 -0.1092
OS -1.02183 -0.1092
OS -1.02183 -0.09936
OE
CE
PIN 3-31 S -0.83188 -0.08459 0 U U
CT
OB -0.86239 -0.07967 I
OS -0.80137 -0.07967
OS -0.80137 -0.08951
OS -0.86239 -0.08951
OS -0.86239 -0.07967
OE
CE
PIN 3-32 S -0.99132 -0.08459 0 U U
CT
OB -1.02183 -0.07967 I
OS -0.96081 -0.07967
OS -0.96081 -0.08951
OS -1.02183 -0.08951
OS -1.02183 -0.07967
OE
CE
PIN 3-33 S -0.83188 -0.06491 0 U U
CT
OB -0.86239 -0.05999 I
OS -0.80137 -0.05999
OS -0.80137 -0.06983
OS -0.86239 -0.06983
OS -0.86239 -0.05999
OE
CE
PIN 3-34 S -0.99132 -0.06491 0 U U
CT
OB -1.02183 -0.05999 I
OS -0.96081 -0.05999
OS -0.96081 -0.06983
OS -1.02183 -0.06983
OS -1.02183 -0.05999
OE
CE
PIN 3-35 S -0.83188 -0.04522 0 U U
CT
OB -0.86239 -0.0403 I
OS -0.80137 -0.0403
OS -0.80137 -0.05014
OS -0.86239 -0.05014
OS -0.86239 -0.0403
OE
CE
PIN 3-36 S -0.99132 -0.04522 0 U U
CT
OB -1.02183 -0.0403 I
OS -0.96081 -0.0403
OS -0.96081 -0.05014
OS -1.02183 -0.05014
OS -1.02183 -0.0403
OE
CE
PIN 3-37 S -0.83188 -0.02554 0 U U
CT
OB -0.86239 -0.02062 I
OS -0.80137 -0.02062
OS -0.80137 -0.03046
OS -0.86239 -0.03046
OS -0.86239 -0.02062
OE
CE
PIN 3-38 S -0.99132 -0.02554 0 U U
CT
OB -1.02183 -0.02062 I
OS -0.96081 -0.02062
OS -0.96081 -0.03046
OS -1.02183 -0.03046
OS -1.02183 -0.02062
OE
CE
PIN 3-39 S -0.83188 -0.00585 0 U U
CT
OB -0.86239 -0.00093 I
OS -0.80137 -0.00093
OS -0.80137 -0.01077
OS -0.86239 -0.01077
OS -0.86239 -0.00093
OE
CE
PIN 3-40 S -0.99132 -0.00585 0 U U
CT
OB -1.02183 -0.00093 I
OS -0.96081 -0.00093
OS -0.96081 -0.01077
OS -1.02183 -0.01077
OS -1.02183 -0.00093
OE
CE
PIN 3-41 S -0.83188 0.01383 0 U U
CT
OB -0.86239 0.01875 I
OS -0.80137 0.01875
OS -0.80137 0.00891
OS -0.86239 0.00891
OS -0.86239 0.01875
OE
CE
PIN 3-42 S -0.99132 0.01383 0 U U
CT
OB -1.02183 0.01875 I
OS -0.96081 0.01875
OS -0.96081 0.00891
OS -1.02183 0.00891
OS -1.02183 0.01875
OE
CE
PIN 3-43 S -0.83188 0.03352 0 U U
CT
OB -0.86239 0.03844 I
OS -0.80137 0.03844
OS -0.80137 0.0286
OS -0.86239 0.0286
OS -0.86239 0.03844
OE
CE
PIN 3-44 S -0.99132 0.03352 0 U U
CT
OB -1.02183 0.03844 I
OS -0.96081 0.03844
OS -0.96081 0.0286
OS -1.02183 0.0286
OS -1.02183 0.03844
OE
CE
PIN 3-45 S -0.83188 0.0532 0 U U
CT
OB -0.86239 0.05812 I
OS -0.80137 0.05812
OS -0.80137 0.04828
OS -0.86239 0.04828
OS -0.86239 0.05812
OE
CE
PIN 3-46 S -0.99132 0.0532 0 U U
CT
OB -1.02183 0.05812 I
OS -0.96081 0.05812
OS -0.96081 0.04828
OS -1.02183 0.04828
OS -1.02183 0.05812
OE
CE
PIN 3-47 S -0.83188 0.07289 0 U U
CT
OB -0.86239 0.07781 I
OS -0.80137 0.07781
OS -0.80137 0.06797
OS -0.86239 0.06797
OS -0.86239 0.07781
OE
CE
PIN 3-48 S -0.99132 0.07289 0 U U
CT
OB -1.02183 0.07781 I
OS -0.96081 0.07781
OS -0.96081 0.06797
OS -1.02183 0.06797
OS -1.02183 0.07781
OE
CE
PIN 3-49 S -0.83188 0.09257 0 U U
CT
OB -0.86239 0.09749 I
OS -0.80137 0.09749
OS -0.80137 0.08765
OS -0.86239 0.08765
OS -0.86239 0.09749
OE
CE
PIN 3-50 S -0.99132 0.09257 0 U U
CT
OB -1.02183 0.09749 I
OS -0.96081 0.09749
OS -0.96081 0.08765
OS -1.02183 0.08765
OS -1.02183 0.09749
OE
CE
PIN 3-51 S -0.83188 0.11226 0 U U
CT
OB -0.86239 0.11718 I
OS -0.80137 0.11718
OS -0.80137 0.10734
OS -0.86239 0.10734
OS -0.86239 0.11718
OE
CE
PIN 3-52 S -0.99132 0.11226 0 U U
CT
OB -1.02183 0.11718 I
OS -0.96081 0.11718
OS -0.96081 0.10734
OS -1.02183 0.10734
OS -1.02183 0.11718
OE
CE
PIN 3-53 S -0.83188 0.13194 0 U U
CT
OB -0.86239 0.13686 I
OS -0.80137 0.13686
OS -0.80137 0.12702
OS -0.86239 0.12702
OS -0.86239 0.13686
OE
CE
PIN 3-54 S -0.99132 0.13194 0 U U
CT
OB -1.02183 0.13686 I
OS -0.96081 0.13686
OS -0.96081 0.12702
OS -1.02183 0.12702
OS -1.02183 0.13686
OE
CE
PIN 3-55 S -0.83188 0.15163 0 U U
CT
OB -0.86239 0.15655 I
OS -0.80137 0.15655
OS -0.80137 0.14671
OS -0.86239 0.14671
OS -0.86239 0.15655
OE
CE
PIN 3-56 S -0.99132 0.15163 0 U U
CT
OB -1.02183 0.15655 I
OS -0.96081 0.15655
OS -0.96081 0.14671
OS -1.02183 0.14671
OS -1.02183 0.15655
OE
CE
PIN 3-57 S -0.83188 0.17131 0 U U
CT
OB -0.86239 0.17623 I
OS -0.80137 0.17623
OS -0.80137 0.16639
OS -0.86239 0.16639
OS -0.86239 0.17623
OE
CE
PIN 3-58 S -0.99132 0.17131 0 U U
CT
OB -1.02183 0.17623 I
OS -0.96081 0.17623
OS -0.96081 0.16639
OS -1.02183 0.16639
OS -1.02183 0.17623
OE
CE
PIN 3-59 S -0.83188 0.191 0 U U
CT
OB -0.86239 0.19592 I
OS -0.80137 0.19592
OS -0.80137 0.18608
OS -0.86239 0.18608
OS -0.86239 0.19592
OE
CE
PIN 3-60 S -0.99132 0.191 0 U U
CT
OB -1.02183 0.19592 I
OS -0.96081 0.19592
OS -0.96081 0.18608
OS -1.02183 0.18608
OS -1.02183 0.19592
OE
CE
PIN 3-61 S -0.83188 0.21068 0 U U
CT
OB -0.86239 0.2156 I
OS -0.80137 0.2156
OS -0.80137 0.20576
OS -0.86239 0.20576
OS -0.86239 0.2156
OE
CE
PIN 3-62 S -0.99132 0.21068 0 U U
CT
OB -1.02183 0.2156 I
OS -0.96081 0.2156
OS -0.96081 0.20576
OS -1.02183 0.20576
OS -1.02183 0.2156
OE
CE
PIN 3-63 S -0.83188 0.23037 0 U U
CT
OB -0.86239 0.23529 I
OS -0.80137 0.23529
OS -0.80137 0.22545
OS -0.86239 0.22545
OS -0.86239 0.23529
OE
CE
PIN 3-64 S -0.99132 0.23037 0 U U
CT
OB -1.02183 0.23529 I
OS -0.96081 0.23529
OS -0.96081 0.22545
OS -1.02183 0.22545
OS -1.02183 0.23529
OE
CE
PIN 3-65 S -0.83188 0.25005 0 U U
CT
OB -0.86239 0.25497 I
OS -0.80137 0.25497
OS -0.80137 0.24513
OS -0.86239 0.24513
OS -0.86239 0.25497
OE
CE
PIN 3-66 S -0.99132 0.25005 0 U U
CT
OB -1.02183 0.25497 I
OS -0.96081 0.25497
OS -0.96081 0.24513
OS -1.02183 0.24513
OS -1.02183 0.25497
OE
CE
PIN 3-67 S -0.83188 0.26974 0 U U
CT
OB -0.86239 0.27466 I
OS -0.80137 0.27466
OS -0.80137 0.26482
OS -0.86239 0.26482
OS -0.86239 0.27466
OE
CE
PIN 3-68 S -0.99132 0.26974 0 U U
CT
OB -1.02183 0.27466 I
OS -0.96081 0.27466
OS -0.96081 0.26482
OS -1.02183 0.26482
OS -1.02183 0.27466
OE
CE
PIN 3-69 S -0.83188 0.28942 0 U U
CT
OB -0.86239 0.29434 I
OS -0.80137 0.29434
OS -0.80137 0.2845
OS -0.86239 0.2845
OS -0.86239 0.29434
OE
CE
PIN 3-70 S -0.99132 0.28942 0 U U
CT
OB -1.02183 0.29434 I
OS -0.96081 0.29434
OS -0.96081 0.2845
OS -1.02183 0.2845
OS -1.02183 0.29434
OE
CE
PIN 3-71 S -0.83188 0.30911 0 U U
CT
OB -0.86239 0.31403 I
OS -0.80137 0.31403
OS -0.80137 0.30419
OS -0.86239 0.30419
OS -0.86239 0.31403
OE
CE
PIN 3-72 S -0.99132 0.30911 0 U U
CT
OB -1.02183 0.31403 I
OS -0.96081 0.31403
OS -0.96081 0.30419
OS -1.02183 0.30419
OS -1.02183 0.31403
OE
CE
PIN 3-73 S -0.83188 0.32879 0 U U
CT
OB -0.86239 0.33371 I
OS -0.80137 0.33371
OS -0.80137 0.32387
OS -0.86239 0.32387
OS -0.86239 0.33371
OE
CE
PIN 3-74 S -0.99132 0.32879 0 U U
CT
OB -1.02183 0.33371 I
OS -0.96081 0.33371
OS -0.96081 0.32387
OS -1.02183 0.32387
OS -1.02183 0.33371
OE
CE
PIN 3-75 S -0.83188 0.34848 0 U U
CT
OB -0.86239 0.3534 I
OS -0.80137 0.3534
OS -0.80137 0.34356
OS -0.86239 0.34356
OS -0.86239 0.3534
OE
CE
PIN 3-76 S -0.99132 0.34848 0 U U
CT
OB -1.02183 0.3534 I
OS -0.96081 0.3534
OS -0.96081 0.34356
OS -1.02183 0.34356
OS -1.02183 0.3534
OE
CE
PIN 3-77 S -0.83188 0.36816 0 U U
CT
OB -0.86239 0.37308 I
OS -0.80137 0.37308
OS -0.80137 0.36324
OS -0.86239 0.36324
OS -0.86239 0.37308
OE
CE
PIN 3-78 S -0.99132 0.36816 0 U U
CT
OB -1.02183 0.37308 I
OS -0.96081 0.37308
OS -0.96081 0.36324
OS -1.02183 0.36324
OS -1.02183 0.37308
OE
CE
PIN 3-79 S -0.83188 0.38785 0 U U
CT
OB -0.86239 0.39277 I
OS -0.80137 0.39277
OS -0.80137 0.38293
OS -0.86239 0.38293
OS -0.86239 0.39277
OE
CE
PIN 3-80 S -0.99132 0.38785 0 U U
CT
OB -1.02183 0.39277 I
OS -0.96081 0.39277
OS -0.96081 0.38293
OS -1.02183 0.38293
OS -1.02183 0.39277
OE
CE
PIN 4-1 S 0.37227 -0.66123 0 U U
CT
OB 0.36735 -0.63072 I
OS 0.37719 -0.63072
OS 0.37719 -0.69174
OS 0.36735 -0.69174
OS 0.36735 -0.63072
OE
CE
PIN 4-2 S 0.37227 -0.82067 0 U U
CT
OB 0.36735 -0.79016 I
OS 0.37719 -0.79016
OS 0.37719 -0.85118
OS 0.36735 -0.85118
OS 0.36735 -0.79016
OE
CE
PIN 4-3 S 0.35258 -0.66123 0 U U
CT
OB 0.34766 -0.63072 I
OS 0.3575 -0.63072
OS 0.3575 -0.69174
OS 0.34766 -0.69174
OS 0.34766 -0.63072
OE
CE
PIN 4-4 S 0.35258 -0.82067 0 U U
CT
OB 0.34766 -0.79016 I
OS 0.3575 -0.79016
OS 0.3575 -0.85118
OS 0.34766 -0.85118
OS 0.34766 -0.79016
OE
CE
PIN 4-5 S 0.3329 -0.66123 0 U U
CT
OB 0.32798 -0.63072 I
OS 0.33782 -0.63072
OS 0.33782 -0.69174
OS 0.32798 -0.69174
OS 0.32798 -0.63072
OE
CE
PIN 4-6 S 0.3329 -0.82067 0 U U
CT
OB 0.32798 -0.79016 I
OS 0.33782 -0.79016
OS 0.33782 -0.85118
OS 0.32798 -0.85118
OS 0.32798 -0.79016
OE
CE
PIN 4-7 S 0.31321 -0.66123 0 U U
CT
OB 0.30829 -0.63072 I
OS 0.31813 -0.63072
OS 0.31813 -0.69174
OS 0.30829 -0.69174
OS 0.30829 -0.63072
OE
CE
PIN 4-8 S 0.31321 -0.82067 0 U U
CT
OB 0.30829 -0.79016 I
OS 0.31813 -0.79016
OS 0.31813 -0.85118
OS 0.30829 -0.85118
OS 0.30829 -0.79016
OE
CE
PIN 4-9 S 0.29353 -0.66123 0 U U
CT
OB 0.28861 -0.63072 I
OS 0.29845 -0.63072
OS 0.29845 -0.69174
OS 0.28861 -0.69174
OS 0.28861 -0.63072
OE
CE
PIN 4-10 S 0.29353 -0.82067 0 U U
CT
OB 0.28861 -0.79016 I
OS 0.29845 -0.79016
OS 0.29845 -0.85118
OS 0.28861 -0.85118
OS 0.28861 -0.79016
OE
CE
PIN 4-11 S 0.27384 -0.66123 0 U U
CT
OB 0.26892 -0.63072 I
OS 0.27876 -0.63072
OS 0.27876 -0.69174
OS 0.26892 -0.69174
OS 0.26892 -0.63072
OE
CE
PIN 4-12 S 0.27384 -0.82067 0 U U
CT
OB 0.26892 -0.79016 I
OS 0.27876 -0.79016
OS 0.27876 -0.85118
OS 0.26892 -0.85118
OS 0.26892 -0.79016
OE
CE
PIN 4-13 S 0.25416 -0.66123 0 U U
CT
OB 0.24924 -0.63072 I
OS 0.25908 -0.63072
OS 0.25908 -0.69174
OS 0.24924 -0.69174
OS 0.24924 -0.63072
OE
CE
PIN 4-14 S 0.25416 -0.82067 0 U U
CT
OB 0.24924 -0.79016 I
OS 0.25908 -0.79016
OS 0.25908 -0.85118
OS 0.24924 -0.85118
OS 0.24924 -0.79016
OE
CE
PIN 4-15 S 0.23447 -0.66123 0 U U
CT
OB 0.22955 -0.63072 I
OS 0.23939 -0.63072
OS 0.23939 -0.69174
OS 0.22955 -0.69174
OS 0.22955 -0.63072
OE
CE
PIN 4-16 S 0.23447 -0.82067 0 U U
CT
OB 0.22955 -0.79016 I
OS 0.23939 -0.79016
OS 0.23939 -0.85118
OS 0.22955 -0.85118
OS 0.22955 -0.79016
OE
CE
PIN 4-17 S 0.21479 -0.66123 0 U U
CT
OB 0.20987 -0.63072 I
OS 0.21971 -0.63072
OS 0.21971 -0.69174
OS 0.20987 -0.69174
OS 0.20987 -0.63072
OE
CE
PIN 4-18 S 0.21479 -0.82067 0 U U
CT
OB 0.20987 -0.79016 I
OS 0.21971 -0.79016
OS 0.21971 -0.85118
OS 0.20987 -0.85118
OS 0.20987 -0.79016
OE
CE
PIN 4-19 S 0.1951 -0.66123 0 U U
CT
OB 0.19018 -0.63072 I
OS 0.20002 -0.63072
OS 0.20002 -0.69174
OS 0.19018 -0.69174
OS 0.19018 -0.63072
OE
CE
PIN 4-20 S 0.1951 -0.82067 0 U U
CT
OB 0.19018 -0.79016 I
OS 0.20002 -0.79016
OS 0.20002 -0.85118
OS 0.19018 -0.85118
OS 0.19018 -0.79016
OE
CE
PIN 4-21 S 0.17542 -0.66123 0 U U
CT
OB 0.1705 -0.63072 I
OS 0.18034 -0.63072
OS 0.18034 -0.69174
OS 0.1705 -0.69174
OS 0.1705 -0.63072
OE
CE
PIN 4-22 S 0.17542 -0.82067 0 U U
CT
OB 0.1705 -0.79016 I
OS 0.18034 -0.79016
OS 0.18034 -0.85118
OS 0.1705 -0.85118
OS 0.1705 -0.79016
OE
CE
PIN 4-23 S 0.15573 -0.66123 0 U U
CT
OB 0.15081 -0.63072 I
OS 0.16065 -0.63072
OS 0.16065 -0.69174
OS 0.15081 -0.69174
OS 0.15081 -0.63072
OE
CE
PIN 4-24 S 0.15573 -0.82067 0 U U
CT
OB 0.15081 -0.79016 I
OS 0.16065 -0.79016
OS 0.16065 -0.85118
OS 0.15081 -0.85118
OS 0.15081 -0.79016
OE
CE
PIN 4-25 S 0.13605 -0.66123 0 U U
CT
OB 0.13113 -0.63072 I
OS 0.14097 -0.63072
OS 0.14097 -0.69174
OS 0.13113 -0.69174
OS 0.13113 -0.63072
OE
CE
PIN 4-26 S 0.13605 -0.82067 0 U U
CT
OB 0.13113 -0.79016 I
OS 0.14097 -0.79016
OS 0.14097 -0.85118
OS 0.13113 -0.85118
OS 0.13113 -0.79016
OE
CE
PIN 4-27 S 0.11636 -0.66123 0 U U
CT
OB 0.11144 -0.63072 I
OS 0.12128 -0.63072
OS 0.12128 -0.69174
OS 0.11144 -0.69174
OS 0.11144 -0.63072
OE
CE
PIN 4-28 S 0.11636 -0.82067 0 U U
CT
OB 0.11144 -0.79016 I
OS 0.12128 -0.79016
OS 0.12128 -0.85118
OS 0.11144 -0.85118
OS 0.11144 -0.79016
OE
CE
PIN 4-29 S 0.09668 -0.66123 0 U U
CT
OB 0.09176 -0.63072 I
OS 0.1016 -0.63072
OS 0.1016 -0.69174
OS 0.09176 -0.69174
OS 0.09176 -0.63072
OE
CE
PIN 4-30 S 0.09668 -0.82067 0 U U
CT
OB 0.09176 -0.79016 I
OS 0.1016 -0.79016
OS 0.1016 -0.85118
OS 0.09176 -0.85118
OS 0.09176 -0.79016
OE
CE
PIN 4-31 S 0.07699 -0.66123 0 U U
CT
OB 0.07207 -0.63072 I
OS 0.08191 -0.63072
OS 0.08191 -0.69174
OS 0.07207 -0.69174
OS 0.07207 -0.63072
OE
CE
PIN 4-32 S 0.07699 -0.82067 0 U U
CT
OB 0.07207 -0.79016 I
OS 0.08191 -0.79016
OS 0.08191 -0.85118
OS 0.07207 -0.85118
OS 0.07207 -0.79016
OE
CE
PIN 4-33 S 0.05731 -0.66123 0 U U
CT
OB 0.05239 -0.63072 I
OS 0.06223 -0.63072
OS 0.06223 -0.69174
OS 0.05239 -0.69174
OS 0.05239 -0.63072
OE
CE
PIN 4-34 S 0.05731 -0.82067 0 U U
CT
OB 0.05239 -0.79016 I
OS 0.06223 -0.79016
OS 0.06223 -0.85118
OS 0.05239 -0.85118
OS 0.05239 -0.79016
OE
CE
PIN 4-35 S 0.03762 -0.66123 0 U U
CT
OB 0.0327 -0.63072 I
OS 0.04254 -0.63072
OS 0.04254 -0.69174
OS 0.0327 -0.69174
OS 0.0327 -0.63072
OE
CE
PIN 4-36 S 0.03762 -0.82067 0 U U
CT
OB 0.0327 -0.79016 I
OS 0.04254 -0.79016
OS 0.04254 -0.85118
OS 0.0327 -0.85118
OS 0.0327 -0.79016
OE
CE
PIN 4-37 S 0.01794 -0.66123 0 U U
CT
OB 0.01302 -0.63072 I
OS 0.02286 -0.63072
OS 0.02286 -0.69174
OS 0.01302 -0.69174
OS 0.01302 -0.63072
OE
CE
PIN 4-38 S 0.01794 -0.82067 0 U U
CT
OB 0.01302 -0.79016 I
OS 0.02286 -0.79016
OS 0.02286 -0.85118
OS 0.01302 -0.85118
OS 0.01302 -0.79016
OE
CE
PIN 4-39 S -0.00175 -0.66123 0 U U
CT
OB -0.00667 -0.63072 I
OS 0.00317 -0.63072
OS 0.00317 -0.69174
OS -0.00667 -0.69174
OS -0.00667 -0.63072
OE
CE
PIN 4-40 S -0.00175 -0.82067 0 U U
CT
OB -0.00667 -0.79016 I
OS 0.00317 -0.79016
OS 0.00317 -0.85118
OS -0.00667 -0.85118
OS -0.00667 -0.79016
OE
CE
PIN 4-41 S -0.02143 -0.66123 0 U U
CT
OB -0.02635 -0.63072 I
OS -0.01651 -0.63072
OS -0.01651 -0.69174
OS -0.02635 -0.69174
OS -0.02635 -0.63072
OE
CE
PIN 4-42 S -0.02143 -0.82067 0 U U
CT
OB -0.02635 -0.79016 I
OS -0.01651 -0.79016
OS -0.01651 -0.85118
OS -0.02635 -0.85118
OS -0.02635 -0.79016
OE
CE
PIN 4-43 S -0.04112 -0.66123 0 U U
CT
OB -0.04604 -0.63072 I
OS -0.0362 -0.63072
OS -0.0362 -0.69174
OS -0.04604 -0.69174
OS -0.04604 -0.63072
OE
CE
PIN 4-44 S -0.04112 -0.82067 0 U U
CT
OB -0.04604 -0.79016 I
OS -0.0362 -0.79016
OS -0.0362 -0.85118
OS -0.04604 -0.85118
OS -0.04604 -0.79016
OE
CE
PIN 4-45 S -0.0608 -0.66123 0 U U
CT
OB -0.06572 -0.63072 I
OS -0.05588 -0.63072
OS -0.05588 -0.69174
OS -0.06572 -0.69174
OS -0.06572 -0.63072
OE
CE
PIN 4-46 S -0.0608 -0.82067 0 U U
CT
OB -0.06572 -0.79016 I
OS -0.05588 -0.79016
OS -0.05588 -0.85118
OS -0.06572 -0.85118
OS -0.06572 -0.79016
OE
CE
PIN 4-47 S -0.08049 -0.66123 0 U U
CT
OB -0.08541 -0.63072 I
OS -0.07557 -0.63072
OS -0.07557 -0.69174
OS -0.08541 -0.69174
OS -0.08541 -0.63072
OE
CE
PIN 4-48 S -0.08049 -0.82067 0 U U
CT
OB -0.08541 -0.79016 I
OS -0.07557 -0.79016
OS -0.07557 -0.85118
OS -0.08541 -0.85118
OS -0.08541 -0.79016
OE
CE
PIN 4-49 S -0.10017 -0.66123 0 U U
CT
OB -0.10509 -0.63072 I
OS -0.09525 -0.63072
OS -0.09525 -0.69174
OS -0.10509 -0.69174
OS -0.10509 -0.63072
OE
CE
PIN 4-50 S -0.10017 -0.82067 0 U U
CT
OB -0.10509 -0.79016 I
OS -0.09525 -0.79016
OS -0.09525 -0.85118
OS -0.10509 -0.85118
OS -0.10509 -0.79016
OE
CE
PIN 4-51 S -0.11986 -0.66123 0 U U
CT
OB -0.12478 -0.63072 I
OS -0.11494 -0.63072
OS -0.11494 -0.69174
OS -0.12478 -0.69174
OS -0.12478 -0.63072
OE
CE
PIN 4-52 S -0.11986 -0.82067 0 U U
CT
OB -0.12478 -0.79016 I
OS -0.11494 -0.79016
OS -0.11494 -0.85118
OS -0.12478 -0.85118
OS -0.12478 -0.79016
OE
CE
PIN 4-53 S -0.13954 -0.66123 0 U U
CT
OB -0.14446 -0.63072 I
OS -0.13462 -0.63072
OS -0.13462 -0.69174
OS -0.14446 -0.69174
OS -0.14446 -0.63072
OE
CE
PIN 4-54 S -0.13954 -0.82067 0 U U
CT
OB -0.14446 -0.79016 I
OS -0.13462 -0.79016
OS -0.13462 -0.85118
OS -0.14446 -0.85118
OS -0.14446 -0.79016
OE
CE
PIN 4-55 S -0.15923 -0.66123 0 U U
CT
OB -0.16415 -0.63072 I
OS -0.15431 -0.63072
OS -0.15431 -0.69174
OS -0.16415 -0.69174
OS -0.16415 -0.63072
OE
CE
PIN 4-56 S -0.15923 -0.82067 0 U U
CT
OB -0.16415 -0.79016 I
OS -0.15431 -0.79016
OS -0.15431 -0.85118
OS -0.16415 -0.85118
OS -0.16415 -0.79016
OE
CE
PIN 4-57 S -0.17891 -0.66123 0 U U
CT
OB -0.18383 -0.63072 I
OS -0.17399 -0.63072
OS -0.17399 -0.69174
OS -0.18383 -0.69174
OS -0.18383 -0.63072
OE
CE
PIN 4-58 S -0.17891 -0.82067 0 U U
CT
OB -0.18383 -0.79016 I
OS -0.17399 -0.79016
OS -0.17399 -0.85118
OS -0.18383 -0.85118
OS -0.18383 -0.79016
OE
CE
PIN 4-59 S -0.1986 -0.66123 0 U U
CT
OB -0.20352 -0.63072 I
OS -0.19368 -0.63072
OS -0.19368 -0.69174
OS -0.20352 -0.69174
OS -0.20352 -0.63072
OE
CE
PIN 4-60 S -0.1986 -0.82067 0 U U
CT
OB -0.20352 -0.79016 I
OS -0.19368 -0.79016
OS -0.19368 -0.85118
OS -0.20352 -0.85118
OS -0.20352 -0.79016
OE
CE
PIN 4-61 S -0.21828 -0.66123 0 U U
CT
OB -0.2232 -0.63072 I
OS -0.21336 -0.63072
OS -0.21336 -0.69174
OS -0.2232 -0.69174
OS -0.2232 -0.63072
OE
CE
PIN 4-62 S -0.21828 -0.82067 0 U U
CT
OB -0.2232 -0.79016 I
OS -0.21336 -0.79016
OS -0.21336 -0.85118
OS -0.2232 -0.85118
OS -0.2232 -0.79016
OE
CE
PIN 4-63 S -0.23797 -0.66123 0 U U
CT
OB -0.24289 -0.63072 I
OS -0.23305 -0.63072
OS -0.23305 -0.69174
OS -0.24289 -0.69174
OS -0.24289 -0.63072
OE
CE
PIN 4-64 S -0.23797 -0.82067 0 U U
CT
OB -0.24289 -0.79016 I
OS -0.23305 -0.79016
OS -0.23305 -0.85118
OS -0.24289 -0.85118
OS -0.24289 -0.79016
OE
CE
PIN 4-65 S -0.25765 -0.66123 0 U U
CT
OB -0.26257 -0.63072 I
OS -0.25273 -0.63072
OS -0.25273 -0.69174
OS -0.26257 -0.69174
OS -0.26257 -0.63072
OE
CE
PIN 4-66 S -0.25765 -0.82067 0 U U
CT
OB -0.26257 -0.79016 I
OS -0.25273 -0.79016
OS -0.25273 -0.85118
OS -0.26257 -0.85118
OS -0.26257 -0.79016
OE
CE
PIN 4-67 S -0.27734 -0.66123 0 U U
CT
OB -0.28226 -0.63072 I
OS -0.27242 -0.63072
OS -0.27242 -0.69174
OS -0.28226 -0.69174
OS -0.28226 -0.63072
OE
CE
PIN 4-68 S -0.27734 -0.82067 0 U U
CT
OB -0.28226 -0.79016 I
OS -0.27242 -0.79016
OS -0.27242 -0.85118
OS -0.28226 -0.85118
OS -0.28226 -0.79016
OE
CE
PIN 4-69 S -0.29702 -0.66123 0 U U
CT
OB -0.30194 -0.63072 I
OS -0.2921 -0.63072
OS -0.2921 -0.69174
OS -0.30194 -0.69174
OS -0.30194 -0.63072
OE
CE
PIN 4-70 S -0.29702 -0.82067 0 U U
CT
OB -0.30194 -0.79016 I
OS -0.2921 -0.79016
OS -0.2921 -0.85118
OS -0.30194 -0.85118
OS -0.30194 -0.79016
OE
CE
PIN 4-71 S -0.31671 -0.66123 0 U U
CT
OB -0.32163 -0.63072 I
OS -0.31179 -0.63072
OS -0.31179 -0.69174
OS -0.32163 -0.69174
OS -0.32163 -0.63072
OE
CE
PIN 4-72 S -0.31671 -0.82067 0 U U
CT
OB -0.32163 -0.79016 I
OS -0.31179 -0.79016
OS -0.31179 -0.85118
OS -0.32163 -0.85118
OS -0.32163 -0.79016
OE
CE
PIN 4-73 S -0.33639 -0.66123 0 U U
CT
OB -0.34131 -0.63072 I
OS -0.33147 -0.63072
OS -0.33147 -0.69174
OS -0.34131 -0.69174
OS -0.34131 -0.63072
OE
CE
PIN 4-74 S -0.33639 -0.82067 0 U U
CT
OB -0.34131 -0.79016 I
OS -0.33147 -0.79016
OS -0.33147 -0.85118
OS -0.34131 -0.85118
OS -0.34131 -0.79016
OE
CE
PIN 4-75 S -0.35608 -0.66123 0 U U
CT
OB -0.361 -0.63072 I
OS -0.35116 -0.63072
OS -0.35116 -0.69174
OS -0.361 -0.69174
OS -0.361 -0.63072
OE
CE
PIN 4-76 S -0.35608 -0.82067 0 U U
CT
OB -0.361 -0.79016 I
OS -0.35116 -0.79016
OS -0.35116 -0.85118
OS -0.361 -0.85118
OS -0.361 -0.79016
OE
CE
PIN 4-77 S -0.37576 -0.66123 0 U U
CT
OB -0.38068 -0.63072 I
OS -0.37084 -0.63072
OS -0.37084 -0.69174
OS -0.38068 -0.69174
OS -0.38068 -0.63072
OE
CE
PIN 4-78 S -0.37576 -0.82067 0 U U
CT
OB -0.38068 -0.79016 I
OS -0.37084 -0.79016
OS -0.37084 -0.85118
OS -0.38068 -0.85118
OS -0.38068 -0.79016
OE
CE
PIN 4-79 S -0.39545 -0.66123 0 U U
CT
OB -0.40037 -0.63072 I
OS -0.39053 -0.63072
OS -0.39053 -0.69174
OS -0.40037 -0.69174
OS -0.40037 -0.63072
OE
CE
PIN 4-80 S -0.39545 -0.82067 0 U U
CT
OB -0.40037 -0.79016 I
OS -0.39053 -0.79016
OS -0.39053 -0.85118
OS -0.40037 -0.85118
OS -0.40037 -0.79016
OE
CE
PIN 81 S 0.41656 -0.74095 0 U U
CT
OB 0.389985 -0.707485 I
OS 0.443135 -0.707485
OS 0.443135 -0.774415
OS 0.389985 -0.774415
OS 0.389985 -0.707485
OE
CE
PIN 81 S -0.9116 -0.42416 0 U U
CT
OB -0.945065 -0.397585 I
OS -0.878135 -0.397585
OS -0.878135 -0.450735
OS -0.945065 -0.450735
OS -0.945065 -0.397585
OE
CE
PIN 81 S -0.43975 0.73899 0 U U
CT
OB -0.466325 0.772455 I
OS -0.413175 0.772455
OS -0.413175 0.705525
OS -0.466325 0.705525
OS -0.466325 0.772455
OE
CE
PIN 81 S 0.96331 0.4321 0 U U
CT
OB 0.929845 0.458675 I
OS 0.996775 0.458675
OS 0.996775 0.405525
OS 0.929845 0.405525
OS 0.929845 0.458675
OE
CE
PIN 82 T 0.38211 -0.74095 0 U U
CR 0.38211 -0.74095 0.01083
PIN 82 T -0.9116 -0.38971 0 U U
CR -0.9116 -0.38971 0.01083
PIN 82 T -0.4053 0.73899 0 U U
CR -0.4053 0.73899 0.01083
PIN 82 T 0.96331 0.39765 0 U U
CR 0.96331 0.39765 0.01083
PIN 83 T 0.3821 0.73899 0 U U
CR 0.3821 0.73899 0.01083
PIN 83 T -0.40529 -0.74095 0 U U
CR -0.40529 -0.74095 0.01083
PIN 83 T -0.9116 0.39769 0 U U
CR -0.9116 0.39769 0.01083
PIN 83 T 0.96331 -0.38975 0 U U
CR 0.96331 -0.38975 0.01083
PIN 84 S 0.41655 0.73899 0 U U
CT
OB 0.389975 0.772455 I
OS 0.443125 0.772455
OS 0.443125 0.705525
OS 0.389975 0.705525
OS 0.389975 0.772455
OE
CE
PIN 84 S -0.43974 -0.74095 0 U U
CT
OB -0.466315 -0.707485 I
OS -0.413165 -0.707485
OS -0.413165 -0.774415
OS -0.466315 -0.774415
OS -0.466315 -0.707485
OE
CE
PIN 84 S -0.9116 0.43214 0 U U
CT
OB -0.945065 0.458715 I
OS -0.878135 0.458715
OS -0.878135 0.405565
OS -0.945065 0.405565
OS -0.945065 0.458715
OE
CE
PIN 84 S 0.96331 -0.4242 0 U U
CT
OB 0.929845 -0.397625 I
OS 0.996775 -0.397625
OS 0.996775 -0.450775
OS 0.929845 -0.450775
OS 0.929845 -0.397625
OE
CE
#
# PKG 3
PKG AMPHENOL-901-143-6RFX 0.1414214 -0.16 -0.16 0.3558016 0.16
CT
OB 0.3558016 -0.1377888 I
OS -0.1377888 -0.1377888
OS -0.1377888 0.1378016
OS 0.3558016 0.1378016
OS 0.3558016 -0.1377888
OE
CE
PIN 1 T 0 0 0 U U
CR 0 0 0.056
PIN 2 T -0.1 -0.1 0 U U
CR -0.1 -0.1 0.06
PIN 3 T -0.1 0.1 0 U U
CR -0.1 0.1 0.06
PIN 4 T 0.1 0.1 0 U U
CR 0.1 0.1 0.06
PIN 5 T 0.1 -0.1 0 U U
CR 0.1 -0.1 0.06
#
# PKG 4
PKG BMP388 0.019685 -0.0354134 -0.0354528 0.0354134 0.0354528
RC -0.0354134 -0.0354528 0.0708268 0.0709056
PIN 1 S 0.0098425 0.0300394 0 U U
CT
OB 0.0049425 0.0246394 I
OS 0.0049425 0.0354394
OS 0.0147425 0.0354394
OS 0.0147425 0.0246394
OS 0.0049425 0.0246394
OE
CE
PIN 2 S -0.0098425 0.0300394 0 U U
CT
OB -0.0147425 0.0246394 I
OS -0.0147425 0.0354394
OS -0.0049425 0.0354394
OS -0.0049425 0.0246394
OS -0.0147425 0.0246394
OE
CE
PIN 3 S -0.03 0.019685 0 U U
CT
OB -0.0354134 0.02460625 I
OS -0.0245866 0.02460625
OS -0.0245866 0.01476375
OS -0.0354134 0.01476375
OS -0.0354134 0.02460625
OE
CE
PIN 4 S -0.03 0 0 U U
CT
OB -0.0354134 0.00492125 I
OS -0.0245866 0.00492125
OS -0.0245866 -0.00492125
OS -0.0354134 -0.00492125
OS -0.0354134 0.00492125
OE
CE
PIN 5 S -0.03 -0.019685 0 U U
CT
OB -0.0354134 -0.01476375 I
OS -0.0245866 -0.01476375
OS -0.0245866 -0.02460625
OS -0.0354134 -0.02460625
OS -0.0354134 -0.01476375
OE
CE
PIN 6 S -0.0098425 -0.0300394 0 U U
CT
OB -0.0147425 -0.0354394 I
OS -0.0147425 -0.0246394
OS -0.0049425 -0.0246394
OS -0.0049425 -0.0354394
OS -0.0147425 -0.0354394
OE
CE
PIN 7 S 0.0098425 -0.0300394 0 U U
CT
OB 0.0049425 -0.0354394 I
OS 0.0049425 -0.0246394
OS 0.0147425 -0.0246394
OS 0.0147425 -0.0354394
OS 0.0049425 -0.0354394
OE
CE
PIN 8 S 0.03 -0.019685 0 U U
CT
OB 0.0245866 -0.01476375 I
OS 0.0354134 -0.01476375
OS 0.0354134 -0.02460625
OS 0.0245866 -0.02460625
OS 0.0245866 -0.01476375
OE
CE
PIN 9 S 0.03 0 0 U U
CT
OB 0.0245866 0.00492125 I
OS 0.0354134 0.00492125
OS 0.0354134 -0.00492125
OS 0.0245866 -0.00492125
OS 0.0245866 0.00492125
OE
CE
PIN 10 S 0.03 0.019685 0 U U
CT
OB 0.0245866 0.02460625 I
OS 0.0354134 0.02460625
OS 0.0354134 0.01476375
OS 0.0245866 0.01476375
OS 0.0245866 0.02460625
OE
CE
#
# PKG 5
PKG CAPC1005X06N 0.0338583 -0.0303149 -0.0125984 0.030315 0.0125984
CT
OB 0.0216536 -0.011811 I
OS -0.0216535 -0.011811
OS -0.0216535 0.011811
OS 0.0216536 0.011811
OS 0.0216536 -0.011811
OE
CE
PIN 1 S -0.0169291 0 0 U U
CT
OB -0.0302291 -0.0125 I
OS -0.0302291 0.0125
OS -0.0036291 0.0125
OS -0.0036291 -0.0125
OS -0.0302291 -0.0125
OE
CE
PIN 2 S 0.0169292 0 0 U U
CT
OB 0.0036292 -0.0125 I
OS 0.0036292 0.0125
OS 0.0302292 0.0125
OS 0.0302292 -0.0125
OS 0.0036292 -0.0125
OE
CE
#
# PKG 6
PKG CAPC1608X10N 0.0629921 -0.0511811 -0.0187008 0.051181 0.0187008
CT
OB 0.0344488 -0.0187008 I
OS -0.0344489 -0.0187008
OS -0.0344489 0.0187008
OS 0.0344488 0.0187008
OS 0.0344488 -0.0187008
OE
CE
PIN 1 S -0.0314961 0 0 U U
CT
OB -0.0510961 -0.0187 I
OS -0.0510961 0.0187
OS -0.0118961 0.0187
OS -0.0118961 -0.0187
OS -0.0510961 -0.0187
OE
CE
PIN 2 S 0.031496 0 0 U U
CT
OB 0.011896 -0.0187 I
OS 0.011896 0.0187
OS 0.051096 0.0187
OS 0.051096 -0.0187
OS 0.011896 -0.0187
OE
CE
#
# PKG 7
PKG CAPC2012X14N 0.0708662 -0.0580709 -0.0285433 0.0580709 0.0285433
CT
OB 0.0433071 -0.0285433 I
OS -0.0433071 -0.0285433
OS -0.0433071 0.0285433
OS 0.0433071 0.0285433
OS 0.0433071 -0.0285433
OE
CE
PIN 1 S -0.0354331 0 0 U U
CT
OB -0.0580331 -0.0285 I
OS -0.0580331 0.0285
OS -0.0128331 0.0285
OS -0.0128331 -0.0285
OS -0.0580331 -0.0285
OE
CE
PIN 2 S 0.0354331 0 0 U U
CT
OB 0.0128331 -0.0285 I
OS 0.0128331 0.0285
OS 0.0580331 0.0285
OS 0.0580331 -0.0285
OS 0.0128331 -0.0285
OE
CE
#
# PKG 8
PKG CUI_PJ-002A 0.2195213 -0.0492126 -0.1760768 0.537928 0.2293307
CT
OB 0.537928 -0.1760768 I
OS -0.029 -0.1760768
OS -0.029 0.194
OS 0.537928 0.194
OS 0.537928 -0.1760768
OE
CE
PIN 1 T 0 0 0 U U
CT
OB -0.0492 -0.0492 I
OS -0.0492 0.0492
OC 0.0492 0.0492 0 0.0492 Y
OS 0.0492 -0.0492
OC -0.0492 -0.0492 0 -0.0492 Y
OE
CE
PIN 2 T 0.2362205 0 0 U U
CT
OB 0.1920205 -0.0442 I
OS 0.1920205 0.0442
OC 0.2804205 0.0442 0.2362205 0.0442 Y
OS 0.2804205 -0.0442
OC 0.1920205 -0.0442 0.2362205 -0.0442 Y
OE
CE
PIN 3 T 0.1181102 0.1850394 0 U U
CT
OB 0.1623102 0.1408394 I
OS 0.0739102 0.1408394
OC 0.0739102 0.2292394 0.0739102 0.1850394 Y
OS 0.1623102 0.2292394
OC 0.1623102 0.1408394 0.1623102 0.1850394 Y
OE
CE
#
# PKG 9
PKG DIOM1608X06N 0.0570866 -0.0482283 -0.0167323 0.0482283 0.0167323
CT
OB 0.0314961 -0.015748 I
OS -0.0314961 -0.015748
OS -0.0314961 0.015748
OS 0.0314961 0.015748
OS 0.0314961 -0.015748
OE
CE
PIN 1 S -0.0285433 0 0 U U
CT
OB -0.0481433 -0.0167 I
OS -0.0481433 0.0167
OS -0.0089433 0.0167
OS -0.0089433 -0.0167
OS -0.0481433 -0.0167
OE
CE
PIN 2 S 0.0285433 0 0 U U
CT
OB 0.0089433 -0.0167 I
OS 0.0089433 0.0167
OS 0.0481433 0.0167
OS 0.0481433 -0.0167
OS 0.0089433 -0.0167
OE
CE
#
# PKG 10
PKG DIOM6959X26N 0.2244094 -0.160433 -0.1239968 0.160433 0.1240032
CT
OB 0.1600096 -0.1239968 I
OS -0.1599904 -0.1239968
OS -0.1599904 0.1240032
OS 0.1600096 0.1240032
OS 0.1600096 -0.1239968
OE
CE
PIN A S 0.1122047 0 0 U U
CT
OB 0.0640047 -0.062 I
OS 0.0640047 0.062
OS 0.1604047 0.062
OS 0.1604047 -0.062
OS 0.0640047 -0.062
OE
CE
PIN K S -0.1122047 0 0 U U
CT
OB -0.1604047 -0.062 I
OS -0.1604047 0.062
OS -0.0640047 0.062
OS -0.0640047 -0.062
OS -0.1604047 -0.062
OE
CE
#
# PKG 11
PKG FP-BU2032SM-BT-GTR-MFG 1.1535434 -0.6437008 -0.3287402 0.6437008 0.3287402
CT
OB 0.6437008 -0.3287402 I
OS -0.6437008 -0.3287402
OS -0.6437008 0.3287402
OS 0.6437008 0.3287402
OS 0.6437008 -0.3287402
OE
CE
PIN 1 S 0.5767717 0 0 U U
CT
OB 0.51377955 0.08267715 I
OS 0.63976385 0.08267715
OS 0.63976385 -0.08267715
OS 0.51377955 -0.08267715
OS 0.51377955 0.08267715
OE
CE
PIN 2 S -0.5767717 0 0 U U
CT
OB -0.63976385 0.08267715 I
OS -0.51377955 0.08267715
OS -0.51377955 -0.08267715
OS -0.63976385 -0.08267715
OS -0.63976385 0.08267715
OE
CE
#
# PKG 12
PKG FUSM1608X60N 0.0543307 -0.0413386 -0.019685 0.0413385 0.019685
CT
OB 0.032 -0.016 I
OS -0.032 -0.016
OS -0.032 0.016
OS 0.032 0.016
OS 0.032 -0.016
OE
CE
PIN 1 S -0.0271654 0 0 U U
CT
OB -0.0412654 -0.0196 I
OS -0.0412654 0.0196
OS -0.0130654 0.0196
OS -0.0130654 -0.0196
OS -0.0412654 -0.0196
OE
CE
PIN 2 S 0.0271653 0 0 U U
CT
OB 0.0130653 -0.0196 I
OS 0.0130653 0.0196
OS 0.0412653 0.0196
OS 0.0412653 -0.0196
OS 0.0130653 -0.0196
OE
CE
#
# PKG 13
PKG IND_PM124SH 0.3818898 -0.2680315 -0.2569685 0.2680315 0.2569685
CT
OB 0.2680315 -0.2569685 I
OS -0.2680315 -0.2569685
OS -0.2680315 0.2569685
OS 0.2680315 0.2569685
OS 0.2680315 -0.2569685
OE
CE
PIN 1 S -0.1909449 0 0 U U
CT
OB -0.2480315 0.1062992 I
OS -0.1338583 0.1062992
OS -0.1338583 -0.1062992
OS -0.2480315 -0.1062992
OS -0.2480315 0.1062992
OE
CE
PIN 2 S 0.1909449 0 0 U U
CT
OB 0.1338583 0.1062992 I
OS 0.2480315 0.1062992
OS 0.2480315 -0.1062992
OS 0.1338583 -0.1062992
OS 0.1338583 0.1062992
OE
CE
#
# PKG 14
PKG INDC1608X09N 0.0523622 -0.0433071 -0.0192913 0.0433071 0.0192913
CT
OB 0.0345045 -0.0184978 I
OS -0.0344955 -0.0184978
OS -0.0344955 0.0185022
OS 0.0345045 0.0185022
OS 0.0345045 -0.0184978
OE
CE
PIN 1 S -0.0261811 0 0 U U
CT
OB -0.0432811 -0.0192 I
OS -0.0432811 0.0192
OS -0.0090811 0.0192
OS -0.0090811 -0.0192
OS -0.0432811 -0.0192
OE
CE
PIN 2 S 0.0261811 0 0 U U
CT
OB 0.0090811 -0.0192 I
OS 0.0090811 0.0192
OS 0.0432811 0.0192
OS 0.0432811 -0.0192
OS 0.0090811 -0.0192
OE
CE
#
# PKG 15
PKG J1-0603 0.0590551 -0.043307 -0.0187008 0.0433071 0.0187008
CT
OB 0.0334646 -0.0187008 I
OS -0.0334646 -0.0187008
OS -0.0334646 0.0187008
OS 0.0334646 0.0187008
OS 0.0334646 -0.0187008
OE
CE
PIN 1 S -0.0295275 0.0000001 0 U U
CT
OB -0.0432275 -0.0176999 I
OS -0.0432275 0.0177001
OS -0.0158275 0.0177001
OS -0.0158275 -0.0176999
OS -0.0432275 -0.0176999
OE
CE
PIN 2 S 0.0295276 0.0000001 0 U U
CT
OB 0.0158276 -0.0176999 I
OS 0.0158276 0.0177001
OS 0.0432276 0.0177001
OS 0.0432276 -0.0176999
OS 0.0158276 -0.0176999
OE
CE
#
# PKG 16
PKG L101011MS02Q 0.1811024 -0.2144992 -0.3764928 0.2144992 0.3765056
CT
OB 0.2144992 -0.3764928 I
OS -0.2144992 -0.3764928
OS -0.2144992 0.3765056
OS 0.2144992 0.3765056
OS 0.2144992 -0.3764928
OE
CE
PIN 1 T -0.1122047 -0.1811024 0 U U
CR -0.1122047 -0.1811024 0.0492126
PIN 2 T -0.1122047 0 0 U U
CR -0.1122047 0 0.0492126
#
# PKG 17
PKG LGA-28 0.0195276 -0.1023622 -0.0748031 0.1023622 0.0748031
RC -0.1023622 -0.0748031 0.2047244 0.1496062
PIN 1 S 0.0885827 0.0615157 0 U U
CT
OB 0.0934827 0.0483157 I
OS 0.0836827 0.0483157
OS 0.0836827 0.0747157
OS 0.0934827 0.0747157
OS 0.0934827 0.0483157
OE
CE
PIN 2 S 0.0910433 0.0295276 0 U U
CT
OB 0.0797244 0.03444885 I
OS 0.1023622 0.03444885
OS 0.1023622 0.02460635
OS 0.0797244 0.02460635
OS 0.0797244 0.03444885
OE
CE
PIN 3 S 0.0910433 0.01 0 U U
CT
OB 0.0797244 0.01492125 I
OS 0.1023622 0.01492125
OS 0.1023622 0.00507875
OS 0.0797244 0.00507875
OS 0.0797244 0.01492125
OE
CE
PIN 4 S 0.0910433 -0.0098425 0 U U
CT
OB 0.0797244 -0.00492125 I
OS 0.1023622 -0.00492125
OS 0.1023622 -0.01476375
OS 0.0797244 -0.01476375
OS 0.0797244 -0.00492125
OE
CE
PIN 5 S 0.0910433 -0.0295276 0 U U
CT
OB 0.0797244 -0.02460635 I
OS 0.1023622 -0.02460635
OS 0.1023622 -0.03444885
OS 0.0797244 -0.03444885
OS 0.0797244 -0.02460635
OE
CE
PIN 6 S 0.0885827 -0.0615157 0 U U
CT
OB 0.0934827 -0.0747157 I
OS 0.0836827 -0.0747157
OS 0.0836827 -0.0483157
OS 0.0934827 -0.0483157
OS 0.0934827 -0.0747157
OE
CE
PIN 7 S 0.0688976 -0.0615157 0 U U
CT
OB 0.0737976 -0.0747157 I
OS 0.0639976 -0.0747157
OS 0.0639976 -0.0483157
OS 0.0737976 -0.0483157
OS 0.0737976 -0.0747157
OE
CE
PIN 8 S 0.0492126 -0.0615157 0 U U
CT
OB 0.0541126 -0.0747157 I
OS 0.0443126 -0.0747157
OS 0.0443126 -0.0483157
OS 0.0541126 -0.0483157
OS 0.0541126 -0.0747157
OE
CE
PIN 9 S 0.0295276 -0.0615157 0 U U
CT
OB 0.0344276 -0.0747157 I
OS 0.0246276 -0.0747157
OS 0.0246276 -0.0483157
OS 0.0344276 -0.0483157
OS 0.0344276 -0.0747157
OE
CE
PIN 10 S 0.0098425 -0.0615157 0 U U
CT
OB 0.0147425 -0.0747157 I
OS 0.0049425 -0.0747157
OS 0.0049425 -0.0483157
OS 0.0147425 -0.0483157
OS 0.0147425 -0.0747157
OE
CE
PIN 11 S -0.0098425 -0.0615157 0 U U
CT
OB -0.0049425 -0.0747157 I
OS -0.0147425 -0.0747157
OS -0.0147425 -0.0483157
OS -0.0049425 -0.0483157
OS -0.0049425 -0.0747157
OE
CE
PIN 12 S -0.0295276 -0.0615157 0 U U
CT
OB -0.0246276 -0.0747157 I
OS -0.0344276 -0.0747157
OS -0.0344276 -0.0483157
OS -0.0246276 -0.0483157
OS -0.0246276 -0.0747157
OE
CE
PIN 13 S -0.0492126 -0.0615157 0 U U
CT
OB -0.0443126 -0.0747157 I
OS -0.0541126 -0.0747157
OS -0.0541126 -0.0483157
OS -0.0443126 -0.0483157
OS -0.0443126 -0.0747157
OE
CE
PIN 14 S -0.0688976 -0.0615157 0 U U
CT
OB -0.0639976 -0.0747157 I
OS -0.0737976 -0.0747157
OS -0.0737976 -0.0483157
OS -0.0639976 -0.0483157
OS -0.0639976 -0.0747157
OE
CE
PIN 15 S -0.0885827 -0.0615157 0 U U
CT
OB -0.0836827 -0.0747157 I
OS -0.0934827 -0.0747157
OS -0.0934827 -0.0483157
OS -0.0836827 -0.0483157
OS -0.0836827 -0.0747157
OE
CE
PIN 16 S -0.0910433 -0.0295276 0 U U
CT
OB -0.0797433 -0.0344276 I
OS -0.1023433 -0.0344276
OS -0.1023433 -0.0246276
OS -0.0797433 -0.0246276
OS -0.0797433 -0.0344276
OE
CE
PIN 17 S -0.0910433 -0.0098425 0 U U
CT
OB -0.0797433 -0.0147425 I
OS -0.1023433 -0.0147425
OS -0.1023433 -0.0049425
OS -0.0797433 -0.0049425
OS -0.0797433 -0.0147425
OE
CE
PIN 18 S -0.0910433 0.0098425 0 U U
CT
OB -0.0797433 0.0049425 I
OS -0.1023433 0.0049425
OS -0.1023433 0.0147425
OS -0.0797433 0.0147425
OS -0.0797433 0.0049425
OE
CE
PIN 19 S -0.0910433 0.0295276 0 U U
CT
OB -0.0797433 0.0246276 I
OS -0.1023433 0.0246276
OS -0.1023433 0.0344276
OS -0.0797433 0.0344276
OS -0.0797433 0.0246276
OE
CE
PIN 20 S -0.0885827 0.0615157 0 U U
CT
OB -0.0836827 0.0483157 I
OS -0.0934827 0.0483157
OS -0.0934827 0.0747157
OS -0.0836827 0.0747157
OS -0.0836827 0.0483157
OE
CE
PIN 21 S -0.0688976 0.0615157 0 U U
CT
OB -0.0639976 0.0483157 I
OS -0.0737976 0.0483157
OS -0.0737976 0.0747157
OS -0.0639976 0.0747157
OS -0.0639976 0.0483157
OE
CE
PIN 22 S -0.0492126 0.0615157 0 U U
CT
OB -0.0443126 0.0483157 I
OS -0.0541126 0.0483157
OS -0.0541126 0.0747157
OS -0.0443126 0.0747157
OS -0.0443126 0.0483157
OE
CE
PIN 23 S -0.0295276 0.0615157 0 U U
CT
OB -0.0246276 0.0483157 I
OS -0.0344276 0.0483157
OS -0.0344276 0.0747157
OS -0.0246276 0.0747157
OS -0.0246276 0.0483157
OE
CE
PIN 24 S -0.0098425 0.0615157 0 U U
CT
OB -0.0049425 0.0483157 I
OS -0.0147425 0.0483157
OS -0.0147425 0.0747157
OS -0.0049425 0.0747157
OS -0.0049425 0.0483157
OE
CE
PIN 25 S 0.0098425 0.0615157 0 U U
CT
OB 0.0147425 0.0483157 I
OS 0.0049425 0.0483157
OS 0.0049425 0.0747157
OS 0.0147425 0.0747157
OS 0.0147425 0.0483157
OE
CE
PIN 26 S 0.0295276 0.0615157 0 U U
CT
OB 0.0344276 0.0483157 I
OS 0.0246276 0.0483157
OS 0.0246276 0.0747157
OS 0.0344276 0.0747157
OS 0.0344276 0.0483157
OE
CE
PIN 27 S 0.0492126 0.0615157 0 U U
CT
OB 0.0541126 0.0483157 I
OS 0.0443126 0.0483157
OS 0.0443126 0.0747157
OS 0.0541126 0.0747157
OS 0.0541126 0.0483157
OE
CE
PIN 28 S 0.0688976 0.0615157 0 U U
CT
OB 0.0737976 0.0483157 I
OS 0.0639976 0.0483157
OS 0.0639976 0.0747157
OS 0.0737976 0.0747157
OS 0.0737976 0.0483157
OE
CE
#
# PKG 18
PKG MAC-SA5X 0.02 0.0569882 0.0970486 1.8367126 1.8367126
CT
OB 1.173232 0.106304 I
OS 0.8267744 0.106304
OS 0.8267744 0.3188992
OS 1.173232 0.3188992
OS 1.173232 0.106304
OE
CE
PIN 1 S 1.090208 0.2899619 0 U U
CT
OB 1.095108 0.2545619 I
OS 1.085308 0.2545619
OS 1.085308 0.3253619
OS 1.095108 0.3253619
OS 1.095108 0.2545619
OE
CE
PIN 2 S 1.090208 0.1324816 0 U U
CT
OB 1.095108 0.0970816 I
OS 1.085308 0.0970816
OS 1.085308 0.1678816
OS 1.095108 0.1678816
OS 1.095108 0.0970816
OE
CE
PIN 3 S 1.070208 0.2899619 0 U U
CT
OB 1.075108 0.2545619 I
OS 1.065308 0.2545619
OS 1.065308 0.3253619
OS 1.075108 0.3253619
OS 1.075108 0.2545619
OE
CE
PIN 4 S 1.070208 0.1324816 0 U U
CT
OB 1.075108 0.0970816 I
OS 1.065308 0.0970816
OS 1.065308 0.1678816
OS 1.075108 0.1678816
OS 1.075108 0.0970816
OE
CE
PIN 5 S 1.050208 0.2899619 0 U U
CT
OB 1.055108 0.2545619 I
OS 1.045308 0.2545619
OS 1.045308 0.3253619
OS 1.055108 0.3253619
OS 1.055108 0.2545619
OE
CE
PIN 6 S 1.050208 0.1324816 0 U U
CT
OB 1.055108 0.0970816 I
OS 1.045308 0.0970816
OS 1.045308 0.1678816
OS 1.055108 0.1678816
OS 1.055108 0.0970816
OE
CE
PIN 7 S 1.030208 0.2899619 0 U U
CT
OB 1.035108 0.2545619 I
OS 1.025308 0.2545619
OS 1.025308 0.3253619
OS 1.035108 0.3253619
OS 1.035108 0.2545619
OE
CE
PIN 8 S 1.030208 0.1324816 0 U U
CT
OB 1.035108 0.0970816 I
OS 1.025308 0.0970816
OS 1.025308 0.1678816
OS 1.035108 0.1678816
OS 1.035108 0.0970816
OE
CE
PIN 9 S 1.010208 0.2899619 0 U U
CT
OB 1.015108 0.2545619 I
OS 1.005308 0.2545619
OS 1.005308 0.3253619
OS 1.015108 0.3253619
OS 1.015108 0.2545619
OE
CE
PIN 10 S 1.010208 0.1324816 0 U U
CT
OB 1.015108 0.0970816 I
OS 1.005308 0.0970816
OS 1.005308 0.1678816
OS 1.015108 0.1678816
OS 1.015108 0.0970816
OE
CE
PIN 11 S 0.990208 0.2899619 0 U U
CT
OB 0.995108 0.2545619 I
OS 0.985308 0.2545619
OS 0.985308 0.3253619
OS 0.995108 0.3253619
OS 0.995108 0.2545619
OE
CE
PIN 12 S 0.990208 0.1324816 0 U U
CT
OB 0.995108 0.0970816 I
OS 0.985308 0.0970816
OS 0.985308 0.1678816
OS 0.995108 0.1678816
OS 0.995108 0.0970816
OE
CE
PIN 13 S 0.970208 0.2899619 0 U U
CT
OB 0.975108 0.2545619 I
OS 0.965308 0.2545619
OS 0.965308 0.3253619
OS 0.975108 0.3253619
OS 0.975108 0.2545619
OE
CE
PIN 14 S 0.970208 0.1324816 0 U U
CT
OB 0.975108 0.0970816 I
OS 0.965308 0.0970816
OS 0.965308 0.1678816
OS 0.975108 0.1678816
OS 0.975108 0.0970816
OE
CE
PIN 15 S 0.950208 0.2899619 0 U U
CT
OB 0.955108 0.2545619 I
OS 0.945308 0.2545619
OS 0.945308 0.3253619
OS 0.955108 0.3253619
OS 0.955108 0.2545619
OE
CE
PIN 16 S 0.950208 0.1324816 0 U U
CT
OB 0.955108 0.0970816 I
OS 0.945308 0.0970816
OS 0.945308 0.1678816
OS 0.955108 0.1678816
OS 0.955108 0.0970816
OE
CE
PIN 17 S 0.930208 0.2899619 0 U U
CT
OB 0.935108 0.2545619 I
OS 0.925308 0.2545619
OS 0.925308 0.3253619
OS 0.935108 0.3253619
OS 0.935108 0.2545619
OE
CE
PIN 18 S 0.930208 0.1324816 0 U U
CT
OB 0.935108 0.0970816 I
OS 0.925308 0.0970816
OS 0.925308 0.1678816
OS 0.935108 0.1678816
OS 0.935108 0.0970816
OE
CE
PIN 19 S 0.910208 0.2899619 0 U U
CT
OB 0.915108 0.2545619 I
OS 0.905308 0.2545619
OS 0.905308 0.3253619
OS 0.915108 0.3253619
OS 0.915108 0.2545619
OE
CE
PIN 20 S 0.910208 0.1324816 0 U U
CT
OB 0.915108 0.0970816 I
OS 0.905308 0.0970816
OS 0.905308 0.1678816
OS 0.915108 0.1678816
OS 0.915108 0.0970816
OE
CE
PIN P1 T 1.7992126 1.7992126 0 U U
CR 1.7992126 1.7992126 0.0375
PIN P2 T 1 1.7992126 0 U U
CR 1 1.7992126 0.0375
PIN P3 T 0.2007874 1.7992126 0 U U
CR 0.2007874 1.7992126 0.0375
PIN P4 T 0.2007874 0.2007874 0 U U
CR 0.2007874 0.2007874 0.0375
PIN P5 T 1.7992126 0.2007874 0 U U
CR 1.7992126 0.2007874 0.0375
PIN P6 T 0.0944882 0.2834646 0 U U
CR 0.0944882 0.2834646 0.0375
PIN P7 T 0.0944882 0.4015748 0 U U
CR 0.0944882 0.4015748 0.0375
PIN P8 T 0.0944882 0.519685 0 U U
CR 0.0944882 0.519685 0.0375
#
# PKG 19
PKG MCSM-090-02984-00X 0.2 -0.79998 -0.69498 0.79998 0.69498
CT
OB 0.79998 -0.69498 I
OS -0.79998 -0.69498
OS -0.79998 0.69498
OS 0.79998 0.69498
OS 0.79998 -0.69498
OE
CE
PIN 1 T -0.65 0.5 0 U U
CT
OB -0.6805118 0.5305118 I
OS -0.6194882 0.5305118
OS -0.6194882 0.4694882
OS -0.6805118 0.4694882
OS -0.6805118 0.5305118
OE
CE
PIN 4 T -0.65 -0.1 0 U U
CR -0.65 -0.1 0.0305118
PIN 5 T -0.65 -0.3 0 U U
CR -0.65 -0.3 0.0305118
PIN 6 T -0.65 -0.5 0 U U
CR -0.65 -0.5 0.0305118
PIN 7 T 0.65 -0.5 0 U U
CR 0.65 -0.5 0.0305118
PIN 8 T 0.65 -0.3 0 U U
CR 0.65 -0.3 0.0305118
PIN 9 T 0.65 -0.1 0 U U
CR 0.65 -0.1 0.0305118
PIN 10 T 0.65 0.1 0 U U
CR 0.65 0.1 0.0305118
PIN 12 T 0.65 0.5 0 U U
CR 0.65 0.5 0.0305118
#
# PKG 20
PKG OMRON-B3U-1000P 0.1338582 -0.0826771 -0.0492128 0.0826771 0.0492128
CT
OB 0.0787392 -0.0492128 I
OS -0.0787392 -0.0492128
OS -0.0787392 0.0492128
OS 0.0787392 0.0492128
OS 0.0787392 -0.0492128
OE
CE
PIN 1 S -0.0669291 0 0 U U
CT
OB -0.08267715 0.03346455 I
OS -0.05118105 0.03346455
OS -0.05118105 -0.03346455
OS -0.08267715 -0.03346455
OS -0.08267715 0.03346455
OE
CE
PIN 2 S 0.0669291 0 0 U U
CT
OB 0.05118105 0.03346455 I
OS 0.08267715 0.03346455
OS 0.08267715 -0.03346455
OS 0.05118105 -0.03346455
OS 0.05118105 0.03346455
OE
CE
#
# PKG 21
PKG PCIE_4LANE_EDGE 0 -0.6636 -0.18974 0.66361 -0.02474
RC -0.6636 -0.18974 1.32721 0.165
PIN A1 S -0.6496 -0.08774 0 U U
CT
OB -0.6636 -0.02474 I
OS -0.6356 -0.02474
OS -0.6356 -0.15074
OS -0.6636 -0.15074
OS -0.6636 -0.02474
OE
CE
PIN A2 S -0.61023 -0.10724 0 U U
CT
OB -0.62423 -0.02474 I
OS -0.59623 -0.02474
OS -0.59623 -0.18974
OS -0.62423 -0.18974
OS -0.62423 -0.02474
OE
CE
PIN A3 S -0.57086 -0.10724 0 U U
CT
OB -0.58486 -0.02474 I
OS -0.55686 -0.02474
OS -0.55686 -0.18974
OS -0.58486 -0.18974
OS -0.58486 -0.02474
OE
CE
PIN A4 S -0.53149 -0.10724 0 U U
CT
OB -0.54549 -0.02474 I
OS -0.51749 -0.02474
OS -0.51749 -0.18974
OS -0.54549 -0.18974
OS -0.54549 -0.02474
OE
CE
PIN A5 S -0.49212 -0.10724 0 U U
CT
OB -0.50612 -0.02474 I
OS -0.47812 -0.02474
OS -0.47812 -0.18974
OS -0.50612 -0.18974
OS -0.50612 -0.02474
OE
CE
PIN A6 S -0.45275 -0.10724 0 U U
CT
OB -0.46675 -0.02474 I
OS -0.43875 -0.02474
OS -0.43875 -0.18974
OS -0.46675 -0.18974
OS -0.46675 -0.02474
OE
CE
PIN A7 S -0.41338 -0.10724 0 U U
CT
OB -0.42738 -0.02474 I
OS -0.39938 -0.02474
OS -0.39938 -0.18974
OS -0.42738 -0.18974
OS -0.42738 -0.02474
OE
CE
PIN A8 S -0.37401 -0.10724 0 U U
CT
OB -0.38801 -0.02474 I
OS -0.36001 -0.02474
OS -0.36001 -0.18974
OS -0.38801 -0.18974
OS -0.38801 -0.02474
OE
CE
PIN A9 S -0.33464 -0.10724 0 U U
CT
OB -0.34864 -0.02474 I
OS -0.32064 -0.02474
OS -0.32064 -0.18974
OS -0.34864 -0.18974
OS -0.34864 -0.02474
OE
CE
PIN A10 S -0.29527 -0.10724 0 U U
CT
OB -0.30927 -0.02474 I
OS -0.28127 -0.02474
OS -0.28127 -0.18974
OS -0.30927 -0.18974
OS -0.30927 -0.02474
OE
CE
PIN A11 S -0.2559 -0.10724 0 U U
CT
OB -0.2699 -0.02474 I
OS -0.2419 -0.02474
OS -0.2419 -0.18974
OS -0.2699 -0.18974
OS -0.2699 -0.02474
OE
CE
PIN A12 S -0.13779 -0.10724 0 U U
CT
OB -0.15179 -0.02474 I
OS -0.12379 -0.02474
OS -0.12379 -0.18974
OS -0.15179 -0.18974
OS -0.15179 -0.02474
OE
CE
PIN A13 S -0.09842 -0.10724 0 U U
CT
OB -0.11242 -0.02474 I
OS -0.08442 -0.02474
OS -0.08442 -0.18974
OS -0.11242 -0.18974
OS -0.11242 -0.02474
OE
CE
PIN A14 S -0.05905 -0.10724 0 U U
CT
OB -0.07305 -0.02474 I
OS -0.04505 -0.02474
OS -0.04505 -0.18974
OS -0.07305 -0.18974
OS -0.07305 -0.02474
OE
CE
PIN A15 S -0.01968 -0.10724 0 U U
CT
OB -0.03368 -0.02474 I
OS -0.00568 -0.02474
OS -0.00568 -0.18974
OS -0.03368 -0.18974
OS -0.03368 -0.02474
OE
CE
PIN A16 S 0.01969 -0.10724 0 U U
CT
OB 0.00569 -0.02474 I
OS 0.03369 -0.02474
OS 0.03369 -0.18974
OS 0.00569 -0.18974
OS 0.00569 -0.02474
OE
CE
PIN A17 S 0.05906 -0.10724 0 U U
CT
OB 0.04506 -0.02474 I
OS 0.07306 -0.02474
OS 0.07306 -0.18974
OS 0.04506 -0.18974
OS 0.04506 -0.02474
OE
CE
PIN A18 S 0.09843 -0.10724 0 U U
CT
OB 0.08443 -0.02474 I
OS 0.11243 -0.02474
OS 0.11243 -0.18974
OS 0.08443 -0.18974
OS 0.08443 -0.02474
OE
CE
PIN A19 S 0.1378 -0.10724 0 U U
CT
OB 0.1238 -0.02474 I
OS 0.1518 -0.02474
OS 0.1518 -0.18974
OS 0.1238 -0.18974
OS 0.1238 -0.02474
OE
CE
PIN A20 S 0.17717 -0.10724 0 U U
CT
OB 0.16317 -0.02474 I
OS 0.19117 -0.02474
OS 0.19117 -0.18974
OS 0.16317 -0.18974
OS 0.16317 -0.02474
OE
CE
PIN A21 S 0.21654 -0.10724 0 U U
CT
OB 0.20254 -0.02474 I
OS 0.23054 -0.02474
OS 0.23054 -0.18974
OS 0.20254 -0.18974
OS 0.20254 -0.02474
OE
CE
PIN A22 S 0.25591 -0.10724 0 U U
CT
OB 0.24191 -0.02474 I
OS 0.26991 -0.02474
OS 0.26991 -0.18974
OS 0.24191 -0.18974
OS 0.24191 -0.02474
OE
CE
PIN A23 S 0.29528 -0.10724 0 U U
CT
OB 0.28128 -0.02474 I
OS 0.30928 -0.02474
OS 0.30928 -0.18974
OS 0.28128 -0.18974
OS 0.28128 -0.02474
OE
CE
PIN A24 S 0.33465 -0.10724 0 U U
CT
OB 0.32065 -0.02474 I
OS 0.34865 -0.02474
OS 0.34865 -0.18974
OS 0.32065 -0.18974
OS 0.32065 -0.02474
OE
CE
PIN A25 S 0.37402 -0.10724 0 U U
CT
OB 0.36002 -0.02474 I
OS 0.38802 -0.02474
OS 0.38802 -0.18974
OS 0.36002 -0.18974
OS 0.36002 -0.02474
OE
CE
PIN A26 S 0.41339 -0.10724 0 U U
CT
OB 0.39939 -0.02474 I
OS 0.42739 -0.02474
OS 0.42739 -0.18974
OS 0.39939 -0.18974
OS 0.39939 -0.02474
OE
CE
PIN A27 S 0.45276 -0.10724 0 U U
CT
OB 0.43876 -0.02474 I
OS 0.46676 -0.02474
OS 0.46676 -0.18974
OS 0.43876 -0.18974
OS 0.43876 -0.02474
OE
CE
PIN A28 S 0.49213 -0.10724 0 U U
CT
OB 0.47813 -0.02474 I
OS 0.50613 -0.02474
OS 0.50613 -0.18974
OS 0.47813 -0.18974
OS 0.47813 -0.02474
OE
CE
PIN A29 S 0.5315 -0.10724 0 U U
CT
OB 0.5175 -0.02474 I
OS 0.5455 -0.02474
OS 0.5455 -0.18974
OS 0.5175 -0.18974
OS 0.5175 -0.02474
OE
CE
PIN A30 S 0.57087 -0.10724 0 U U
CT
OB 0.55687 -0.02474 I
OS 0.58487 -0.02474
OS 0.58487 -0.18974
OS 0.55687 -0.18974
OS 0.55687 -0.02474
OE
CE
PIN A31 S 0.61024 -0.10724 0 U U
CT
OB 0.59624 -0.02474 I
OS 0.62424 -0.02474
OS 0.62424 -0.18974
OS 0.59624 -0.18974
OS 0.59624 -0.02474
OE
CE
PIN A32 S 0.64961 -0.10724 0 U U
CT
OB 0.63561 -0.02474 I
OS 0.66361 -0.02474
OS 0.66361 -0.18974
OS 0.63561 -0.18974
OS 0.63561 -0.02474
OE
CE
PIN B1 S -0.6496 -0.10724 0 U U
CT
OB -0.6636 -0.02474 I
OS -0.6356 -0.02474
OS -0.6356 -0.18974
OS -0.6636 -0.18974
OS -0.6636 -0.02474
OE
CE
PIN B2 S -0.61023 -0.10724 0 U U
CT
OB -0.62423 -0.02474 I
OS -0.59623 -0.02474
OS -0.59623 -0.18974
OS -0.62423 -0.18974
OS -0.62423 -0.02474
OE
CE
PIN B3 S -0.57086 -0.10724 0 U U
CT
OB -0.58486 -0.02474 I
OS -0.55686 -0.02474
OS -0.55686 -0.18974
OS -0.58486 -0.18974
OS -0.58486 -0.02474
OE
CE
PIN B4 S -0.53149 -0.10724 0 U U
CT
OB -0.54549 -0.02474 I
OS -0.51749 -0.02474
OS -0.51749 -0.18974
OS -0.54549 -0.18974
OS -0.54549 -0.02474
OE
CE
PIN B5 S -0.49212 -0.10724 0 U U
CT
OB -0.50612 -0.02474 I
OS -0.47812 -0.02474
OS -0.47812 -0.18974
OS -0.50612 -0.18974
OS -0.50612 -0.02474
OE
CE
PIN B6 S -0.45275 -0.10724 0 U U
CT
OB -0.46675 -0.02474 I
OS -0.43875 -0.02474
OS -0.43875 -0.18974
OS -0.46675 -0.18974
OS -0.46675 -0.02474
OE
CE
PIN B7 S -0.41338 -0.10724 0 U U
CT
OB -0.42738 -0.02474 I
OS -0.39938 -0.02474
OS -0.39938 -0.18974
OS -0.42738 -0.18974
OS -0.42738 -0.02474
OE
CE
PIN B8 S -0.37401 -0.10724 0 U U
CT
OB -0.38801 -0.02474 I
OS -0.36001 -0.02474
OS -0.36001 -0.18974
OS -0.38801 -0.18974
OS -0.38801 -0.02474
OE
CE
PIN B9 S -0.33464 -0.10724 0 U U
CT
OB -0.34864 -0.02474 I
OS -0.32064 -0.02474
OS -0.32064 -0.18974
OS -0.34864 -0.18974
OS -0.34864 -0.02474
OE
CE
PIN B10 S -0.29527 -0.10724 0 U U
CT
OB -0.30927 -0.02474 I
OS -0.28127 -0.02474
OS -0.28127 -0.18974
OS -0.30927 -0.18974
OS -0.30927 -0.02474
OE
CE
PIN B11 S -0.2559 -0.10724 0 U U
CT
OB -0.2699 -0.02474 I
OS -0.2419 -0.02474
OS -0.2419 -0.18974
OS -0.2699 -0.18974
OS -0.2699 -0.02474
OE
CE
PIN B12 S -0.13779 -0.10724 0 U U
CT
OB -0.15179 -0.02474 I
OS -0.12379 -0.02474
OS -0.12379 -0.18974
OS -0.15179 -0.18974
OS -0.15179 -0.02474
OE
CE
PIN B13 S -0.09842 -0.10724 0 U U
CT
OB -0.11242 -0.02474 I
OS -0.08442 -0.02474
OS -0.08442 -0.18974
OS -0.11242 -0.18974
OS -0.11242 -0.02474
OE
CE
PIN B14 S -0.05905 -0.10724 0 U U
CT
OB -0.07305 -0.02474 I
OS -0.04505 -0.02474
OS -0.04505 -0.18974
OS -0.07305 -0.18974
OS -0.07305 -0.02474
OE
CE
PIN B15 S -0.01968 -0.10724 0 U U
CT
OB -0.03368 -0.02474 I
OS -0.00568 -0.02474
OS -0.00568 -0.18974
OS -0.03368 -0.18974
OS -0.03368 -0.02474
OE
CE
PIN B16 S 0.01969 -0.10724 0 U U
CT
OB 0.00569 -0.02474 I
OS 0.03369 -0.02474
OS 0.03369 -0.18974
OS 0.00569 -0.18974
OS 0.00569 -0.02474
OE
CE
PIN B17 S 0.05906 -0.10724 0 U U
CT
OB 0.04506 -0.02474 I
OS 0.07306 -0.02474
OS 0.07306 -0.18974
OS 0.04506 -0.18974
OS 0.04506 -0.02474
OE
CE
PIN B18 S 0.09843 -0.10724 0 U U
CT
OB 0.08443 -0.02474 I
OS 0.11243 -0.02474
OS 0.11243 -0.18974
OS 0.08443 -0.18974
OS 0.08443 -0.02474
OE
CE
PIN B19 S 0.1378 -0.10724 0 U U
CT
OB 0.1238 -0.02474 I
OS 0.1518 -0.02474
OS 0.1518 -0.18974
OS 0.1238 -0.18974
OS 0.1238 -0.02474
OE
CE
PIN B20 S 0.17717 -0.10724 0 U U
CT
OB 0.16317 -0.02474 I
OS 0.19117 -0.02474
OS 0.19117 -0.18974
OS 0.16317 -0.18974
OS 0.16317 -0.02474
OE
CE
PIN B21 S 0.21654 -0.10724 0 U U
CT
OB 0.20254 -0.02474 I
OS 0.23054 -0.02474
OS 0.23054 -0.18974
OS 0.20254 -0.18974
OS 0.20254 -0.02474
OE
CE
PIN B22 S 0.25591 -0.10724 0 U U
CT
OB 0.24191 -0.02474 I
OS 0.26991 -0.02474
OS 0.26991 -0.18974
OS 0.24191 -0.18974
OS 0.24191 -0.02474
OE
CE
PIN B23 S 0.29528 -0.10724 0 U U
CT
OB 0.28128 -0.02474 I
OS 0.30928 -0.02474
OS 0.30928 -0.18974
OS 0.28128 -0.18974
OS 0.28128 -0.02474
OE
CE
PIN B24 S 0.33465 -0.10724 0 U U
CT
OB 0.32065 -0.02474 I
OS 0.34865 -0.02474
OS 0.34865 -0.18974
OS 0.32065 -0.18974
OS 0.32065 -0.02474
OE
CE
PIN B25 S 0.37402 -0.10724 0 U U
CT
OB 0.36002 -0.02474 I
OS 0.38802 -0.02474
OS 0.38802 -0.18974
OS 0.36002 -0.18974
OS 0.36002 -0.02474
OE
CE
PIN B26 S 0.41339 -0.10724 0 U U
CT
OB 0.39939 -0.02474 I
OS 0.42739 -0.02474
OS 0.42739 -0.18974
OS 0.39939 -0.18974
OS 0.39939 -0.02474
OE
CE
PIN B27 S 0.45276 -0.10724 0 U U
CT
OB 0.43876 -0.02474 I
OS 0.46676 -0.02474
OS 0.46676 -0.18974
OS 0.43876 -0.18974
OS 0.43876 -0.02474
OE
CE
PIN B28 S 0.49213 -0.10724 0 U U
CT
OB 0.47813 -0.02474 I
OS 0.50613 -0.02474
OS 0.50613 -0.18974
OS 0.47813 -0.18974
OS 0.47813 -0.02474
OE
CE
PIN B29 S 0.5315 -0.10724 0 U U
CT
OB 0.5175 -0.02474 I
OS 0.5455 -0.02474
OS 0.5455 -0.18974
OS 0.5175 -0.18974
OS 0.5175 -0.02474
OE
CE
PIN B30 S 0.57087 -0.10724 0 U U
CT
OB 0.55687 -0.02474 I
OS 0.58487 -0.02474
OS 0.58487 -0.18974
OS 0.55687 -0.18974
OS 0.55687 -0.02474
OE
CE
PIN B31 S 0.61024 -0.08774 0 U U
CT
OB 0.59624 -0.02474 I
OS 0.62424 -0.02474
OS 0.62424 -0.15074
OS 0.59624 -0.15074
OS 0.59624 -0.02474
OE
CE
PIN B32 S 0.64961 -0.10724 0 U U
CT
OB 0.63561 -0.02474 I
OS 0.66361 -0.02474
OS 0.66361 -0.18974
OS 0.63561 -0.18974
OS 0.63561 -0.02474
OE
CE
#
# PKG 22
PKG RCB-F9T 0.0787401 0.6426036 0.1116142 0.9574036 0.3694882
CT
OB 0.9574036 0.1310559 I
OS 0.6426036 0.1310559
OS 0.6426036 0.3500559
OS 0.9574036 0.3500559
OS 0.9574036 0.1310559
OE
CE
PIN 0 T 0.7271654 0.2405512 0 U U
CR 0.7271654 0.2405512 0.01496065
PIN 0 T 0.8846457 0.2405512 0 U U
CR 0.8846457 0.2405512 0.01496065
PIN 1 S 0.9240157 0.1530512 0 U U
CT
OB 0.90196845 0.1944882 I
OS 0.94606295 0.1944882
OS 0.94606295 0.1116142
OS 0.90196845 0.1116142
OS 0.90196845 0.1944882
OE
CE
PIN 2 S 0.9240157 0.3280512 0 U U
CT
OB 0.90196845 0.3694882 I
OS 0.94606295 0.3694882
OS 0.94606295 0.2866142
OS 0.90196845 0.2866142
OS 0.90196845 0.3694882
OE
CE
PIN 3 S 0.8452756 0.1530512 0 U U
CT
OB 0.82322835 0.1944882 I
OS 0.86732285 0.1944882
OS 0.86732285 0.1116142
OS 0.82322835 0.1116142
OS 0.82322835 0.1944882
OE
CE
PIN 4 S 0.8452756 0.3280512 0 U U
CT
OB 0.82322835 0.3694882 I
OS 0.86732285 0.3694882
OS 0.86732285 0.2866142
OS 0.82322835 0.2866142
OS 0.82322835 0.3694882
OE
CE
PIN 5 S 0.7665354 0.1530512 0 U U
CT
OB 0.74448815 0.1944882 I
OS 0.78858265 0.1944882
OS 0.78858265 0.1116142
OS 0.74448815 0.1116142
OS 0.74448815 0.1944882
OE
CE
PIN 6 S 0.7665354 0.3280512 0 U U
CT
OB 0.74448815 0.3694882 I
OS 0.78858265 0.3694882
OS 0.78858265 0.2866142
OS 0.74448815 0.2866142
OS 0.74448815 0.3694882
OE
CE
PIN 7 S 0.6877953 0.1530512 0 U U
CT
OB 0.66574805 0.1944882 I
OS 0.70984255 0.1944882
OS 0.70984255 0.1116142
OS 0.66574805 0.1116142
OS 0.66574805 0.1944882
OE
CE
PIN 8 S 0.6877953 0.3280512 0 U U
CT
OB 0.66574805 0.3694882 I
OS 0.70984255 0.3694882
OS 0.70984255 0.2866142
OS 0.66574805 0.2866142
OS 0.66574805 0.3694882
OE
CE
#
# PKG 23
PKG RESC1005X04N 0.0334646 -0.0295276 -0.011811 0.0295276 0.011811
CT
OB 0.0216535 -0.011811 I
OS -0.0216536 -0.011811
OS -0.0216536 0.011811
OS 0.0216535 0.011811
OS 0.0216535 -0.011811
OE
CE
PIN 1 S -0.0167323 0 0 U U
CT
OB -0.0294323 -0.0118 I
OS -0.0294323 0.0118
OS -0.0040323 0.0118
OS -0.0040323 -0.0118
OS -0.0294323 -0.0118
OE
CE
PIN 2 S 0.0167323 0 0 U U
CT
OB 0.0040323 -0.0118 I
OS 0.0040323 0.0118
OS 0.0294323 0.0118
OS 0.0294323 -0.0118
OS 0.0040323 -0.0118
OE
CE
#
# PKG 24
PKG RESC1608X50N 0.0543307 -0.0413386 -0.019685 0.0413385 0.019685
CT
OB 0.0324803 -0.0187008 I
OS -0.0324804 -0.0187008
OS -0.0324804 0.0187008
OS 0.0324803 0.0187008
OS 0.0324803 -0.0187008
OE
CE
PIN 1 S -0.0271654 0 0 U U
CT
OB -0.0412654 -0.0196 I
OS -0.0412654 0.0196
OS -0.0130654 0.0196
OS -0.0130654 -0.0196
OS -0.0412654 -0.0196
OE
CE
PIN 2 S 0.0271653 0 0 U U
CT
OB 0.0130653 -0.0196 I
OS 0.0130653 0.0196
OS 0.0412653 0.0196
OS 0.0412653 -0.0196
OS 0.0130653 -0.0196
OE
CE
#
# PKG 25
PKG RESC2012X50N 0.0787402 -0.0580709 -0.0285433 0.0580709 0.0285433
CT
OB 0.0433071 -0.0275591 I
OS -0.0433071 -0.0275591
OS -0.0433071 0.027559
OS 0.0433071 0.027559
OS 0.0433071 -0.0275591
OE
CE
PIN 1 S -0.0393701 0 0 U U
CT
OB -0.0580701 -0.0285 I
OS -0.0580701 0.0285
OS -0.0206701 0.0285
OS -0.0206701 -0.0285
OS -0.0580701 -0.0285
OE
CE
PIN 2 S 0.0393701 0 0 U U
CT
OB 0.0206701 -0.0285 I
OS 0.0206701 0.0285
OS 0.0580701 0.0285
OS 0.0580701 -0.0285
OS 0.0206701 -0.0285
OE
CE
#
# PKG 26
PKG SAMTEC_HTST-105-01-L-DV-A 0.1 -0.4000032 -0.2350393 0.3999968 0.2350394
CT
OB 0.3999968 -0.2199993 I
OS -0.4000032 -0.2199993
OS -0.4000032 0.2200007
OS 0.3999968 0.2200007
OS 0.3999968 -0.2199993
OE
CE
PIN 1 S -0.2 -0.1350393 0 U U
CT
OB -0.225 -0.0350393 I
OS -0.175 -0.0350393
OS -0.175 -0.2350393
OS -0.225 -0.2350393
OS -0.225 -0.0350393
OE
CE
PIN 2 S -0.2 0.1350394 0 U U
CT
OB -0.225 0.2350394 I
OS -0.175 0.2350394
OS -0.175 0.0350394
OS -0.225 0.0350394
OS -0.225 0.2350394
OE
CE
PIN 3 S -0.1 -0.1350393 0 U U
CT
OB -0.125 -0.0350393 I
OS -0.075 -0.0350393
OS -0.075 -0.2350393
OS -0.125 -0.2350393
OS -0.125 -0.0350393
OE
CE
PIN 4 S -0.1 0.1350394 0 U U
CT
OB -0.125 0.2350394 I
OS -0.075 0.2350394
OS -0.075 0.0350394
OS -0.125 0.0350394
OS -0.125 0.2350394
OE
CE
PIN 5 S 0 -0.1350393 0 U U
CT
OB -0.025 -0.0350393 I
OS 0.025 -0.0350393
OS 0.025 -0.2350393
OS -0.025 -0.2350393
OS -0.025 -0.0350393
OE
CE
PIN 6 S 0 0.1350394 0 U U
CT
OB -0.025 0.2350394 I
OS 0.025 0.2350394
OS 0.025 0.0350394
OS -0.025 0.0350394
OS -0.025 0.2350394
OE
CE
PIN 7 S 0.1 -0.1350393 0 U U
CT
OB 0.075 -0.0350393 I
OS 0.125 -0.0350393
OS 0.125 -0.2350393
OS 0.075 -0.2350393
OS 0.075 -0.0350393
OE
CE
PIN 8 S 0.1 0.1350394 0 U U
CT
OB 0.075 0.2350394 I
OS 0.125 0.2350394
OS 0.125 0.0350394
OS 0.075 0.0350394
OS 0.075 0.2350394
OE
CE
PIN 9 S 0.2 -0.1350393 0 U U
CT
OB 0.175 -0.0350393 I
OS 0.225 -0.0350393
OS 0.225 -0.2350393
OS 0.175 -0.2350393
OS 0.175 -0.0350393
OE
CE
PIN 10 S 0.2 0.1350394 0 U U
CT
OB 0.175 0.2350394 I
OS 0.225 0.2350394
OS 0.225 0.0350394
OS 0.175 0.0350394
OS 0.175 0.2350394
OE
CE
PIN empty-1 T 0.15 0.0000001 0 U U
CR 0.15 0.0000001 0.03299215
PIN empty-2 T -0.15 0.0000001 0 U U
CR -0.15 0.0000001 0.03299215
#
# PKG 27
PKG SiT5155 0.0462598 -0.0669291 -0.1023622 0.0669291 0.1023622
RC -0.0669291 -0.1023622 0.1338582 0.2047244
PIN 1 S -0.0462598 0.0797244 0 U U
CT
OB -0.0669291 0.1023622 I
OS -0.0255905 0.1023622
OS -0.0255905 0.0570866
OS -0.0669291 0.0570866
OS -0.0669291 0.1023622
OE
CE
PIN 2 S -0.0403543 0.023622 0 U U
CT
OB -0.0669291 0.03740155 I
OS -0.0137795 0.03740155
OS -0.0137795 0.00984245
OS -0.0669291 0.00984245
OS -0.0669291 0.03740155
OE
CE
PIN 3 S -0.0403543 -0.023622 0 U U
CT
OB -0.0669291 -0.00984245 I
OS -0.0137795 -0.00984245
OS -0.0137795 -0.03740155
OS -0.0669291 -0.03740155
OS -0.0669291 -0.00984245
OE
CE
PIN 4 S -0.0462598 -0.0797244 0 U U
CT
OB -0.0669291 -0.0570866 I
OS -0.0255905 -0.0570866
OS -0.0255905 -0.1023622
OS -0.0669291 -0.1023622
OS -0.0669291 -0.0570866
OE
CE
PIN 5 S 0 -0.0797244 0 U U
CT
OB -0.0137 -0.1023244 I
OS -0.0137 -0.0571244
OS 0.0137 -0.0571244
OS 0.0137 -0.1023244
OS -0.0137 -0.1023244
OE
CE
PIN 6 S 0.0462598 -0.0797244 0 U U
CT
OB 0.0255905 -0.0570866 I
OS 0.0669291 -0.0570866
OS 0.0669291 -0.1023622
OS 0.0255905 -0.1023622
OS 0.0255905 -0.0570866
OE
CE
PIN 7 S 0.0403543 -0.023622 0 U U
CT
OB 0.0137795 -0.00984245 I
OS 0.0669291 -0.00984245
OS 0.0669291 -0.03740155
OS 0.0137795 -0.03740155
OS 0.0137795 -0.00984245
OE
CE
PIN 8 S 0.0403543 0.023622 0 U U
CT
OB 0.0137795 0.03740155 I
OS 0.0669291 0.03740155
OS 0.0669291 0.00984245
OS 0.0137795 0.00984245
OS 0.0137795 0.03740155
OE
CE
PIN 9 S 0.0462598 0.0797244 0 U U
CT
OB 0.0255905 0.1023622 I
OS 0.0669291 0.1023622
OS 0.0669291 0.0570866
OS 0.0255905 0.0570866
OS 0.0255905 0.1023622
OE
CE
PIN 10 S 0 0.0797244 0 U U
CT
OB -0.0137 0.0571244 I
OS -0.0137 0.1023244
OS 0.0137 0.1023244
OS 0.0137 0.0571244
OS -0.0137 0.0571244
OE
CE
#
# PKG 28
PKG SIT5721 0.0590551 -0.1299212 -0.1377952 0.1299212 0.1377952
RC -0.1299212 -0.1377952 0.2598424 0.2755904
PIN 1 S -0.0846456 0.1181102 0 U U
CT
OB -0.1299212 0.13779525 I
OS -0.03937 0.13779525
OS -0.03937 0.09842515
OS -0.1299212 0.09842515
OS -0.1299212 0.13779525
OE
CE
PIN 2 S -0.0944882 0.0590551 0 U U
CT
OB -0.12992125 0.07874015 I
OS -0.05905515 0.07874015
OS -0.05905515 0.03937005
OS -0.12992125 0.03937005
OS -0.12992125 0.07874015
OE
CE
PIN 3 S -0.0944882 0 0 U U
CT
OB -0.12992125 0.01968505 I
OS -0.05905515 0.01968505
OS -0.05905515 -0.01968505
OS -0.12992125 -0.01968505
OS -0.12992125 0.01968505
OE
CE
PIN 4 S -0.0944882 -0.0590551 0 U U
CT
OB -0.12992125 -0.03937005 I
OS -0.05905515 -0.03937005
OS -0.05905515 -0.07874015
OS -0.12992125 -0.07874015
OS -0.12992125 -0.03937005
OE
CE
PIN 5 S -0.0944882 -0.1181102 0 U U
CT
OB -0.0590882 -0.1377102 I
OS -0.1298882 -0.1377102
OS -0.1298882 -0.0985102
OS -0.0590882 -0.0985102
OS -0.0590882 -0.1377102
OE
CE
PIN 6 S 0.0944882 -0.1181102 0 U U
CT
OB 0.05905515 -0.09842515 I
OS 0.12992125 -0.09842515
OS 0.12992125 -0.13779525
OS 0.05905515 -0.13779525
OS 0.05905515 -0.09842515
OE
CE
PIN 7 S 0.0944882 -0.0590551 0 U U
CT
OB 0.05905515 -0.03937005 I
OS 0.12992125 -0.03937005
OS 0.12992125 -0.07874015
OS 0.05905515 -0.07874015
OS 0.05905515 -0.03937005
OE
CE
PIN 8 S 0.0944882 0 0 U U
CT
OB 0.05905515 0.01968505 I
OS 0.12992125 0.01968505
OS 0.12992125 -0.01968505
OS 0.05905515 -0.01968505
OS 0.05905515 0.01968505
OE
CE
PIN 9 S 0.0944882 0.0590551 0 U U
CT
OB 0.05905515 0.07874015 I
OS 0.12992125 0.07874015
OS 0.12992125 0.03937005
OS 0.05905515 0.03937005
OS 0.05905515 0.07874015
OE
CE
PIN 10 S 0.0944882 0.1181102 0 U U
CT
OB 0.1298882 0.0985102 I
OS 0.0590882 0.0985102
OS 0.0590882 0.1377102
OS 0.1298882 0.1377102
OS 0.1298882 0.0985102
OE
CE
#
# PKG 29
PKG SM8 0.1259842 -0.15 -0.1003936 0.15 0.1003936
CT
OB 0.118 0.06 I
OS 0.15 0.06
OS 0.15 -0.06
OS 0.118 -0.06
OS 0.118 -0.075
OS 0.098 -0.075
OS 0.098 -0.06
OS -0.098 -0.06
OS -0.098 -0.075
OS -0.118 -0.075
OS -0.118 -0.06
OS -0.15 -0.06
OS -0.15 0.06
OS -0.118 0.06
OS -0.118 0.075
OS -0.098 0.075
OS -0.098 0.06
OS 0.098 0.06
OS 0.098 0.075
OS 0.118 0.075
OS 0.118 0.06
OE
CE
PIN 1 S -0.1082677 -0.0629921 0 U U
CT
OB -0.1337677 -0.1003921 I
OS -0.1337677 -0.0255921
OS -0.0827677 -0.0255921
OS -0.0827677 -0.1003921
OS -0.1337677 -0.1003921
OE
CE
PIN 2 S 0.1082677 -0.0629921 0 U U
CT
OB 0.0827677 -0.1003921 I
OS 0.0827677 -0.0255921
OS 0.1337677 -0.0255921
OS 0.1337677 -0.1003921
OS 0.0827677 -0.1003921
OE
CE
PIN 3 S 0.1082677 0.0629921 0 U U
CT
OB 0.0827677 0.0255921 I
OS 0.0827677 0.1003921
OS 0.1337677 0.1003921
OS 0.1337677 0.0255921
OS 0.0827677 0.0255921
OE
CE
PIN 4 S -0.1082677 0.0629921 0 U U
CT
OB -0.1337677 0.0255921 I
OS -0.1337677 0.1003921
OS -0.0827677 0.1003921
OS -0.0827677 0.0255921
OS -0.1337677 0.0255921
OE
CE
#
# PKG 30
PKG SODFL370X135-2N 0.1437008 -0.0846457 -0.0423901 0.0846457 0.0423715
CT
OB 0.0757774 -0.0423901 I
OS -0.0758002 -0.0423901
OS -0.0758002 0.0423715
OS 0.0757774 0.0423715
OS 0.0757774 -0.0423901
OE
CE
PIN 1 S -0.0718504 0 0 U U
CT
OB -0.0845504 -0.0206 I
OS -0.0845504 0.0206
OS -0.0591504 0.0206
OS -0.0591504 -0.0206
OS -0.0845504 -0.0206
OE
CE
PIN 2 S 0.0718504 0 0 U U
CT
OB 0.0591504 -0.0206 I
OS 0.0591504 0.0206
OS 0.0845504 0.0206
OS 0.0845504 -0.0206
OS 0.0591504 -0.0206
OE
CE
#
# PKG 31
PKG SOIC127P600X175-8N 0.05 -0.1362204 -0.0964656 0.1362204 0.0964496
CT
OB 0.1181152 -0.0964656 I
OS -0.1181024 -0.0964656
OS -0.1181024 0.0964496
OS 0.1181152 0.0964496
OS 0.1181152 -0.0964656
OE
CE
PIN 1 S -0.0974409 0.075 0 U U
CT
OB -0.13622045 0.08622045 I
OS -0.05866135 0.08622045
OS -0.05866135 0.06377955
OS -0.13622045 0.06377955
OS -0.13622045 0.08622045
OE
CE
PIN 2 S -0.0974409 0.025 0 U U
CT
OB -0.13622045 0.03622045 I
OS -0.05866135 0.03622045
OS -0.05866135 0.01377955
OS -0.13622045 0.01377955
OS -0.13622045 0.03622045
OE
CE
PIN 3 S -0.0974409 -0.025 0 U U
CT
OB -0.13622045 -0.01377955 I
OS -0.05866135 -0.01377955
OS -0.05866135 -0.03622045
OS -0.13622045 -0.03622045
OS -0.13622045 -0.01377955
OE
CE
PIN 4 S -0.0974409 -0.075 0 U U
CT
OB -0.13622045 -0.06377955 I
OS -0.05866135 -0.06377955
OS -0.05866135 -0.08622045
OS -0.13622045 -0.08622045
OS -0.13622045 -0.06377955
OE
CE
PIN 5 S 0.0974409 -0.075 0 U U
CT
OB 0.05866135 -0.06377955 I
OS 0.13622045 -0.06377955
OS 0.13622045 -0.08622045
OS 0.05866135 -0.08622045
OS 0.05866135 -0.06377955
OE
CE
PIN 6 S 0.0974409 -0.025 0 U U
CT
OB 0.05866135 -0.01377955 I
OS 0.13622045 -0.01377955
OS 0.13622045 -0.03622045
OS 0.05866135 -0.03622045
OS 0.05866135 -0.01377955
OE
CE
PIN 7 S 0.0974409 0.025 0 U U
CT
OB 0.05866135 0.03622045 I
OS 0.13622045 0.03622045
OS 0.13622045 0.01377955
OS 0.05866135 0.01377955
OS 0.05866135 0.03622045
OE
CE
PIN 8 S 0.0974409 0.075 0 U U
CT
OB 0.05866135 0.08622045 I
OS 0.13622045 0.08622045
OS 0.13622045 0.06377955
OS 0.05866135 0.06377955
OS 0.05866135 0.08622045
OE
CE
#
# PKG 32
PKG SOP64P600X170-16N 0.025 -0.1358268 -0.0984955 0.1358267 0.0985093
CT
OB 0.1220131 -0.0984955 I
OS -0.1219997 -0.0984955
OS -0.1219997 0.0985093
OS 0.1220131 0.0985093
OS 0.1220131 -0.0984955
OE
CE
PIN 1 S -0.1072835 0.0875 0 U U
CT
OB -0.0876835 0.0787 I
OS -0.1268835 0.0787
OC -0.1268835 0.0963 -0.1268835 0.0875 Y
OS -0.0876835 0.0963
OC -0.0876835 0.0787 -0.0876835 0.0875 Y
OE
CE
PIN 2 S -0.1072835 0.0625 0 U U
CT
OB -0.0876835 0.0537 I
OS -0.1268835 0.0537
OC -0.1268835 0.0713 -0.1268835 0.0625 Y
OS -0.0876835 0.0713
OC -0.0876835 0.0537 -0.0876835 0.0625 Y
OE
CE
PIN 3 S -0.1072835 0.0375 0 U U
CT
OB -0.0876835 0.0287 I
OS -0.1268835 0.0287
OC -0.1268835 0.0463 -0.1268835 0.0375 Y
OS -0.0876835 0.0463
OC -0.0876835 0.0287 -0.0876835 0.0375 Y
OE
CE
PIN 4 S -0.1072835 0.0125 0 U U
CT
OB -0.0876835 0.0037 I
OS -0.1268835 0.0037
OC -0.1268835 0.0213 -0.1268835 0.0125 Y
OS -0.0876835 0.0213
OC -0.0876835 0.0037 -0.0876835 0.0125 Y
OE
CE
PIN 5 S -0.1072835 -0.0125 0 U U
CT
OB -0.0876835 -0.0213 I
OS -0.1268835 -0.0213
OC -0.1268835 -0.0037 -0.1268835 -0.0125 Y
OS -0.0876835 -0.0037
OC -0.0876835 -0.0213 -0.0876835 -0.0125 Y
OE
CE
PIN 6 S -0.1072835 -0.0375 0 U U
CT
OB -0.0876835 -0.0463 I
OS -0.1268835 -0.0463
OC -0.1268835 -0.0287 -0.1268835 -0.0375 Y
OS -0.0876835 -0.0287
OC -0.0876835 -0.0463 -0.0876835 -0.0375 Y
OE
CE
PIN 7 S -0.1072835 -0.0625 0 U U
CT
OB -0.0876835 -0.0713 I
OS -0.1268835 -0.0713
OC -0.1268835 -0.0537 -0.1268835 -0.0625 Y
OS -0.0876835 -0.0537
OC -0.0876835 -0.0713 -0.0876835 -0.0625 Y
OE
CE
PIN 8 S -0.1072835 -0.0875 0 U U
CT
OB -0.0876835 -0.0963 I
OS -0.1268835 -0.0963
OC -0.1268835 -0.0787 -0.1268835 -0.0875 Y
OS -0.0876835 -0.0787
OC -0.0876835 -0.0963 -0.0876835 -0.0875 Y
OE
CE
PIN 9 S 0.1072834 -0.0875 0 U U
CT
OB 0.1268834 -0.0963 I
OS 0.0876834 -0.0963
OC 0.0876834 -0.0787 0.0876834 -0.0875 Y
OS 0.1268834 -0.0787
OC 0.1268834 -0.0963 0.1268834 -0.0875 Y
OE
CE
PIN 10 S 0.1072834 -0.0625 0 U U
CT
OB 0.1268834 -0.0713 I
OS 0.0876834 -0.0713
OC 0.0876834 -0.0537 0.0876834 -0.0625 Y
OS 0.1268834 -0.0537
OC 0.1268834 -0.0713 0.1268834 -0.0625 Y
OE
CE
PIN 11 S 0.1072834 -0.0375 0 U U
CT
OB 0.1268834 -0.0463 I
OS 0.0876834 -0.0463
OC 0.0876834 -0.0287 0.0876834 -0.0375 Y
OS 0.1268834 -0.0287
OC 0.1268834 -0.0463 0.1268834 -0.0375 Y
OE
CE
PIN 12 S 0.1072834 -0.0125 0 U U
CT
OB 0.1268834 -0.0213 I
OS 0.0876834 -0.0213
OC 0.0876834 -0.0037 0.0876834 -0.0125 Y
OS 0.1268834 -0.0037
OC 0.1268834 -0.0213 0.1268834 -0.0125 Y
OE
CE
PIN 13 S 0.1072834 0.0125 0 U U
CT
OB 0.1268834 0.0037 I
OS 0.0876834 0.0037
OC 0.0876834 0.0213 0.0876834 0.0125 Y
OS 0.1268834 0.0213
OC 0.1268834 0.0037 0.1268834 0.0125 Y
OE
CE
PIN 14 S 0.1072834 0.0375 0 U U
CT
OB 0.1268834 0.0287 I
OS 0.0876834 0.0287
OC 0.0876834 0.0463 0.0876834 0.0375 Y
OS 0.1268834 0.0463
OC 0.1268834 0.0287 0.1268834 0.0375 Y
OE
CE
PIN 15 S 0.1072834 0.0625 0 U U
CT
OB 0.1268834 0.0537 I
OS 0.0876834 0.0537
OC 0.0876834 0.0713 0.0876834 0.0625 Y
OS 0.1268834 0.0713
OC 0.1268834 0.0537 0.1268834 0.0625 Y
OE
CE
PIN 16 S 0.1072834 0.0875 0 U U
CT
OB 0.1268834 0.0787 I
OS 0.0876834 0.0787
OC 0.0876834 0.0963 0.0876834 0.0875 Y
OS 0.1268834 0.0963
OC 0.1268834 0.0787 0.1268834 0.0875 Y
OE
CE
#
# PKG 33
PKG SOT65P210X110-3N 0.0511811 -0.0620078 -0.0433121 0.0620079 0.0432991
CT
OB 0.0392002 -0.0433121 I
OS -0.0491902 -0.0433121
OS -0.0491902 0.0432991
OS 0.0392002 0.0432991
OS 0.0392002 -0.0433121
OE
CE
PIN 1 S -0.0442913 0.0255906 0 U U
CT
OB -0.0619913 0.0157906 I
OS -0.0619913 0.0353906
OS -0.0265913 0.0353906
OS -0.0265913 0.0157906
OS -0.0619913 0.0157906
OE
CE
PIN 2 S -0.0442913 -0.0255905 0 U U
CT
OB -0.0619913 -0.0353905 I
OS -0.0619913 -0.0157905
OS -0.0265913 -0.0157905
OS -0.0265913 -0.0353905
OS -0.0619913 -0.0353905
OE
CE
PIN 3 S 0.0442914 0 0 U U
CT
OB 0.0265914 -0.0098 I
OS 0.0265914 0.0098
OS 0.0619914 0.0098
OS 0.0619914 -0.0098
OS 0.0265914 -0.0098
OE
CE
#
# PKG 34
PKG U.FL_UMCC_JACK 0.0835282 -0.0787402 -0.0807087 0.0787402 0.061024
CT
OB 0.0590528 -0.061024 I
OS -0.0590592 -0.061024
OS -0.0590592 0.061024
OS 0.0590528 0.061024
OS 0.0590528 -0.061024
OE
CE
PIN 1 S 0 -0.0600394 0 U U
CT
OB -0.01968505 -0.0393701 I
OS 0.01968505 -0.0393701
OS 0.01968505 -0.0807087
OS -0.01968505 -0.0807087
OS -0.01968505 -0.0393701
OE
CE
PIN 2 S -0.0580709 0 0 U U
CT
OB -0.0787402 0.0433071 I
OS -0.0374016 0.0433071
OS -0.0374016 -0.0433071
OS -0.0787402 -0.0433071
OS -0.0787402 0.0433071
OE
CE
PIN 3 S 0.0580709 0 0 U U
CT
OB 0.0374016 0.0433071 I
OS 0.0787402 0.0433071
OS 0.0787402 -0.0433071
OS 0.0374016 -0.0433071
OS 0.0374016 0.0433071
OE
CE
#
# PKG 35
PKG USB_1734035 0.031496 -0.1515749 -0.3346457 0.2775591 0.0452756
CT
OB 0.2588582 -0.3346457 I
OS -0.1309082 -0.3346457
OS -0.1309082 0.0275591
OS 0.2588582 0.0275591
OS 0.2588582 -0.3346457
OE
CE
PIN 0 T 0.1496063 -0.1023622 0 U U
CR 0.1496063 -0.1023622 0.01574805
PIN 0 T -0.0236221 -0.1023622 0 U U
CR -0.0236221 -0.1023622 0.01574805
PIN 0 S 0.238189 -0.2204724 0 U U
CT
OB 0.1988189 -0.1712598 I
OS 0.2775591 -0.1712598
OS 0.2775591 -0.269685
OS 0.1988189 -0.269685
OS 0.1988189 -0.1712598
OE
CE
PIN 0 S 0.238189 -0.003937 0 U U
CT
OB 0.1988189 0.0452756 I
OS 0.2775591 0.0452756
OS 0.2775591 -0.0531496
OS 0.1988189 -0.0531496
OS 0.1988189 0.0452756
OE
CE
PIN 0 S -0.1122048 -0.003937 0 U U
CT
OB -0.1515749 0.0452756 I
OS -0.0728347 0.0452756
OS -0.0728347 -0.0531496
OS -0.1515749 -0.0531496
OS -0.1515749 0.0452756
OE
CE
PIN 0 S -0.1122048 -0.2204724 0 U U
CT
OB -0.1515749 -0.1712598 I
OS -0.0728347 -0.1712598
OS -0.0728347 -0.269685
OS -0.1515749 -0.269685
OS -0.1515749 -0.1712598
OE
CE
PIN 1 S 0 0 0 U U
CT
OB -0.0098425 0.0452756 I
OS 0.0098425 0.0452756
OS 0.0098425 -0.0452756
OS -0.0098425 -0.0452756
OS -0.0098425 0.0452756
OE
CE
PIN 2 S 0.031496 0 0 U U
CT
OB 0.0216535 0.0452756 I
OS 0.0413385 0.0452756
OS 0.0413385 -0.0452756
OS 0.0216535 -0.0452756
OS 0.0216535 0.0452756
OE
CE
PIN 3 S 0.0629921 0 0 U U
CT
OB 0.0531496 0.0452756 I
OS 0.0728346 0.0452756
OS 0.0728346 -0.0452756
OS 0.0531496 -0.0452756
OS 0.0531496 0.0452756
OE
CE
PIN 4 S 0.0944882 0 0 U U
CT
OB 0.0846457 0.0452756 I
OS 0.1043307 0.0452756
OS 0.1043307 -0.0452756
OS 0.0846457 -0.0452756
OS 0.0846457 0.0452756
OE
CE
PIN 5 S 0.1259842 0 0 U U
CT
OB 0.1161417 0.0452756 I
OS 0.1358267 0.0452756
OS 0.1358267 -0.0452756
OS 0.1161417 -0.0452756
OS 0.1161417 0.0452756
OE
CE
#
# PKG 36
PKG USB_47346-1001 0.0255905 -0.1141732 -0.187001 0.2165354 0.0271653
CT
OB 0.2047299 -0.187001 I
OS -0.1023549 -0.187001
OS -0.1023549 0.009847
OS 0.2047299 0.009847
OS 0.2047299 -0.187001
OE
CE
PIN 0 S 0.1840551 -0.1047244 0 U U
CT
OB 0.1515748 -0.07913385 I
OS 0.2165354 -0.07913385
OS 0.2165354 -0.13031495
OS 0.1515748 -0.13031495
OS 0.1515748 -0.07913385
OE
CE
PIN 0 S -0.0816929 -0.1047244 0 U U
CT
OB -0.1141732 -0.07913385 I
OS -0.0492126 -0.07913385
OS -0.0492126 -0.13031495
OS -0.1141732 -0.13031495
OS -0.1141732 -0.07913385
OE
CE
PIN 0 S -0.0472441 -0.0033465 0 U U
CT
OB -0.07519685 0.0271653 I
OS -0.01929135 0.0271653
OS -0.01929135 -0.0338583
OS -0.07519685 -0.0338583
OS -0.07519685 0.0271653
OE
CE
PIN 0 S 0.1496063 -0.0033465 0 U U
CT
OB 0.12165355 0.0271653 I
OS 0.17755905 0.0271653
OS 0.17755905 -0.0338583
OS 0.12165355 -0.0338583
OS 0.12165355 0.0271653
OE
CE
PIN 0 S 0.0059055 -0.1047244 0 U U
CT
OB -0.02952755 -0.06732285 I
OS 0.04133855 -0.06732285
OS 0.04133855 -0.14212595
OS -0.02952755 -0.14212595
OS -0.02952755 -0.06732285
OE
CE
PIN 0 S 0.1122047 -0.1047244 0 U U
CT
OB 0.09251965 -0.06732285 I
OS 0.13188975 -0.06732285
OS 0.13188975 -0.14212595
OS 0.09251965 -0.14212595
OS 0.09251965 -0.06732285
OE
CE
PIN 1 S 0 0 0 U U
CT
OB -0.00885825 0.02716535 I
OS 0.00885825 0.02716535
OS 0.00885825 -0.02716535
OS -0.00885825 -0.02716535
OS -0.00885825 0.02716535
OE
CE
PIN 2 S 0.0255905 0 0 U U
CT
OB 0.01673225 0.02716535 I
OS 0.03444875 0.02716535
OS 0.03444875 -0.02716535
OS 0.01673225 -0.02716535
OS 0.01673225 0.02716535
OE
CE
PIN 3 S 0.0511811 0 0 U U
CT
OB 0.04232285 0.02716535 I
OS 0.06003935 0.02716535
OS 0.06003935 -0.02716535
OS 0.04232285 -0.02716535
OS 0.04232285 0.02716535
OE
CE
PIN 4 S 0.0767717 0 0 U U
CT
OB 0.06791345 0.02716535 I
OS 0.08562995 0.02716535
OS 0.08562995 -0.02716535
OS 0.06791345 -0.02716535
OS 0.06791345 0.02716535
OE
CE
PIN 5 S 0.1023622 0 0 U U
CT
OB 0.09350395 0.02716535 I
OS 0.11122045 0.02716535
OS 0.11122045 -0.02716535
OS 0.09350395 -0.02716535
OS 0.09350395 0.02716535
OE
CE
#
# PKG 37
PKG W16-H2_L 0.05 -0.2165354 -0.2066929 0.2165355 0.2066929
CT
OB 0.1496064 -0.2066929 I
OS -0.1496062 -0.2066929
OS -0.1496062 0.2066929
OS 0.1496064 0.2066929
OS 0.1496064 -0.2066929
OE
CE
PIN 1 S -0.1771653 0.175 0 U U
CT
OB -0.1496653 0.1632 I
OS -0.2046653 0.1632
OC -0.2046653 0.1868 -0.2046653 0.175 Y
OS -0.1496653 0.1868
OC -0.1496653 0.1632 -0.1496653 0.175 Y
OE
CE
PIN 2 S -0.1771653 0.125 0 U U
CT
OB -0.1496653 0.1132 I
OS -0.2046653 0.1132
OC -0.2046653 0.1368 -0.2046653 0.125 Y
OS -0.1496653 0.1368
OC -0.1496653 0.1132 -0.1496653 0.125 Y
OE
CE
PIN 3 S -0.1771653 0.075 0 U U
CT
OB -0.1496653 0.0632 I
OS -0.2046653 0.0632
OC -0.2046653 0.0868 -0.2046653 0.075 Y
OS -0.1496653 0.0868
OC -0.1496653 0.0632 -0.1496653 0.075 Y
OE
CE
PIN 4 S -0.1771653 0.025 0 U U
CT
OB -0.1496653 0.0132 I
OS -0.2046653 0.0132
OC -0.2046653 0.0368 -0.2046653 0.025 Y
OS -0.1496653 0.0368
OC -0.1496653 0.0132 -0.1496653 0.025 Y
OE
CE
PIN 5 S -0.1771653 -0.025 0 U U
CT
OB -0.1496653 -0.0368 I
OS -0.2046653 -0.0368
OC -0.2046653 -0.0132 -0.2046653 -0.025 Y
OS -0.1496653 -0.0132
OC -0.1496653 -0.0368 -0.1496653 -0.025 Y
OE
CE
PIN 6 S -0.1771653 -0.075 0 U U
CT
OB -0.1496653 -0.0868 I
OS -0.2046653 -0.0868
OC -0.2046653 -0.0632 -0.2046653 -0.075 Y
OS -0.1496653 -0.0632
OC -0.1496653 -0.0868 -0.1496653 -0.075 Y
OE
CE
PIN 7 S -0.1771653 -0.125 0 U U
CT
OB -0.1496653 -0.1368 I
OS -0.2046653 -0.1368
OC -0.2046653 -0.1132 -0.2046653 -0.125 Y
OS -0.1496653 -0.1132
OC -0.1496653 -0.1368 -0.1496653 -0.125 Y
OE
CE
PIN 8 S -0.1771653 -0.175 0 U U
CT
OB -0.1496653 -0.1868 I
OS -0.2046653 -0.1868
OC -0.2046653 -0.1632 -0.2046653 -0.175 Y
OS -0.1496653 -0.1632
OC -0.1496653 -0.1868 -0.1496653 -0.175 Y
OE
CE
PIN 9 S 0.1771654 -0.175 0 U U
CT
OB 0.2046654 -0.1868 I
OS 0.1496654 -0.1868
OC 0.1496654 -0.1632 0.1496654 -0.175 Y
OS 0.2046654 -0.1632
OC 0.2046654 -0.1868 0.2046654 -0.175 Y
OE
CE
PIN 10 S 0.1771654 -0.125 0 U U
CT
OB 0.2046654 -0.1368 I
OS 0.1496654 -0.1368
OC 0.1496654 -0.1132 0.1496654 -0.125 Y
OS 0.2046654 -0.1132
OC 0.2046654 -0.1368 0.2046654 -0.125 Y
OE
CE
PIN 11 S 0.1771654 -0.075 0 U U
CT
OB 0.2046654 -0.0868 I
OS 0.1496654 -0.0868
OC 0.1496654 -0.0632 0.1496654 -0.075 Y
OS 0.2046654 -0.0632
OC 0.2046654 -0.0868 0.2046654 -0.075 Y
OE
CE
PIN 12 S 0.1771654 -0.025 0 U U
CT
OB 0.2046654 -0.0368 I
OS 0.1496654 -0.0368
OC 0.1496654 -0.0132 0.1496654 -0.025 Y
OS 0.2046654 -0.0132
OC 0.2046654 -0.0368 0.2046654 -0.025 Y
OE
CE
PIN 13 S 0.1771654 0.025 0 U U
CT
OB 0.2046654 0.0132 I
OS 0.1496654 0.0132
OC 0.1496654 0.0368 0.1496654 0.025 Y
OS 0.2046654 0.0368
OC 0.2046654 0.0132 0.2046654 0.025 Y
OE
CE
PIN 14 S 0.1771654 0.075 0 U U
CT
OB 0.2046654 0.0632 I
OS 0.1496654 0.0632
OC 0.1496654 0.0868 0.1496654 0.075 Y
OS 0.2046654 0.0868
OC 0.2046654 0.0632 0.2046654 0.075 Y
OE
CE
PIN 15 S 0.1771654 0.125 0 U U
CT
OB 0.2046654 0.1132 I
OS 0.1496654 0.1132
OC 0.1496654 0.1368 0.1496654 0.125 Y
OS 0.2046654 0.1368
OC 0.2046654 0.1132 0.2046654 0.125 Y
OE
CE
PIN 16 S 0.1771654 0.175 0 U U
CT
OB 0.2046654 0.1632 I
OS 0.1496654 0.1632
OC 0.1496654 0.1868 0.1496654 0.175 Y
OS 0.2046654 0.1868
OC 0.2046654 0.1632 0.2046654 0.175 Y
OE
CE
#
FGR TEXT
# FGR 0
PRP string '1'
FID C 7 889
FID C 7 887
FID C 7 888
FID C 7 929
#
FGR TEXT
# FGR 1
PRP string '1'
FID C 7 1608
FID C 7 1592
FID C 7 1597
FID C 7 1596
#
FGR TEXT
# FGR 2
PRP string '1'
FID C 7 1315
FID C 7 1326
FID C 7 1322
FID C 7 1323
#
FGR TEXT
# FGR 3
PRP string '2'
FID C 7 819
FID C 7 793
FID C 7 820
FID C 7 821
FID C 7 818
FID C 7 801
#
FGR TEXT
# FGR 4
PRP string '3'
FID C 7 664
FID C 7 671
FID C 7 676
FID C 7 680
FID C 7 679
FID C 7 674
FID C 7 672
FID C 7 675
FID C 7 678
FID C 7 677
FID C 7 673
FID C 7 670
#
FGR TEXT
# FGR 5
PRP string '4'
FID C 7 816
FID C 7 817
FID C 7 792
#
FGR TEXT
# FGR 6
PRP string 'IC?'
FID C 7 1177
FID C 7 1189
FID C 7 1181
FID C 7 1180
FID C 7 1176
FID C 7 1204
FID C 7 1199
FID C 7 1196
FID C 7 1192
FID C 7 1191
FID C 7 1195
FID C 7 1198
FID C 7 1207
FID C 7 1208
FID C 7 1214
FID C 7 1218
FID C 7 1217
FID C 7 1209
#
FGR TEXT
# FGR 7
PRP string 'R36'
FID C 7 305
FID C 7 306
FID C 7 341
FID C 7 347
FID C 7 346
FID C 7 340
FID C 7 323
FID C 7 360
FID C 7 368
FID C 7 385
FID C 7 395
FID C 7 394
FID C 7 383
FID C 7 371
FID C 7 384
FID C 7 393
FID C 7 392
FID C 7 382
FID C 7 367
FID C 7 445
FID C 7 425
FID C 7 406
FID C 7 405
FID C 7 419
FID C 7 435
FID C 7 443
FID C 7 444
FID C 7 436
#
FGR TEXT
# FGR 8
PRP string 'JP2'
FID C 7 726
FID C 7 724
FID C 7 725
FID C 7 758
FID C 7 762
FID C 7 761
FID C 7 763
FID C 7 727
FID C 7 728
FID C 7 732
FID C 7 748
FID C 7 753
FID C 7 765
FID C 7 764
FID C 7 739
FID C 7 733
FID C 7 730
FID C 7 729
#
FGR TEXT
# FGR 9
PRP string 'JP1'
FID C 7 584
FID C 7 581
FID C 7 583
FID C 7 582
FID C 7 580
FID C 7 577
FID C 7 585
FID C 7 586
FID C 7 590
FID C 7 592
FID C 7 591
FID C 7 589
FID C 7 593
FID C 7 596
FID C 7 594
FID C 7 595
#
FGR TEXT
# FGR 10
PRP string 'R16'
FID C 7 476
FID C 7 477
FID C 7 480
FID C 7 482
FID C 7 481
FID C 7 479
FID C 7 478
FID C 7 487
FID C 7 496
FID C 7 490
FID C 7 491
FID C 7 517
FID C 7 512
FID C 7 504
FID C 7 503
FID C 7 509
FID C 7 513
FID C 7 515
FID C 7 516
FID C 7 514
#
FGR TEXT
# FGR 11
PRP string 'R15'
FID C 7 483
FID C 7 484
FID C 7 493
FID C 7 498
FID C 7 497
FID C 7 492
FID C 7 488
FID C 7 501
FID C 7 510
FID C 7 505
FID C 7 506
FID C 7 529
FID C 7 519
FID C 7 518
FID C 7 522
FID C 7 524
FID C 7 528
FID C 7 527
FID C 7 523
FID C 7 521
#
FGR TEXT
# FGR 12
PRP string 'R14'
FID C 7 485
FID C 7 486
FID C 7 495
FID C 7 500
FID C 7 499
FID C 7 494
FID C 7 489
FID C 7 502
FID C 7 511
FID C 7 507
FID C 7 508
FID C 7 525
FID C 7 526
FID C 7 520
#
FGR TEXT
# FGR 13
PRP string 'R17'
FID C 7 875
FID C 7 876
FID C 7 880
FID C 7 884
FID C 7 883
FID C 7 879
FID C 7 878
FID C 7 890
FID C 7 895
FID C 7 892
FID C 7 893
FID C 7 903
FID C 7 921
FID C 7 920
FID C 7 902
#
FGR TEXT
# FGR 14
PRP string 'U3'
FID C 7 1035
FID C 7 1034
FID C 7 1036
FID C 7 1037
FID C 7 1039
FID C 7 1045
FID C 7 1049
FID C 7 1057
FID C 7 1063
FID C 7 1062
FID C 7 1055
FID C 7 1053
FID C 7 1056
FID C 7 1061
FID C 7 1060
FID C 7 1054
FID C 7 1048
#
FGR TEXT
# FGR 15
PRP string 'U10AL'
FID C 7 1707
FID C 7 1706
FID C 7 1714
FID C 7 1739
FID C 7 1750
FID C 7 1773
FID C 7 1786
FID C 7 1777
FID C 7 1778
FID C 7 1793
FID C 7 1798
FID C 7 1803
FID C 7 1809
FID C 7 1808
FID C 7 1802
FID C 7 1797
FID C 7 1792
FID C 7 1819
FID C 7 1820
FID C 7 1837
FID C 7 1849
FID C 7 1847
FID C 7 1848
FID C 7 1856
FID C 7 1855
#
FGR TEXT
# FGR 16
PRP string 'BT1'
FID C 7 2028
FID C 7 2026
FID C 7 2038
FID C 7 2042
FID C 7 2043
FID C 7 2039
FID C 7 2027
FID C 7 2040
FID C 7 2044
FID C 7 2045
FID C 7 2041
FID C 7 2058
FID C 7 2086
FID C 7 2074
FID C 7 2100
FID C 7 2108
FID C 7 2102
FID C 7 2103
#
FGR TEXT
# FGR 17
PRP string 'C72'
FID C 7 1915
FID C 7 1903
FID C 7 1902
FID C 7 1914
FID C 7 1937
FID C 7 1944
FID C 7 1945
FID C 7 1904
FID C 7 1905
FID C 7 1916
FID C 7 1938
FID C 7 1947
FID C 7 1946
FID C 7 1926
FID C 7 1917
FID C 7 1907
FID C 7 1906
#
FGR TEXT
# FGR 18
PRP string 'C73'
FID C 7 1839
FID C 7 1828
FID C 7 1827
FID C 7 1838
FID C 7 1857
FID C 7 1865
FID C 7 1866
FID C 7 1829
FID C 7 1830
FID C 7 1840
FID C 7 1858
FID C 7 1841
FID C 7 1831
FID C 7 1832
FID C 7 1842
FID C 7 1844
FID C 7 1851
FID C 7 1850
FID C 7 1852
FID C 7 1853
FID C 7 1859
FID C 7 1868
FID C 7 1867
#
FGR TEXT
# FGR 19
PRP string 'C74'
FID C 7 1497
FID C 7 1493
FID C 7 1483
FID C 7 1480
FID C 7 1479
FID C 7 1482
FID C 7 1492
FID C 7 1507
FID C 7 1529
FID C 7 1528
FID C 7 1506
FID C 7 1558
FID C 7 1559
FID C 7 1538
#
FGR TEXT
# FGR 20
PRP string 'C75'
FID C 7 1614
FID C 7 1612
FID C 7 1610
FID C 7 1603
FID C 7 1602
FID C 7 1609
FID C 7 1611
FID C 7 1627
FID C 7 1633
FID C 7 1632
FID C 7 1626
FID C 7 1645
FID C 7 1637
FID C 7 1636
FID C 7 1639
FID C 7 1641
FID C 7 1644
FID C 7 1643
FID C 7 1640
FID C 7 1638
#
FGR TEXT
# FGR 21
PRP string 'C76'
FID C 7 1589
FID C 7 1584
FID C 7 1583
FID C 7 1588
FID C 7 1598
FID C 7 1604
FID C 7 1605
FID C 7 1585
FID C 7 1586
FID C 7 1590
FID C 7 1599
FID C 7 1587
FID C 7 1591
FID C 7 1593
FID C 7 1600
FID C 7 1606
FID C 7 1607
FID C 7 1601
FID C 7 1595
FID C 7 1594
#
FGR TEXT
# FGR 22
PRP string 'C77'
FID C 7 1622
FID C 7 1616
FID C 7 1615
FID C 7 1621
FID C 7 1629
FID C 7 1634
FID C 7 1635
FID C 7 1617
FID C 7 1618
FID C 7 1623
FID C 7 1630
FID C 7 1619
FID C 7 1620
FID C 7 1624
FID C 7 1631
#
FGR TEXT
# FGR 23
PRP string 'C78'
FID C 7 1655
FID C 7 1647
FID C 7 1646
FID C 7 1654
FID C 7 1666
FID C 7 1670
FID C 7 1671
FID C 7 1648
FID C 7 1649
FID C 7 1656
FID C 7 1667
FID C 7 1657
FID C 7 1650
FID C 7 1651
FID C 7 1658
FID C 7 1660
FID C 7 1663
FID C 7 1665
FID C 7 1669
FID C 7 1673
FID C 7 1672
FID C 7 1668
FID C 7 1664
FID C 7 1661
FID C 7 1659
FID C 7 1662
#
FGR TEXT
# FGR 24
PRP string 'C79'
FID C 7 1683
FID C 7 1676
FID C 7 1675
FID C 7 1682
FID C 7 1722
FID C 7 1731
FID C 7 1732
FID C 7 1677
FID C 7 1678
FID C 7 1684
FID C 7 1723
FID C 7 1724
FID C 7 1733
FID C 7 1734
FID C 7 1725
FID C 7 1686
FID C 7 1680
FID C 7 1679
FID C 7 1685
FID C 7 1694
FID C 7 1702
#
FGR TEXT
# FGR 25
PRP string 'C80'
FID C 7 1919
FID C 7 1909
FID C 7 1908
FID C 7 1918
FID C 7 1939
FID C 7 1948
FID C 7 1949
FID C 7 1920
FID C 7 1910
FID C 7 1911
FID C 7 1921
FID C 7 1928
FID C 7 1933
FID C 7 1935
FID C 7 1941
FID C 7 1951
FID C 7 1950
FID C 7 1940
FID C 7 1934
FID C 7 1931
FID C 7 1927
FID C 7 1932
FID C 7 1922
FID C 7 1912
FID C 7 1913
FID C 7 1923
FID C 7 1943
FID C 7 1953
FID C 7 1952
FID C 7 1942
#
FGR TEXT
# FGR 26
PRP string 'C81'
FID C 7 1963
FID C 7 1958
FID C 7 1957
FID C 7 1962
FID C 7 1975
FID C 7 1985
FID C 7 1986
FID C 7 1964
FID C 7 1959
FID C 7 1960
FID C 7 1965
FID C 7 1967
FID C 7 1970
FID C 7 1972
FID C 7 1977
FID C 7 1988
FID C 7 1987
FID C 7 1976
FID C 7 1971
FID C 7 1968
FID C 7 1966
FID C 7 1969
FID C 7 1989
FID C 7 1991
FID C 7 1990
FID C 7 1961
#
FGR TEXT
# FGR 27
PRP string 'C82'
FID C 7 2007
FID C 7 1999
FID C 7 1998
FID C 7 2006
FID C 7 2029
FID C 7 2032
FID C 7 2033
FID C 7 2008
FID C 7 2000
FID C 7 2001
FID C 7 2009
FID C 7 2013
FID C 7 2018
FID C 7 2022
FID C 7 2031
FID C 7 2035
FID C 7 2034
FID C 7 2030
FID C 7 2021
FID C 7 2016
FID C 7 2012
FID C 7 2017
FID C 7 2037
FID C 7 2036
FID C 7 2014
FID C 7 2010
FID C 7 2003
FID C 7 2002
#
FGR TEXT
# FGR 28
PRP string 'C83'
FID C 7 2053
FID C 7 2047
FID C 7 2046
FID C 7 2052
FID C 7 2082
FID C 7 2093
FID C 7 2094
FID C 7 2054
FID C 7 2048
FID C 7 2049
FID C 7 2055
FID C 7 2060
FID C 7 2070
FID C 7 2078
FID C 7 2084
FID C 7 2096
FID C 7 2095
FID C 7 2083
FID C 7 2077
FID C 7 2068
FID C 7 2059
FID C 7 2069
FID C 7 2056
FID C 7 2050
FID C 7 2051
FID C 7 2057
FID C 7 2061
FID C 7 2072
FID C 7 2071
FID C 7 2073
FID C 7 2079
FID C 7 2085
FID C 7 2098
FID C 7 2097
#
FGR TEXT
# FGR 29
PRP string 'C84'
FID C 7 1799
FID C 7 1795
FID C 7 1791
FID C 7 1789
FID C 7 1788
FID C 7 1790
FID C 7 1794
FID C 7 1807
FID C 7 1815
FID C 7 1824
FID C 7 1836
FID C 7 1835
FID C 7 1823
FID C 7 1834
FID C 7 1833
FID C 7 1822
FID C 7 1812
FID C 7 1804
FID C 7 1805
FID C 7 1813
FID C 7 1806
FID C 7 1814
FID C 7 1860
FID C 7 1861
FID C 7 1845
#
FGR TEXT
# FGR 30
PRP string 'C85'
FID C 7 2833
FID C 7 2824
FID C 7 2815
FID C 7 2807
FID C 7 2806
FID C 7 2814
FID C 7 2823
FID C 7 2848
FID C 7 2858
FID C 7 2871
FID C 7 2876
FID C 7 2875
FID C 7 2870
FID C 7 2874
FID C 7 2873
FID C 7 2869
FID C 7 2855
FID C 7 2845
FID C 7 2846
FID C 7 2856
FID C 7 2847
FID C 7 2857
FID C 7 2898
FID C 7 2878
FID C 7 2877
FID C 7 2881
FID C 7 2889
FID C 7 2897
FID C 7 2896
FID C 7 2888
FID C 7 2880
#
FGR TEXT
# FGR 31
PRP string 'C86'
FID C 7 2775
FID C 7 2770
FID C 7 2764
FID C 7 2760
FID C 7 2759
FID C 7 2763
FID C 7 2769
FID C 7 2781
FID C 7 2787
FID C 7 2796
FID C 7 2811
FID C 7 2810
FID C 7 2795
FID C 7 2809
FID C 7 2808
FID C 7 2794
FID C 7 2784
FID C 7 2778
FID C 7 2779
FID C 7 2785
FID C 7 2780
FID C 7 2786
FID C 7 2852
FID C 7 2834
FID C 7 2822
FID C 7 2821
FID C 7 2828
FID C 7 2842
FID C 7 2850
FID C 7 2851
FID C 7 2843
#
FGR TEXT
# FGR 32
PRP string 'C91'
FID C 7 717
FID C 7 712
FID C 7 711
FID C 7 716
FID C 7 734
FID C 7 740
FID C 7 741
FID C 7 735
FID C 7 742
FID C 7 743
FID C 7 736
FID C 7 719
FID C 7 714
FID C 7 713
FID C 7 718
FID C 7 722
FID C 7 723
FID C 7 744
FID C 7 746
FID C 7 745
FID C 7 715
#
FGR TEXT
# FGR 33
PRP string 'C92'
FID C 7 607
FID C 7 606
FID C 7 604
FID C 7 601
FID C 7 600
FID C 7 603
FID C 7 605
FID C 7 608
FID C 7 611
FID C 7 621
FID C 7 623
FID C 7 624
FID C 7 622
FID C 7 613
FID C 7 610
FID C 7 609
FID C 7 612
FID C 7 648
FID C 7 630
FID C 7 649
FID C 7 650
FID C 7 647
FID C 7 635
#
FGR TEXT
# FGR 34
PRP string 'R42'
FID C 7 1253
FID C 7 1254
FID C 7 1257
FID C 7 1263
FID C 7 1262
FID C 7 1256
FID C 7 1255
FID C 7 1278
FID C 7 1279
FID C 7 1269
FID C 7 1308
FID C 7 1294
FID C 7 1309
FID C 7 1310
FID C 7 1305
FID C 7 1298
#
FGR TEXT
# FGR 35
PRP string 'R43'
FID C 7 702
FID C 7 703
FID C 7 706
FID C 7 709
FID C 7 708
FID C 7 705
FID C 7 704
FID C 7 720
FID C 7 721
FID C 7 710
FID C 7 731
FID C 7 738
FID C 7 752
FID C 7 757
FID C 7 756
FID C 7 750
FID C 7 747
FID C 7 751
FID C 7 755
FID C 7 754
FID C 7 749
FID C 7 737
#
FGR TEXT
# FGR 36
PRP string 'U16'
FID C 7 614
FID C 7 631
FID C 7 636
FID C 7 637
FID C 7 632
FID C 7 638
FID C 7 640
FID C 7 639
FID C 7 615
FID C 7 616
FID C 7 617
FID C 7 625
FID C 7 633
FID C 7 641
FID C 7 642
FID C 7 634
FID C 7 629
FID C 7 626
#
FGR TEXT
# FGR 37
PRP string 'J4'
FID C 7 942
FID C 7 939
FID C 7 941
FID C 7 940
FID C 7 938
FID C 7 937
FID C 7 944
FID C 7 945
FID C 7 943
#
FGR TEXT
# FGR 38
PRP string 'R5'
FID C 7 2435
FID C 7 2411
FID C 7 2412
FID C 7 2416
FID C 7 2421
FID C 7 2428
FID C 7 2427
FID C 7 2414
FID C 7 2413
FID C 7 2422
FID C 7 2418
FID C 7 2419
FID C 7 2423
FID C 7 2430
FID C 7 2437
FID C 7 2436
#
FGR TEXT
# FGR 39
PRP string 'X1'
FID C 7 3092
FID C 7 3095
FID C 7 3100
FID C 7 3104
FID C 7 3101
FID C 7 3102
#
FGR TEXT
# FGR 40
PRP string 'U13'
FID C 7 1342
FID C 7 1341
FID C 7 1348
FID C 7 1356
FID C 7 1365
FID C 7 1369
FID C 7 1382
FID C 7 1374
FID C 7 1375
FID C 7 1386
FID C 7 1390
FID C 7 1400
FID C 7 1406
FID C 7 1405
FID C 7 1398
FID C 7 1395
FID C 7 1399
FID C 7 1404
FID C 7 1403
FID C 7 1397
FID C 7 1389
#
FGR TEXT
# FGR 41
PRP string 'U11'
FID C 7 1164
FID C 7 1163
FID C 7 1167
FID C 7 1173
FID C 7 1174
FID C 7 1175
FID C 7 1182
FID C 7 1178
FID C 7 1179
FID C 7 1190
FID C 7 1197
FID C 7 1193
FID C 7 1194
#
FGR TEXT
# FGR 42
PRP string 'U10'
FID C 7 2290
FID C 7 2289
FID C 7 2294
FID C 7 2295
FID C 7 2296
FID C 7 2297
FID C 7 2300
FID C 7 2298
FID C 7 2299
FID C 7 2302
FID C 7 2304
FID C 7 2306
FID C 7 2308
FID C 7 2307
FID C 7 2305
FID C 7 2303
FID C 7 2301
#
FGR TEXT
# FGR 43
PRP string 'U9'
FID C 7 882
FID C 7 881
FID C 7 885
FID C 7 891
FID C 7 894
FID C 7 896
FID C 7 899
FID C 7 904
FID C 7 912
FID C 7 913
FID C 7 905
FID C 7 901
FID C 7 898
FID C 7 897
FID C 7 900
#
FGR TEXT
# FGR 44
PRP string 'U8'
FID C 7 2672
FID C 7 2671
FID C 7 2676
FID C 7 2680
FID C 7 2685
FID C 7 2693
FID C 7 2697
FID C 7 2701
FID C 7 2705
FID C 7 2704
FID C 7 2700
FID C 7 2703
FID C 7 2702
FID C 7 2699
FID C 7 2694
FID C 7 2690
FID C 7 2691
FID C 7 2695
FID C 7 2692
FID C 7 2696
#
FGR TEXT
# FGR 45
PRP string 'U6'
FID C 7 1557
FID C 7 1556
FID C 7 1560
FID C 7 1564
FID C 7 1566
FID C 7 1580
FID C 7 1575
FID C 7 1573
FID C 7 1572
FID C 7 1574
FID C 7 1576
FID C 7 1578
FID C 7 1579
FID C 7 1577
#
FGR TEXT
# FGR 46
PRP string 'U5'
FID C 7 948
FID C 7 947
FID C 7 949
FID C 7 950
FID C 7 951
FID C 7 964
FID C 7 953
FID C 7 952
FID C 7 956
FID C 7 958
FID C 7 963
FID C 7 962
FID C 7 957
FID C 7 955
#
FGR TEXT
# FGR 47
PRP string 'U2'
FID C 7 2353
FID C 7 2352
FID C 7 2358
FID C 7 2361
FID C 7 2362
FID C 7 2379
FID C 7 2363
FID C 7 2380
FID C 7 2381
FID C 7 2377
FID C 7 2370
#
FGR TEXT
# FGR 48
PRP string 'U1'
FID C 7 2748
FID C 7 2747
FID C 7 2749
FID C 7 2753
FID C 7 2758
FID C 7 2765
FID C 7 2772
FID C 7 2767
FID C 7 2768
#
FGR TEXT
# FGR 49
PRP string 'SW1'
FID C 7 2269
FID C 7 2266
FID C 7 2263
FID C 7 2256
FID C 7 2255
FID C 7 2262
FID C 7 2265
FID C 7 2268
FID C 7 2267
FID C 7 2264
FID C 7 2261
FID C 7 2271
FID C 7 2270
FID C 7 2272
FID C 7 2273
FID C 7 2274
FID C 7 2277
FID C 7 2275
FID C 7 2276
#
FGR TEXT
# FGR 50
PRP string 'S6'
FID C 7 2179
FID C 7 2176
FID C 7 2173
FID C 7 2166
FID C 7 2165
FID C 7 2172
FID C 7 2175
FID C 7 2178
FID C 7 2177
FID C 7 2174
FID C 7 2171
FID C 7 2188
FID C 7 2183
FID C 7 2181
FID C 7 2180
FID C 7 2182
FID C 7 2184
FID C 7 2186
FID C 7 2187
FID C 7 2185
#
FGR TEXT
# FGR 51
PRP string 'S5'
FID C 7 1997
FID C 7 1994
FID C 7 1984
FID C 7 1974
FID C 7 1973
FID C 7 1983
FID C 7 1993
FID C 7 1996
FID C 7 1995
FID C 7 1992
FID C 7 1982
FID C 7 2025
FID C 7 2005
FID C 7 2004
FID C 7 2015
FID C 7 2020
FID C 7 2024
FID C 7 2023
FID C 7 2019
FID C 7 2011
#
FGR TEXT
# FGR 52
PRP string 'R35'
FID C 7 2191
FID C 7 2192
FID C 7 2197
FID C 7 2199
FID C 7 2198
FID C 7 2196
FID C 7 2193
FID C 7 2200
FID C 7 2202
FID C 7 2207
FID C 7 2211
FID C 7 2210
FID C 7 2205
FID C 7 2203
FID C 7 2206
FID C 7 2209
FID C 7 2208
FID C 7 2204
FID C 7 2201
FID C 7 2220
FID C 7 2213
FID C 7 2212
FID C 7 2215
FID C 7 2217
FID C 7 2219
FID C 7 2218
FID C 7 2216
FID C 7 2214
#
FGR TEXT
# FGR 53
PRP string 'R34'
FID C 7 2116
FID C 7 2117
FID C 7 2123
FID C 7 2127
FID C 7 2126
FID C 7 2122
FID C 7 2119
FID C 7 2129
FID C 7 2133
FID C 7 2145
FID C 7 2153
FID C 7 2152
FID C 7 2143
FID C 7 2137
FID C 7 2144
FID C 7 2151
FID C 7 2150
FID C 7 2142
FID C 7 2132
FID C 7 2158
FID C 7 2159
FID C 7 2155
#
FGR TEXT
# FGR 54
PRP string 'R33'
FID C 7 2221
FID C 7 2222
FID C 7 2225
FID C 7 2227
FID C 7 2226
FID C 7 2224
FID C 7 2223
FID C 7 2228
FID C 7 2231
FID C 7 2238
FID C 7 2242
FID C 7 2241
FID C 7 2236
FID C 7 2232
FID C 7 2237
FID C 7 2240
FID C 7 2239
FID C 7 2235
FID C 7 2230
FID C 7 2243
FID C 7 2245
FID C 7 2250
FID C 7 2254
FID C 7 2253
FID C 7 2248
FID C 7 2246
FID C 7 2249
FID C 7 2252
FID C 7 2251
FID C 7 2247
FID C 7 2244
#
FGR TEXT
# FGR 55
PRP string 'R32'
FID C 7 2114
FID C 7 2115
FID C 7 2121
FID C 7 2125
FID C 7 2124
FID C 7 2120
FID C 7 2118
FID C 7 2128
FID C 7 2131
FID C 7 2141
FID C 7 2149
FID C 7 2148
FID C 7 2139
FID C 7 2134
FID C 7 2140
FID C 7 2147
FID C 7 2146
FID C 7 2138
FID C 7 2130
FID C 7 2160
FID C 7 2154
FID C 7 2161
FID C 7 2162
FID C 7 2157
FID C 7 2156
#
FGR TEXT
# FGR 56
PRP string 'R31'
FID C 7 568
FID C 7 535
FID C 7 536
FID C 7 540
FID C 7 545
FID C 7 559
FID C 7 558
FID C 7 541
FID C 7 537
FID C 7 538
FID C 7 542
FID C 7 544
FID C 7 547
FID C 7 546
FID C 7 548
FID C 7 560
FID C 7 567
FID C 7 570
FID C 7 569
FID C 7 571
FID C 7 573
FID C 7 572
FID C 7 539
#
FGR TEXT
# FGR 57
PRP string 'R30'
FID C 7 470
FID C 7 426
FID C 7 427
FID C 7 437
FID C 7 450
FID C 7 456
FID C 7 455
FID C 7 438
FID C 7 428
FID C 7 429
FID C 7 439
FID C 7 446
FID C 7 452
FID C 7 451
FID C 7 453
FID C 7 457
FID C 7 460
FID C 7 472
FID C 7 471
FID C 7 440
FID C 7 430
FID C 7 431
FID C 7 441
FID C 7 462
FID C 7 474
FID C 7 473
FID C 7 461
#
FGR TEXT
# FGR 58
PRP string 'R29'
FID C 7 283
FID C 7 257
FID C 7 258
FID C 7 263
FID C 7 276
FID C 7 280
FID C 7 279
FID C 7 285
FID C 7 284
FID C 7 272
FID C 7 264
FID C 7 260
FID C 7 259
FID C 7 281
FID C 7 286
FID C 7 287
FID C 7 282
FID C 7 266
FID C 7 262
FID C 7 261
FID C 7 265
FID C 7 273
FID C 7 277
#
FGR TEXT
# FGR 59
PRP string 'R28'
FID C 7 203
FID C 7 162
FID C 7 163
FID C 7 172
FID C 7 188
FID C 7 193
FID C 7 192
FID C 7 205
FID C 7 204
FID C 7 185
FID C 7 173
FID C 7 165
FID C 7 164
FID C 7 174
FID C 7 166
FID C 7 167
FID C 7 175
FID C 7 187
FID C 7 191
FID C 7 195
FID C 7 197
FID C 7 207
FID C 7 206
FID C 7 196
FID C 7 194
FID C 7 189
FID C 7 186
FID C 7 190
#
FGR TEXT
# FGR 60
PRP string 'R27'
FID C 7 1800
FID C 7 1801
FID C 7 1818
FID C 7 1826
FID C 7 1825
FID C 7 1817
FID C 7 1816
FID C 7 1862
FID C 7 1843
FID C 7 1863
FID C 7 1864
FID C 7 1854
FID C 7 1846
FID C 7 1870
FID C 7 1889
FID C 7 1888
FID C 7 1869
#
FGR TEXT
# FGR 61
PRP string 'R26'
FID C 7 1446
FID C 7 1414
FID C 7 1415
FID C 7 1420
FID C 7 1431
FID C 7 1437
FID C 7 1436
FID C 7 1448
FID C 7 1447
FID C 7 1429
FID C 7 1421
FID C 7 1417
FID C 7 1416
FID C 7 1418
FID C 7 1422
FID C 7 1432
FID C 7 1442
FID C 7 1449
FID C 7 1450
FID C 7 1443
FID C 7 1438
FID C 7 1433
#
FGR TEXT
# FGR 62
PRP string 'R25'
FID C 7 1383
FID C 7 1384
FID C 7 1388
FID C 7 1394
FID C 7 1393
FID C 7 1387
FID C 7 1385
FID C 7 1425
FID C 7 1402
FID C 7 1426
FID C 7 1427
FID C 7 1419
FID C 7 1411
FID C 7 1458
FID C 7 1435
FID C 7 1434
FID C 7 1445
FID C 7 1453
FID C 7 1457
FID C 7 1456
FID C 7 1452
FID C 7 1441
#
FGR TEXT
# FGR 63
PRP string 'R24'
FID C 7 1112
FID C 7 1095
FID C 7 1096
FID C 7 1100
FID C 7 1107
FID C 7 1110
FID C 7 1109
FID C 7 1114
FID C 7 1113
FID C 7 1106
FID C 7 1101
FID C 7 1098
FID C 7 1097
FID C 7 1115
FID C 7 1099
FID C 7 1108
#
FGR TEXT
# FGR 64
PRP string 'R23'
FID C 7 931
FID C 7 906
FID C 7 907
FID C 7 914
FID C 7 922
FID C 7 927
FID C 7 926
FID C 7 933
FID C 7 932
FID C 7 918
FID C 7 915
FID C 7 909
FID C 7 908
FID C 7 916
FID C 7 910
FID C 7 911
FID C 7 917
FID C 7 919
FID C 7 924
FID C 7 923
FID C 7 925
FID C 7 928
FID C 7 930
FID C 7 935
FID C 7 934
#
FGR TEXT
# FGR 65
PRP string 'R22'
FID C 7 759
FID C 7 760
FID C 7 771
FID C 7 773
FID C 7 772
FID C 7 770
FID C 7 766
FID C 7 777
FID C 7 774
FID C 7 778
FID C 7 779
FID C 7 776
FID C 7 775
FID C 7 783
FID C 7 780
FID C 7 784
FID C 7 785
FID C 7 782
FID C 7 781
#
FGR TEXT
# FGR 66
PRP string 'R21'
FID C 7 1239
FID C 7 1228
FID C 7 1229
FID C 7 1233
FID C 7 1236
FID C 7 1238
FID C 7 1237
FID C 7 1241
FID C 7 1240
FID C 7 1235
FID C 7 1234
FID C 7 1231
FID C 7 1230
FID C 7 1242
FID C 7 1244
FID C 7 1243
FID C 7 1232
#
FGR TEXT
# FGR 67
PRP string 'R20'
FID C 7 1168
FID C 7 1149
FID C 7 1150
FID C 7 1155
FID C 7 1160
FID C 7 1162
FID C 7 1161
FID C 7 1170
FID C 7 1169
FID C 7 1159
FID C 7 1156
FID C 7 1152
FID C 7 1151
FID C 7 1157
FID C 7 1153
FID C 7 1154
FID C 7 1158
FID C 7 1166
FID C 7 1172
FID C 7 1171
FID C 7 1165
#
FGR TEXT
# FGR 68
PRP string 'R19'
FID C 7 1142
FID C 7 1124
FID C 7 1125
FID C 7 1131
FID C 7 1135
FID C 7 1139
FID C 7 1138
FID C 7 1143
FID C 7 1145
FID C 7 1144
FID C 7 1126
FID C 7 1140
FID C 7 1146
FID C 7 1147
FID C 7 1141
FID C 7 1133
FID C 7 1128
FID C 7 1127
FID C 7 1132
FID C 7 1134
FID C 7 1136
#
FGR TEXT
# FGR 69
PRP string 'R18'
FID C 7 1089
FID C 7 1069
FID C 7 1070
FID C 7 1074
FID C 7 1079
FID C 7 1084
FID C 7 1083
FID C 7 1090
FID C 7 1092
FID C 7 1091
FID C 7 1071
FID C 7 1075
FID C 7 1072
FID C 7 1073
FID C 7 1076
FID C 7 1078
FID C 7 1082
FID C 7 1086
FID C 7 1088
FID C 7 1094
FID C 7 1093
FID C 7 1087
FID C 7 1085
FID C 7 1080
FID C 7 1077
FID C 7 1081
#
FGR TEXT
# FGR 70
PRP string 'R9'
FID C 7 2355
FID C 7 2335
FID C 7 2336
FID C 7 2339
FID C 7 2343
FID C 7 2347
FID C 7 2346
FID C 7 2350
FID C 7 2356
FID C 7 2357
FID C 7 2351
FID C 7 2341
FID C 7 2338
FID C 7 2337
FID C 7 2340
FID C 7 2342
FID C 7 2344
#
FGR TEXT
# FGR 71
PRP string 'R8'
FID C 7 3131
FID C 7 3107
FID C 7 3108
FID C 7 3111
FID C 7 3121
FID C 7 3126
FID C 7 3125
FID C 7 3112
FID C 7 3109
FID C 7 3110
FID C 7 3113
FID C 7 3117
FID C 7 3124
FID C 7 3128
FID C 7 3130
FID C 7 3133
FID C 7 3132
FID C 7 3129
FID C 7 3127
FID C 7 3122
FID C 7 3116
FID C 7 3123
#
FGR TEXT
# FGR 72
PRP string 'R7'
FID C 7 2466
FID C 7 2467
FID C 7 2485
FID C 7 2492
FID C 7 2491
FID C 7 2484
FID C 7 2476
FID C 7 2512
FID C 7 2546
FID C 7 2545
FID C 7 2511
#
FGR TEXT
# FGR 73
PRP string 'R6'
FID C 7 2788
FID C 7 2789
FID C 7 2813
FID C 7 2817
FID C 7 2816
FID C 7 2812
FID C 7 2797
FID C 7 2864
FID C 7 2844
FID C 7 2830
FID C 7 2829
FID C 7 2835
FID C 7 2853
FID C 7 2862
FID C 7 2863
FID C 7 2854
#
FGR TEXT
# FGR 74
PRP string 'R4'
FID C 7 3026
FID C 7 3027
FID C 7 3035
FID C 7 3038
FID C 7 3037
FID C 7 3034
FID C 7 3033
FID C 7 3049
FID C 7 3050
FID C 7 3045
#
FGR TEXT
# FGR 75
PRP string 'R3'
FID C 7 2507
FID C 7 2508
FID C 7 2536
FID C 7 2542
FID C 7 2541
FID C 7 2535
FID C 7 2529
FID C 7 2555
FID C 7 2559
FID C 7 2573
FID C 7 2580
FID C 7 2579
FID C 7 2571
FID C 7 2563
FID C 7 2572
FID C 7 2578
FID C 7 2577
FID C 7 2570
FID C 7 2558
#
FGR TEXT
# FGR 76
PRP string 'R2'
FID C 7 2961
FID C 7 2909
FID C 7 2910
FID C 7 2920
FID C 7 2940
FID C 7 2947
FID C 7 2946
FID C 7 2963
FID C 7 2962
FID C 7 2934
FID C 7 2921
FID C 7 2912
FID C 7 2911
#
FGR TEXT
# FGR 77
PRP string 'R1'
FID C 7 1708
FID C 7 1709
FID C 7 1741
FID C 7 1752
FID C 7 1751
FID C 7 1740
FID C 7 1727
FID C 7 1774
FID C 7 1787
FID C 7 1779
FID C 7 1780
#
FGR TEXT
# FGR 78
PRP string 'P2'
FID C 7 687
FID C 7 688
FID C 7 691
FID C 7 693
FID C 7 692
FID C 7 690
FID C 7 699
FID C 7 696
FID C 7 700
FID C 7 701
FID C 7 698
FID C 7 697
#
FGR TEXT
# FGR 79
PRP string 'P1'
FID C 7 627
FID C 7 628
FID C 7 644
FID C 7 646
FID C 7 645
FID C 7 643
FID C 7 651
FID C 7 654
FID C 7 652
FID C 7 653
#
FGR TEXT
# FGR 80
PRP string 'L2'
FID C 7 3040
FID C 7 3039
FID C 7 3061
FID C 7 3054
FID C 7 3062
FID C 7 3063
FID C 7 3060
FID C 7 3055
#
FGR TEXT
# FGR 81
PRP string 'L1'
FID C 7 2333
FID C 7 2332
FID C 7 2345
FID C 7 2354
FID C 7 2348
FID C 7 2349
#
FGR TEXT
# FGR 82
PRP string 'J3'
FID C 7 1703
FID C 7 1688
FID C 7 1696
FID C 7 1695
FID C 7 1687
FID C 7 1681
FID C 7 1726
FID C 7 1736
FID C 7 1765
FID C 7 1771
FID C 7 1770
FID C 7 1763
FID C 7 1744
FID C 7 1764
FID C 7 1769
FID C 7 1768
FID C 7 1762
FID C 7 1735
#
FGR TEXT
# FGR 83
PRP string 'J2'
FID C 7 3091
FID C 7 3079
FID C 7 3084
FID C 7 3083
FID C 7 3078
FID C 7 3077
FID C 7 3097
FID C 7 3093
FID C 7 3098
FID C 7 3099
FID C 7 3096
FID C 7 3094
#
FGR TEXT
# FGR 84
PRP string 'J1'
FID C 7 2657
FID C 7 2646
FID C 7 2651
FID C 7 2650
FID C 7 2645
FID C 7 2635
FID C 7 2665
FID C 7 2674
FID C 7 2669
FID C 7 2670
#
FGR TEXT
# FGR 85
PRP string 'FB3'
FID C 7 1717
FID C 7 1716
FID C 7 1753
FID C 7 1755
FID C 7 1754
FID C 7 1718
FID C 7 1781
FID C 7 1782
FID C 7 1775
FID C 7 1766
FID C 7 1758
FID C 7 1756
FID C 7 1757
FID C 7 1742
FID C 7 1728
FID C 7 1719
FID C 7 1729
FID C 7 1720
FID C 7 1721
FID C 7 1730
FID C 7 1743
FID C 7 1760
FID C 7 1759
FID C 7 1761
FID C 7 1767
FID C 7 1776
FID C 7 1784
FID C 7 1783
#
FGR TEXT
# FGR 86
PRP string 'FB2'
FID C 7 2063
FID C 7 2062
FID C 7 2087
FID C 7 2089
FID C 7 2088
FID C 7 2064
FID C 7 2104
FID C 7 2105
FID C 7 2101
FID C 7 2099
FID C 7 2092
FID C 7 2090
FID C 7 2091
FID C 7 2080
FID C 7 2075
FID C 7 2065
FID C 7 2107
FID C 7 2106
FID C 7 2081
FID C 7 2076
FID C 7 2067
FID C 7 2066
#
FGR TEXT
# FGR 87
PRP string 'F1'
FID C 7 2439
FID C 7 2426
FID C 7 2425
FID C 7 2434
FID C 7 2424
FID C 7 2443
FID C 7 2446
FID C 7 2444
FID C 7 2445
#
FGR TEXT
# FGR 88
PRP string 'D18'
FID C 7 298
FID C 7 297
FID C 7 307
FID C 7 315
FID C 7 316
FID C 7 308
FID C 7 342
FID C 7 356
FID C 7 348
FID C 7 349
FID C 7 375
FID C 7 389
FID C 7 400
FID C 7 410
FID C 7 409
FID C 7 399
FID C 7 408
FID C 7 407
FID C 7 398
FID C 7 386
FID C 7 372
FID C 7 373
FID C 7 387
FID C 7 374
FID C 7 388
#
FGR TEXT
# FGR 89
PRP string 'D17'
FID C 7 300
FID C 7 299
FID C 7 309
FID C 7 317
FID C 7 318
FID C 7 310
FID C 7 343
FID C 7 357
FID C 7 350
FID C 7 351
FID C 7 377
FID C 7 412
FID C 7 411
FID C 7 376
#
FGR TEXT
# FGR 90
PRP string 'D16'
FID C 7 304
FID C 7 303
FID C 7 313
FID C 7 321
FID C 7 322
FID C 7 314
FID C 7 345
FID C 7 359
FID C 7 354
FID C 7 355
FID C 7 418
FID C 7 397
FID C 7 381
FID C 7 380
FID C 7 391
FID C 7 403
FID C 7 416
FID C 7 417
FID C 7 404
#
FGR TEXT
# FGR 91
PRP string 'D15'
FID C 7 302
FID C 7 301
FID C 7 311
FID C 7 319
FID C 7 320
FID C 7 312
FID C 7 344
FID C 7 358
FID C 7 352
FID C 7 353
FID C 7 415
FID C 7 379
FID C 7 378
FID C 7 396
FID C 7 402
FID C 7 414
FID C 7 413
FID C 7 401
FID C 7 390
#
FGR TEXT
# FGR 92
PRP string 'D14'
FID C 7 530
FID C 7 561
FID C 7 562
FID C 7 557
FID C 7 534
FID C 7 531
FID C 7 563
FID C 7 565
FID C 7 564
FID C 7 532
FID C 7 566
FID C 7 533
FID C 7 543
#
FGR TEXT
# FGR 93
PRP string 'D13'
FID C 7 420
FID C 7 463
FID C 7 464
FID C 7 458
FID C 7 432
FID C 7 421
FID C 7 465
FID C 7 467
FID C 7 466
FID C 7 422
FID C 7 433
FID C 7 423
FID C 7 424
FID C 7 434
FID C 7 442
FID C 7 448
FID C 7 447
FID C 7 449
FID C 7 454
FID C 7 459
FID C 7 469
FID C 7 468
#
FGR TEXT
# FGR 94
PRP string 'D12'
FID C 7 267
FID C 7 289
FID C 7 290
FID C 7 288
FID C 7 274
FID C 7 268
FID C 7 291
FID C 7 293
FID C 7 292
FID C 7 269
FID C 7 295
FID C 7 294
FID C 7 278
FID C 7 275
FID C 7 271
FID C 7 270
#
FGR TEXT
# FGR 95
PRP string 'D11'
FID C 7 168
FID C 7 211
FID C 7 212
FID C 7 198
FID C 7 176
FID C 7 169
FID C 7 213
FID C 7 215
FID C 7 214
FID C 7 170
FID C 7 216
FID C 7 218
FID C 7 217
FID C 7 171
#
FGR TEXT
# FGR 96
PRP string 'D10'
FID C 7 1333
FID C 7 1358
FID C 7 1359
FID C 7 1353
FID C 7 1338
FID C 7 1334
FID C 7 1360
FID C 7 1362
FID C 7 1361
FID C 7 1335
FID C 7 1339
FID C 7 1336
FID C 7 1337
FID C 7 1340
FID C 7 1355
FID C 7 1364
FID C 7 1363
FID C 7 1354
#
FGR TEXT
# FGR 97
PRP string 'D9'
FID C 7 1344
FID C 7 1370
FID C 7 1371
FID C 7 1366
FID C 7 1349
FID C 7 1345
FID C 7 1367
FID C 7 1372
FID C 7 1373
FID C 7 1368
FID C 7 1351
FID C 7 1347
FID C 7 1346
FID C 7 1350
FID C 7 1352
FID C 7 1357
#
FGR TEXT
# FGR 98
PRP string 'D8'
FID C 7 1258
FID C 7 1284
FID C 7 1285
FID C 7 1275
FID C 7 1264
FID C 7 1259
FID C 7 1265
FID C 7 1260
FID C 7 1261
FID C 7 1266
FID C 7 1268
FID C 7 1272
FID C 7 1274
FID C 7 1277
FID C 7 1287
FID C 7 1286
FID C 7 1276
FID C 7 1273
FID C 7 1270
FID C 7 1267
FID C 7 1271
#
FGR TEXT
# FGR 99
PRP string 'D7'
FID C 7 1200
FID C 7 1215
FID C 7 1216
FID C 7 1212
FID C 7 1205
FID C 7 1201
FID C 7 1202
FID C 7 1203
FID C 7 1206
FID C 7 1213
#
FGR TEXT
# FGR 100
PRP string 'D6'
FID C 7 976
FID C 7 975
FID C 7 985
FID C 7 993
FID C 7 994
FID C 7 986
FID C 7 1007
FID C 7 1001
FID C 7 996
FID C 7 995
FID C 7 997
FID C 7 1003
FID C 7 1005
FID C 7 1006
FID C 7 1004
#
FGR TEXT
# FGR 101
PRP string 'D5'
FID C 7 1040
FID C 7 1064
FID C 7 1065
FID C 7 1058
FID C 7 1044
FID C 7 1041
FID C 7 1043
FID C 7 1042
FID C 7 1051
FID C 7 1046
FID C 7 1047
FID C 7 1052
FID C 7 1059
FID C 7 1067
FID C 7 1066
#
FGR TEXT
# FGR 102
PRP string 'D4'
FID C 7 1901
FID C 7 1900
FID C 7 1924
FID C 7 1929
FID C 7 1930
FID C 7 1925
FID C 7 1954
FID C 7 1955
FID C 7 1936
#
FGR TEXT
# FGR 103
PRP string 'D3'
FID C 7 2644
FID C 7 2643
FID C 7 2661
FID C 7 2663
FID C 7 2664
FID C 7 2662
FID C 7 2673
FID C 7 2678
FID C 7 2684
FID C 7 2689
FID C 7 2688
FID C 7 2682
FID C 7 2679
FID C 7 2683
FID C 7 2687
FID C 7 2686
FID C 7 2681
FID C 7 2677
#
FGR TEXT
# FGR 104
PRP string 'D2'
FID C 7 2496
FID C 7 2495
FID C 7 2530
FID C 7 2537
FID C 7 2538
FID C 7 2531
FID C 7 2574
FID C 7 2549
FID C 7 2575
FID C 7 2576
FID C 7 2564
FID C 7 2556
#
FGR TEXT
# FGR 105
PRP string 'D1'
FID C 7 2386
FID C 7 2385
FID C 7 2396
FID C 7 2400
FID C 7 2401
FID C 7 2397
FID C 7 2406
FID C 7 2415
FID C 7 2409
FID C 7 2410
#
FGR TEXT
# FGR 106
PRP string 'C67'
FID C 7 1430
FID C 7 1424
FID C 7 1413
FID C 7 1410
FID C 7 1409
FID C 7 1412
FID C 7 1423
FID C 7 1461
FID C 7 1451
FID C 7 1440
FID C 7 1439
FID C 7 1444
FID C 7 1454
FID C 7 1459
FID C 7 1460
FID C 7 1455
FID C 7 1465
FID C 7 1468
FID C 7 1467
FID C 7 1464
#
FGR TEXT
# FGR 107
PRP string 'C66'
FID C 7 1516
FID C 7 1510
FID C 7 1501
FID C 7 1495
FID C 7 1494
FID C 7 1500
FID C 7 1509
FID C 7 1551
FID C 7 1535
FID C 7 1526
FID C 7 1525
FID C 7 1531
FID C 7 1540
FID C 7 1549
FID C 7 1550
FID C 7 1541
FID C 7 1571
FID C 7 1565
FID C 7 1562
FID C 7 1561
FID C 7 1563
FID C 7 1567
FID C 7 1569
FID C 7 1570
FID C 7 1568
#
FGR TEXT
# FGR 108
PRP string 'C65'
FID C 7 1481
FID C 7 1478
FID C 7 1472
FID C 7 1470
FID C 7 1469
FID C 7 1471
FID C 7 1477
FID C 7 1513
FID C 7 1502
FID C 7 1491
FID C 7 1490
FID C 7 1496
FID C 7 1504
FID C 7 1511
FID C 7 1512
FID C 7 1505
FID C 7 1544
FID C 7 1521
FID C 7 1520
FID C 7 1532
FID C 7 1537
FID C 7 1543
FID C 7 1542
FID C 7 1536
FID C 7 1527
#
FGR TEXT
# FGR 109
PRP string 'C63'
FID C 7 1489
FID C 7 1485
FID C 7 1476
FID C 7 1474
FID C 7 1473
FID C 7 1475
FID C 7 1484
FID C 7 1519
FID C 7 1508
FID C 7 1499
FID C 7 1498
FID C 7 1503
FID C 7 1514
FID C 7 1517
FID C 7 1518
FID C 7 1515
FID C 7 1530
FID C 7 1534
FID C 7 1548
FID C 7 1555
FID C 7 1554
FID C 7 1546
FID C 7 1539
FID C 7 1547
FID C 7 1553
FID C 7 1552
FID C 7 1545
FID C 7 1533
#
FGR TEXT
# FGR 110
PRP string 'C62'
FID C 7 1300
FID C 7 1297
FID C 7 1292
FID C 7 1289
FID C 7 1288
FID C 7 1291
FID C 7 1296
FID C 7 1321
FID C 7 1312
FID C 7 1307
FID C 7 1306
FID C 7 1311
FID C 7 1313
FID C 7 1319
FID C 7 1320
FID C 7 1314
FID C 7 1330
FID C 7 1324
FID C 7 1331
FID C 7 1332
FID C 7 1329
FID C 7 1325
#
FGR TEXT
# FGR 111
PRP string 'C61'
FID C 7 1014
FID C 7 1010
FID C 7 1009
FID C 7 1013
FID C 7 1021
FID C 7 1024
FID C 7 1025
FID C 7 1011
FID C 7 1015
FID C 7 1016
FID C 7 1022
FID C 7 1026
FID C 7 1027
FID C 7 1023
FID C 7 1018
FID C 7 1017
FID C 7 1028
FID C 7 1030
FID C 7 1029
FID C 7 1012
#
FGR TEXT
# FGR 112
PRP string 'C60'
FID C 7 971
FID C 7 966
FID C 7 965
FID C 7 970
FID C 7 980
FID C 7 987
FID C 7 988
FID C 7 967
FID C 7 972
FID C 7 977
FID C 7 981
FID C 7 989
FID C 7 990
FID C 7 982
FID C 7 979
FID C 7 978
FID C 7 973
FID C 7 968
FID C 7 969
FID C 7 974
FID C 7 984
FID C 7 992
FID C 7 991
FID C 7 983
#
FGR TEXT
# FGR 113
PRP string 'C59'
FID C 7 795
FID C 7 787
FID C 7 786
FID C 7 794
FID C 7 805
FID C 7 810
FID C 7 811
FID C 7 789
FID C 7 788
FID C 7 802
FID C 7 798
FID C 7 799
FID C 7 803
FID C 7 806
FID C 7 813
FID C 7 812
FID C 7 807
FID C 7 814
FID C 7 815
FID C 7 808
FID C 7 797
FID C 7 791
FID C 7 790
FID C 7 796
FID C 7 800
FID C 7 804
#
FGR TEXT
# FGR 114
PRP string 'C58'
FID C 7 849
FID C 7 843
FID C 7 842
FID C 7 848
FID C 7 864
FID C 7 868
FID C 7 869
FID C 7 845
FID C 7 844
FID C 7 856
FID C 7 852
FID C 7 853
FID C 7 857
FID C 7 865
FID C 7 871
FID C 7 870
FID C 7 850
FID C 7 846
FID C 7 847
FID C 7 851
FID C 7 855
FID C 7 860
FID C 7 862
FID C 7 867
FID C 7 873
FID C 7 872
FID C 7 866
FID C 7 861
FID C 7 858
FID C 7 854
FID C 7 859
#
FGR TEXT
# FGR 115
PRP string 'C57'
FID C 7 2766
FID C 7 2762
FID C 7 2757
FID C 7 2752
FID C 7 2751
FID C 7 2756
FID C 7 2761
FID C 7 2793
FID C 7 2774
FID C 7 2773
FID C 7 2777
FID C 7 2783
FID C 7 2792
FID C 7 2791
FID C 7 2782
FID C 7 2776
FID C 7 2805
FID C 7 2832
FID C 7 2831
FID C 7 2804
#
FGR TEXT
# FGR 116
PRP string 'C56'
FID C 7 2587
FID C 7 2586
FID C 7 2584
FID C 7 2582
FID C 7 2581
FID C 7 2583
FID C 7 2585
FID C 7 2613
FID C 7 2591
FID C 7 2590
FID C 7 2600
FID C 7 2608
FID C 7 2612
FID C 7 2611
FID C 7 2607
FID C 7 2592
FID C 7 2654
FID C 7 2640
FID C 7 2623
FID C 7 2622
FID C 7 2630
FID C 7 2647
FID C 7 2652
FID C 7 2653
FID C 7 2648
#
FGR TEXT
# FGR 117
PRP string 'C55'
FID C 7 1879
FID C 7 1872
FID C 7 1871
FID C 7 1878
FID C 7 1890
FID C 7 1893
FID C 7 1894
FID C 7 1874
FID C 7 1873
FID C 7 1884
FID C 7 1880
FID C 7 1881
FID C 7 1885
FID C 7 1891
FID C 7 1896
FID C 7 1895
FID C 7 1876
FID C 7 1875
FID C 7 1886
FID C 7 1882
FID C 7 1883
FID C 7 1887
FID C 7 1892
FID C 7 1898
FID C 7 1897
#
FGR TEXT
# FGR 118
PRP string 'C54'
FID C 7 1698
FID C 7 1690
FID C 7 1689
FID C 7 1697
FID C 7 1737
FID C 7 1745
FID C 7 1746
FID C 7 1692
FID C 7 1691
FID C 7 1711
FID C 7 1704
FID C 7 1705
FID C 7 1712
FID C 7 1738
FID C 7 1748
FID C 7 1747
FID C 7 1749
FID C 7 1693
FID C 7 1713
#
FGR TEXT
# FGR 119
PRP string 'C22'
FID C 7 2372
FID C 7 2365
FID C 7 2364
FID C 7 2371
FID C 7 2387
FID C 7 2388
FID C 7 2389
FID C 7 2391
FID C 7 2390
FID C 7 2375
FID C 7 2373
FID C 7 2367
FID C 7 2366
FID C 7 2393
FID C 7 2392
FID C 7 2376
FID C 7 2374
FID C 7 2369
FID C 7 2368
#
FGR TEXT
# FGR 120
PRP string 'C21'
FID C 7 2407
FID C 7 2403
FID C 7 2399
FID C 7 2395
FID C 7 2394
FID C 7 2398
FID C 7 2402
FID C 7 2431
FID C 7 2417
FID C 7 2432
FID C 7 2433
FID C 7 2429
FID C 7 2420
FID C 7 2438
FID C 7 2442
FID C 7 2440
FID C 7 2441
#
FGR TEXT
# FGR 121
PRP string 'C20'
FID C 7 3071
FID C 7 3065
FID C 7 3064
FID C 7 3070
FID C 7 3080
FID C 7 3085
FID C 7 3086
FID C 7 3088
FID C 7 3087
FID C 7 3075
FID C 7 3072
FID C 7 3067
FID C 7 3066
FID C 7 3073
FID C 7 3068
FID C 7 3069
FID C 7 3074
FID C 7 3082
FID C 7 3090
FID C 7 3089
FID C 7 3081
#
FGR TEXT
# FGR 122
PRP string 'C19'
FID C 7 3032
FID C 7 3029
FID C 7 3025
FID C 7 3023
FID C 7 3022
FID C 7 3024
FID C 7 3028
FID C 7 3036
FID C 7 3044
FID C 7 3041
FID C 7 3042
FID C 7 3046
FID C 7 3051
FID C 7 3056
FID C 7 3058
FID C 7 3059
FID C 7 3057
FID C 7 3053
FID C 7 3048
FID C 7 3047
FID C 7 3052
#
FGR TEXT
# FGR 123
PRP string 'C18'
FID C 7 2906
FID C 7 2902
FID C 7 2893
FID C 7 2885
FID C 7 2884
FID C 7 2892
FID C 7 2901
FID C 7 2914
FID C 7 2936
FID C 7 2924
FID C 7 2925
FID C 7 2957
FID C 7 2968
FID C 7 2981
FID C 7 2994
FID C 7 2993
FID C 7 2980
FID C 7 2992
FID C 7 2991
FID C 7 2979
FID C 7 2965
FID C 7 2954
FID C 7 2955
FID C 7 2966
FID C 7 2956
FID C 7 2967
#
FGR TEXT
# FGR 124
PRP string 'C17'
FID C 7 2907
FID C 7 2904
FID C 7 2895
FID C 7 2887
FID C 7 2886
FID C 7 2894
FID C 7 2903
FID C 7 2915
FID C 7 2939
FID C 7 2928
FID C 7 2929
FID C 7 2960
FID C 7 2997
FID C 7 2996
FID C 7 2959
#
FGR TEXT
# FGR 125
PRP string 'C16'
FID C 7 2905
FID C 7 2900
FID C 7 2891
FID C 7 2883
FID C 7 2882
FID C 7 2890
FID C 7 2899
FID C 7 2913
FID C 7 2935
FID C 7 2922
FID C 7 2923
FID C 7 2990
FID C 7 2971
FID C 7 2953
FID C 7 2952
FID C 7 2964
FID C 7 2977
FID C 7 2988
FID C 7 2989
FID C 7 2978
#
FGR TEXT
# FGR 126
PRP string 'C15'
FID C 7 2951
FID C 7 2945
FID C 7 2933
FID C 7 2919
FID C 7 2918
FID C 7 2932
FID C 7 2944
FID C 7 2970
FID C 7 2987
FID C 7 2975
FID C 7 2976
FID C 7 3021
FID C 7 3000
FID C 7 2999
FID C 7 3006
FID C 7 3012
FID C 7 3020
FID C 7 3019
FID C 7 3011
FID C 7 3004
#
FGR TEXT
# FGR 127
PRP string 'C14'
FID C 7 2958
FID C 7 2949
FID C 7 2938
FID C 7 2927
FID C 7 2926
FID C 7 2937
FID C 7 2948
FID C 7 2972
FID C 7 2995
FID C 7 2982
FID C 7 2983
FID C 7 3013
FID C 7 3014
FID C 7 3001
#
FGR TEXT
# FGR 128
PRP string 'C13'
FID C 7 2950
FID C 7 2943
FID C 7 2931
FID C 7 2917
FID C 7 2916
FID C 7 2930
FID C 7 2942
FID C 7 2969
FID C 7 2986
FID C 7 2973
FID C 7 2974
FID C 7 2998
FID C 7 3003
FID C 7 3010
FID C 7 3018
FID C 7 3017
FID C 7 3008
FID C 7 3005
FID C 7 3009
FID C 7 3016
FID C 7 3015
FID C 7 3007
FID C 7 3002
#
FGR TEXT
# FGR 129
PRP string 'C12'
FID C 7 2487
FID C 7 2480
FID C 7 2471
FID C 7 2458
FID C 7 2457
FID C 7 2470
FID C 7 2479
FID C 7 2503
FID C 7 2528
FID C 7 2519
FID C 7 2520
FID C 7 2567
FID C 7 2548
FID C 7 2568
FID C 7 2569
FID C 7 2562
FID C 7 2554
#
FGR TEXT
# FGR 130
PRP string 'C11'
FID C 7 2486
FID C 7 2478
FID C 7 2469
FID C 7 2456
FID C 7 2455
FID C 7 2468
FID C 7 2477
FID C 7 2498
FID C 7 2527
FID C 7 2513
FID C 7 2514
FID C 7 2547
FID C 7 2557
FID C 7 2552
FID C 7 2553
#
FGR TEXT
# FGR 131
PRP string 'C10'
FID C 7 2483
FID C 7 2475
FID C 7 2465
FID C 7 2454
FID C 7 2453
FID C 7 2464
FID C 7 2474
FID C 7 2497
FID C 7 2526
FID C 7 2509
FID C 7 2510
FID C 7 2544
FID C 7 2551
FID C 7 2561
FID C 7 2566
FID C 7 2565
FID C 7 2560
FID C 7 2550
FID C 7 2543
#
FGR TEXT
# FGR 132
PRP string 'C9'
FID C 7 2488
FID C 7 2482
FID C 7 2473
FID C 7 2460
FID C 7 2459
FID C 7 2472
FID C 7 2481
FID C 7 2504
FID C 7 2521
FID C 7 2532
FID C 7 2539
FID C 7 2540
FID C 7 2533
FID C 7 2523
FID C 7 2506
FID C 7 2505
FID C 7 2522
#
FGR TEXT
# FGR 133
PRP string 'C8'
FID C 7 2604
FID C 7 2596
FID C 7 2595
FID C 7 2603
FID C 7 2626
FID C 7 2636
FID C 7 2637
FID C 7 2605
FID C 7 2597
FID C 7 2598
FID C 7 2606
FID C 7 2610
FID C 7 2618
FID C 7 2621
FID C 7 2628
FID C 7 2639
FID C 7 2638
FID C 7 2627
FID C 7 2620
FID C 7 2616
FID C 7 2609
FID C 7 2617
#
FGR TEXT
# FGR 134
PRP string 'C7'
FID C 7 2462
FID C 7 2448
FID C 7 2447
FID C 7 2461
FID C 7 2489
FID C 7 2493
FID C 7 2494
FID C 7 2449
FID C 7 2450
FID C 7 2463
FID C 7 2490
#
FGR TEXT
# FGR 135
PRP string 'C6'
FID C 7 2826
FID C 7 2819
FID C 7 2818
FID C 7 2825
FID C 7 2859
FID C 7 2865
FID C 7 2866
FID C 7 2820
FID C 7 2827
FID C 7 2840
FID C 7 2860
FID C 7 2867
FID C 7 2868
FID C 7 2861
FID C 7 2849
FID C 7 2841
#
FGR TEXT
# FGR 136
PRP string 'C5'
FID C 7 2619
FID C 7 2615
FID C 7 2602
FID C 7 2594
FID C 7 2593
FID C 7 2601
FID C 7 2614
FID C 7 2660
FID C 7 2634
FID C 7 2633
FID C 7 2649
FID C 7 2656
FID C 7 2659
FID C 7 2658
FID C 7 2655
FID C 7 2642
#
FGR TEXT
# FGR 137
PRP string 'C4'
FID C 7 2739
FID C 7 2736
FID C 7 2735
FID C 7 2738
FID C 7 2741
FID C 7 2742
FID C 7 2743
FID C 7 2744
FID C 7 2737
FID C 7 2740
#
FGR TEXT
# FGR 138
PRP string 'C3'
FID C 7 2719
FID C 7 2715
FID C 7 2714
FID C 7 2718
FID C 7 2727
FID C 7 2729
FID C 7 2730
FID C 7 2720
FID C 7 2716
FID C 7 2717
FID C 7 2721
FID C 7 2722
FID C 7 2724
FID C 7 2723
FID C 7 2725
FID C 7 2726
FID C 7 2728
FID C 7 2732
FID C 7 2731
#
FGR TEXT
# FGR 139
PRP string 'C2'
FID C 7 2285
FID C 7 2284
FID C 7 2282
FID C 7 2280
FID C 7 2279
FID C 7 2281
FID C 7 2283
FID C 7 2291
FID C 7 2286
FID C 7 2292
FID C 7 2293
FID C 7 2288
FID C 7 2287
#
FGR TEXT
# FGR 140
PRP string 'C1'
FID C 7 2317
FID C 7 2316
FID C 7 2314
FID C 7 2310
FID C 7 2309
FID C 7 2313
FID C 7 2315
FID C 7 2318
FID C 7 2322
FID C 7 2320
FID C 7 2321
#
FGR TEXT
# FGR 141
PRP string 'AN8'
FID C 7 138
FID C 7 139
FID C 7 146
FID C 7 152
FID C 7 150
FID C 7 151
FID C 7 177
FID C 7 178
FID C 7 199
FID C 7 222
FID C 7 232
FID C 7 239
FID C 7 247
FID C 7 246
FID C 7 238
FID C 7 245
FID C 7 244
FID C 7 237
FID C 7 229
FID C 7 219
FID C 7 220
FID C 7 230
FID C 7 221
FID C 7 231
#
FGR TEXT
# FGR 142
PRP string 'AN7'
FID C 7 140
FID C 7 141
FID C 7 147
FID C 7 155
FID C 7 153
FID C 7 154
FID C 7 179
FID C 7 180
FID C 7 200
FID C 7 224
FID C 7 249
FID C 7 248
FID C 7 223
#
FGR TEXT
# FGR 143
PRP string 'AN6'
FID C 7 144
FID C 7 145
FID C 7 149
FID C 7 161
FID C 7 159
FID C 7 160
FID C 7 183
FID C 7 184
FID C 7 202
FID C 7 255
FID C 7 236
FID C 7 228
FID C 7 227
FID C 7 234
FID C 7 242
FID C 7 253
FID C 7 254
FID C 7 243
#
FGR TEXT
# FGR 144
PRP string 'AN5'
FID C 7 142
FID C 7 143
FID C 7 148
FID C 7 158
FID C 7 156
FID C 7 157
FID C 7 181
FID C 7 182
FID C 7 201
FID C 7 252
FID C 7 226
FID C 7 225
FID C 7 235
FID C 7 241
FID C 7 251
FID C 7 250
FID C 7 240
FID C 7 233
#
FGR TEXT
# FGR 145
PRP string 'AN4'
FID C 7 77
FID C 7 78
FID C 7 85
FID C 7 91
FID C 7 89
FID C 7 90
FID C 7 101
FID C 7 102
FID C 7 109
FID C 7 124
FID C 7 125
FID C 7 113
#
FGR TEXT
# FGR 146
PRP string 'AN3'
FID C 7 83
FID C 7 84
FID C 7 88
FID C 7 100
FID C 7 98
FID C 7 99
FID C 7 107
FID C 7 108
FID C 7 112
FID C 7 116
FID C 7 121
FID C 7 130
FID C 7 137
FID C 7 136
FID C 7 128
FID C 7 123
FID C 7 129
FID C 7 135
FID C 7 134
FID C 7 127
FID C 7 120
#
FGR TEXT
# FGR 147
PRP string 'AN2'
FID C 7 79
FID C 7 80
FID C 7 86
FID C 7 94
FID C 7 92
FID C 7 93
FID C 7 103
FID C 7 104
FID C 7 110
FID C 7 131
FID C 7 114
FID C 7 132
FID C 7 133
FID C 7 126
FID C 7 117
#
FGR TEXT
# FGR 148
PRP string 'AN1'
FID C 7 81
FID C 7 82
FID C 7 87
FID C 7 97
FID C 7 95
FID C 7 96
FID C 7 105
FID C 7 106
FID C 7 111
FID C 7 115
FID C 7 122
FID C 7 118
FID C 7 119
#
FGR TEXT
# FGR 149
PRP string 'U14'
FID C 0 205
FID C 0 204
FID C 0 201
FID C 0 194
FID C 0 190
FID C 0 172
FID C 0 162
FID C 0 167
FID C 0 168
FID C 0 145
FID C 0 146
FID C 0 148
#
FGR TEXT
# FGR 150
PRP string 'C87'
FID C 0 45
FID C 0 51
FID C 0 57
FID C 0 62
FID C 0 61
FID C 0 56
FID C 0 50
FID C 0 40
FID C 0 33
FID C 0 25
FID C 0 22
FID C 0 21
FID C 0 24
FID C 0 20
FID C 0 19
FID C 0 23
FID C 0 30
FID C 0 37
FID C 0 38
FID C 0 32
FID C 0 39
FID C 0 31
FID C 0 18
FID C 0 16
FID C 0 15
FID C 0 17
#
FGR TEXT
# FGR 151
PRP string 'C88'
FID C 0 71
FID C 0 73
FID C 0 80
FID C 0 82
FID C 0 81
FID C 0 79
FID C 0 72
FID C 0 70
FID C 0 66
FID C 0 60
FID C 0 55
FID C 0 54
FID C 0 59
FID C 0 53
FID C 0 52
FID C 0 58
FID C 0 63
FID C 0 67
FID C 0 68
FID C 0 65
FID C 0 69
FID C 0 64
FID C 0 49
FID C 0 44
FID C 0 36
FID C 0 29
FID C 0 28
FID C 0 35
FID C 0 27
FID C 0 26
FID C 0 34
FID C 0 41
FID C 0 46
FID C 0 47
FID C 0 43
FID C 0 48
FID C 0 42
#
FGR TEXT
# FGR 152
PRP string 'C89'
FID C 0 174
FID C 0 180
FID C 0 179
FID C 0 173
FID C 0 155
FID C 0 149
FID C 0 150
FID C 0 175
FID C 0 181
FID C 0 182
FID C 0 176
FID C 0 170
FID C 0 165
FID C 0 161
FID C 0 157
FID C 0 152
FID C 0 151
FID C 0 156
FID C 0 160
FID C 0 164
FID C 0 169
FID C 0 163
FID C 0 158
FID C 0 153
FID C 0 154
FID C 0 159
FID C 0 178
FID C 0 184
FID C 0 183
FID C 0 177
FID C 0 171
FID C 0 166
#
FGR TEXT
# FGR 153
PRP string 'C90'
FID C 0 279
FID C 0 281
FID C 0 290
FID C 0 294
FID C 0 293
FID C 0 289
FID C 0 280
FID C 0 276
FID C 0 273
FID C 0 271
FID C 0 263
FID C 0 264
FID C 0 272
FID C 0 275
FID C 0 278
FID C 0 277
FID C 0 274
FID C 0 256
FID C 0 252
FID C 0 246
FID C 0 238
FID C 0 237
FID C 0 245
FID C 0 251
FID C 0 255
#
FGR TEXT
# FGR 154
PRP string 'C53'
FID C 0 347
FID C 0 351
FID C 0 350
FID C 0 346
FID C 0 334
FID C 0 328
FID C 0 329
FID C 0 353
FID C 0 352
FID C 0 338
FID C 0 343
FID C 0 344
FID C 0 339
FID C 0 335
FID C 0 331
FID C 0 330
FID C 0 348
FID C 0 354
FID C 0 355
FID C 0 349
FID C 0 345
FID C 0 342
FID C 0 340
FID C 0 341
FID C 0 337
FID C 0 336
FID C 0 333
FID C 0 332
#
FGR TEXT
# FGR 155
PRP string 'C52'
FID C 0 320
FID C 0 323
FID C 0 322
FID C 0 319
FID C 0 312
FID C 0 306
FID C 0 307
FID C 0 325
FID C 0 324
FID C 0 314
FID C 0 316
FID C 0 317
FID C 0 315
FID C 0 313
FID C 0 309
FID C 0 308
FID C 0 311
FID C 0 310
FID C 0 318
FID C 0 321
FID C 0 327
FID C 0 326
#
FGR TEXT
# FGR 156
PRP string 'C51'
FID C 0 300
FID C 0 302
FID C 0 301
FID C 0 299
FID C 0 291
FID C 0 282
FID C 0 283
FID C 0 304
FID C 0 303
FID C 0 295
FID C 0 297
FID C 0 298
FID C 0 296
FID C 0 292
FID C 0 285
FID C 0 284
FID C 0 286
FID C 0 288
FID C 0 287
FID C 0 305
#
FGR TEXT
# FGR 157
PRP string 'C50'
FID C 0 260
FID C 0 266
FID C 0 265
FID C 0 259
FID C 0 247
FID C 0 239
FID C 0 240
FID C 0 268
FID C 0 267
FID C 0 253
FID C 0 257
FID C 0 258
FID C 0 254
FID C 0 248
FID C 0 242
FID C 0 241
FID C 0 261
FID C 0 269
FID C 0 270
FID C 0 262
FID C 0 250
FID C 0 244
FID C 0 243
FID C 0 249
#
FGR TEXT
# FGR 158
PRP string 'C49'
FID C 0 229
FID C 0 233
FID C 0 232
FID C 0 228
FID C 0 222
FID C 0 217
FID C 0 218
FID C 0 219
FID C 0 234
FID C 0 225
FID C 0 223
FID C 0 220
FID C 0 221
FID C 0 224
FID C 0 231
FID C 0 236
FID C 0 235
FID C 0 230
FID C 0 227
FID C 0 226
#
FGR TEXT
# FGR 159
PRP string 'C48'
FID C 0 207
FID C 0 212
FID C 0 211
FID C 0 206
FID C 0 191
FID C 0 185
FID C 0 186
FID C 0 187
FID C 0 213
FID C 0 197
FID C 0 208
FID C 0 214
FID C 0 215
FID C 0 209
FID C 0 203
FID C 0 200
FID C 0 196
FID C 0 193
FID C 0 189
FID C 0 188
FID C 0 192
FID C 0 195
FID C 0 199
FID C 0 202
FID C 0 198
#
FGR TEXT
# FGR 160
PRP string 'C47'
FID C 0 138
FID C 0 141
FID C 0 140
FID C 0 137
FID C 0 134
FID C 0 131
FID C 0 132
FID C 0 133
FID C 0 142
FID C 0 136
FID C 0 143
FID C 0 144
FID C 0 139
FID C 0 135
#
FGR TEXT
# FGR 161
PRP string 'C46'
FID C 0 125
FID C 0 128
FID C 0 127
FID C 0 124
FID C 0 117
FID C 0 112
FID C 0 113
FID C 0 114
FID C 0 129
FID C 0 121
FID C 0 130
FID C 0 126
FID C 0 122
FID C 0 118
FID C 0 115
FID C 0 116
FID C 0 119
FID C 0 120
FID C 0 123
#
FGR TEXT
# FGR 162
PRP string 'C45'
FID C 0 106
FID C 0 108
FID C 0 107
FID C 0 105
FID C 0 98
FID C 0 93
FID C 0 94
FID C 0 95
FID C 0 109
FID C 0 100
FID C 0 111
FID C 0 110
FID C 0 101
FID C 0 103
FID C 0 104
FID C 0 102
FID C 0 99
FID C 0 97
FID C 0 96
#
FGR TEXT
# FGR 163
PRP string 'C44'
FID C 0 86
FID C 0 90
FID C 0 89
FID C 0 85
FID C 0 78
FID C 0 74
FID C 0 75
FID C 0 76
FID C 0 91
FID C 0 83
FID C 0 77
FID C 0 92
FID C 0 84
#

### steps/pcb/netlists/cadnet/netlist
H optimize n staggered n
$0 $NONE$
$1 +3.3V
$2 +3.3V_CLEAN
$3 +3.3V_PCIE
$4 +5.0V
$5 +12V
$6 +12V_PCIE
$7 5721_STATUS
$8 ANT1
$9 ANT2
$10 ANT3
$11 ANT4
$12 CSN
$13 DCXO1
$14 DCXO2
$15 FPGA_TCK
$16 FPGA_TDI
$17 FPGA_TDO
$18 FPGA_TMS
$19 GND
$20 GPS1_RST
$21 GPS1_RX
$22 GPS1_TP1
$23 GPS1_TP2
$24 GPS1_TX
$25 GPS2_RST
$26 GPS2_RX
$27 GPS2_TP1
$28 GPS2_TP2
$29 GPS2_TX
$30 IMU_BOOT
$31 IMU_CLKSEL0
$32 IMU_ENV_SCL
$33 IMU_ENV_SDA
$34 IMU_INT
$35 IMU_NRST
$36 IMU_PS0
$37 IMU_PS1
$38 KEY1
$39 KEY2
$40 LED1
$41 LED2
$42 LED3
$43 LED4
$44 MAC_10Mout
$45 MAC_ALARM
$46 MAC_BITE
$47 MAC_PPS_IN0+
$48 MAC_PPS_IN0-
$49 MAC_PPS_IN1+
$50 MAC_PPS_IN1-
$51 MAC_PPS_OUT+
$52 MAC_PPS_OUT-
$53 MAC_RX
$54 MAC_TX
$55 MAC_USB_PWR
$56 MAC_USB+
$57 MAC_USB-
$58 MISO
$59 MOSI
$60 NetBT1_2
$61 NetC3_1
$62 NetC3_2
$63 NetC4_1
$64 NetC4_2
$65 NetC19_2
$66 NetC20_1
$67 NetC20_2
$68 NetC21_2
$69 NetC22_1
$70 NetC22_2
$71 NetC44_1
$72 NetC45_1
$73 NetC46_1
$74 NetC47_1
$75 NetC48_1
$76 NetC49_1
$77 NetC50_1
$78 NetC51_1
$79 NetC52_1
$80 NetC53_1
$81 NetC54_2
$82 NetC72_2
$83 NetC85_2
$84 NetC86_2
$85 NetD1_1
$86 NetD1_2
$87 NetD2_1
$88 NetD2_2
$89 NetD4_1
$90 NetD9_1
$91 NetD10_1
$92 NetD11_1
$93 NetD12_1
$94 NetD13_1
$95 NetD14_1
$96 NetJ3_2
$97 NetJ3_3
$98 NetJ4_2
$99 NetJ4_3
$100 NetJP1_2
$101 NetJP1_3
$102 NetJP2_2
$103 NetJP2_3
$104 NetP2_B17
$105 NetP2_B31
$106 NetR2_1
$107 NetR3_1
$108 NetR4_2
$109 NetR5_1
$110 NetR18_2
$111 NetR19_2
$112 NetR20_2
$113 NetR21_2
$114 NetR27_2
$115 NetR32_1
$116 NetR33_1
$117 NetR42_1
$118 NetR43_2
$119 NetU6_3
$120 NetU16_3
$121 OE_5356
$122 PCIE_CLK_N
$123 PCIE_CLK_P
$124 PCIE_PERST
$125 PCIE_RX0_N
$126 PCIE_RX0_P
$127 PCIE_RX1_N
$128 PCIE_RX1_P
$129 PCIE_RX2_N
$130 PCIE_RX2_P
$131 PCIE_RX3_N
$132 PCIE_RX3_P
$133 PCIE_TX0_N
$134 PCIE_TX0_P
$135 PCIE_TX1_N
$136 PCIE_TX1_P
$137 PCIE_TX2_N
$138 PCIE_TX2_P
$139 PCIE_TX3_N
$140 PCIE_TX3_P
$141 PRSNT
$142 RTC_MFP
$143 SCK
$144 SCL
$145 SDA
$146 UART1_RXD
$147 UART1_TXD
#
#Netlist points
#
0 0 3.1112205 2.9372047 T 0.0787402 0.023622 e s
0 0 3.1112205 2.9872047 T 0.0787402 0.023622 e s
0 0 3.1112205 3.0372047 T 0.0787402 0.023622 e s
0 0 3.1112205 3.0872047 T 0.0787402 0.023622 e s
0 0 2.7568898 2.9372047 T 0.0787402 0.023622 e s
0 0 2.7568898 2.9872047 T 0.0787402 0.023622 e s
0 0 2.7568898 3.0372047 T 0.0787402 0.023622 e s
0 0 2.7568898 3.0872047 T 0.0787402 0.023622 e s
0 0 2.7568898 3.1372047 T 0.0787402 0.023622 e s
0 0 2.7568898 3.2872047 T 0.0787402 0.023622 e s
0 0 2.1996929 4.275063 T 0.0649606 0.0511811 e s
0 0 2.4654409 4.275063 T 0.0649606 0.0511811 e s
0 0 2.3069763 4.1703386 T 0.0177165 0.0543307 e s
0 0 2.383748 4.1703386 T 0.0177165 0.0543307 e s
0 0 2.4309921 4.1736851 T 0.0559055 0.0610236 e s
0 0 2.2341417 4.1736851 T 0.0559055 0.0610236 e s
0 0 2.3778425 4.275063 T 0.0708661 0.0748031 e s
0 0 2.2715433 4.275063 T 0.0393701 0.0748031 e s
0 0 3.8399606 4.0237008 T 0.019685 0.0905512 e s
0 0 3.6962598 4.2441732 T 0.0787402 0.0984252 e s
0 0 3.6962598 4.0276378 T 0.0787402 0.0984252 e s
0 0 4.0466536 4.0276378 T 0.0787402 0.0984252 e s
0 0 4.0466536 4.2441732 T 0.0787402 0.0984252 e s
0 0 1.631559 4.174563 T 0.0570866 0.0177165 e s
0 0 1.631559 4.074563 T 0.0570866 0.0177165 e s
0 0 1.631559 4.049563 T 0.0570866 0.0177165 e s
0 0 1.8461259 4.199563 T 0.0570866 0.0177165 e s
0 0 1.8461259 4.174563 T 0.0570866 0.0177165 e s
0 0 1.8461259 4.149563 T 0.0570866 0.0177165 e s
0 0 6.9431102 3.2940551 T 0.0511811 0.0748031 e s
0 0 6.9431102 3.1680709 T 0.0511811 0.0748031 e s
0 0 3.5693307 3.3853543 T 0.0393701 0.0905512 e s
0 0 3.5102756 3.2062205 T 0.0393701 0.0708661 e s
0 0 3.3921654 3.2062205 T 0.0393701 0.0708661 e s
0 0 3.4512205 3.2062205 T 0.0393701 0.0708661 e s
0 0 3.5251968 2.995685 T 0.0531496 0.0275591 e s
0 0 3.5251968 2.948441 T 0.0531496 0.0275591 e s
0 0 3.4444882 2.948441 T 0.0531496 0.0275591 e s
0 0 3.2448425 3.951063 T 0.05 0.2 e s
0 0 3.2448425 4.2211417 T 0.05 0.2 e s
0 0 2.1515751 0.1377953 T 0.028 0.165 e s
0 0 2.1122051 0.1377953 T 0.028 0.165 e s
0 0 2.3090551 0.1377953 T 0.028 0.165 e s
0 0 3.0177151 0.1377953 T 0.028 0.165 e s
0 0 1.9547251 0.1377953 T 0.028 0.165 e s
0 0 1.9940951 0.1377953 T 0.028 0.165 e s
0 0 2.1909451 0.1377953 T 0.028 0.165 e s
0 0 3.9114214 1.7596232 T 0.0708661 0.0098425 e s
0 0 3.9114214 1.7396232 T 0.0708661 0.0098425 e s
0 0 4.0689017 1.7196232 T 0.0708661 0.0098425 e s
0 0 3.9114214 1.7196232 T 0.0708661 0.0098425 e s
0 0 4.0689017 1.6996232 T 0.0708661 0.0098425 e s
0 0 3.9114214 1.6996232 T 0.0708661 0.0098425 e s
0 0 3.9114214 1.6796232 T 0.0708661 0.0098425 e s
0 0 6.5113582 3.1524803 T 0.0265748 0.0098425 e s
0 0 6.3883268 3.1721654 T 0.0265748 0.0098425 e s
0 0 6.3883268 3.1918504 T 0.0265748 0.0098425 e s
0 0 6.3883268 3.2115354 T 0.0265748 0.0098425 e s
0 0 6.3883268 3.2705906 T 0.0265748 0.0098425 e s
0 0 6.3883268 3.2902756 T 0.0265748 0.0098425 e s
0 0 6.5113582 3.3099606 T 0.0265748 0.0098425 e s
0 0 6.5113582 3.2902756 T 0.0265748 0.0098425 e s
0 0 6.5113582 3.2705906 T 0.0265748 0.0098425 e s
0 0 6.5113582 3.2509055 T 0.0265748 0.0098425 e s
0 0 3.2091732 2.7952756 T 0.0108268 0.0098425 e s
0 0 3.2490157 2.7849212 T 0.0098425 0.0108268 e s
0 0 3.0249825 2.438533 T 0.05315 0.06693 e s
0 0 2.2129825 1.038313 T 0.00984 0.06102 e s
0 0 2.2129825 0.878873 T 0.00984 0.06102 e s
0 0 3.0249925 0.958593 T 0.05315 0.06693 e s
0 0 2.1686925 0.958593 T 0.05315 0.06693 e s
0 0 2.6657425 0.878873 T 0.00984 0.06102 e s
0 0 2.7247925 0.878873 T 0.00984 0.06102 e s
0 0 2.7838525 0.878873 T 0.00984 0.06102 e s
0 0 2.8429025 0.878873 T 0.00984 0.06102 e s
0 0 2.9610125 0.878873 T 0.00984 0.06102 e s
0 0 2.9610125 1.038313 T 0.00984 0.06102 e s
0 0 2.9807025 1.038313 T 0.00984 0.06102 e s
0 0 2.9807025 0.878873 T 0.00984 0.06102 e s
0 0 2.9413325 1.038313 T 0.00984 0.06102 e s
0 0 2.9413325 0.878873 T 0.00984 0.06102 e s
0 0 2.9216425 1.038313 T 0.00984 0.06102 e s
0 0 2.9216425 0.878873 T 0.00984 0.06102 e s
0 0 2.8822725 1.038313 T 0.00984 0.06102 e s
0 0 2.8625925 1.038313 T 0.00984 0.06102 e s
0 0 2.5279425 1.038313 T 0.00984 0.06102 e s
0 0 2.5476325 1.038313 T 0.00984 0.06102 e s
0 0 2.3310925 1.038313 T 0.00984 0.06102 e s
0 0 2.3507825 1.038313 T 0.00984 0.06102 e s
0 0 2.2326725 1.038313 T 0.00984 0.06102 e s
0 0 2.2523525 1.038313 T 0.00984 0.06102 e s
0 0 2.2720425 1.038313 T 0.00984 0.06102 e s
0 0 2.2917225 1.038313 T 0.00984 0.06102 e s
0 0 2.4492025 1.038313 T 0.00984 0.06102 e s
0 0 2.4885725 1.038313 T 0.00984 0.06102 e s
0 0 2.4688925 1.038313 T 0.00984 0.06102 e s
0 0 2.4295225 1.038313 T 0.00984 0.06102 e s
0 0 2.3901525 1.038313 T 0.00984 0.06102 e s
0 0 2.3704625 1.038313 T 0.00984 0.06102 e s
0 0 2.5673125 1.038313 T 0.00984 0.06102 e s
0 0 2.2720425 0.878873 T 0.00984 0.06102 e s
0 0 2.2523525 0.878873 T 0.00984 0.06102 e s
0 0 2.4688925 0.878873 T 0.00984 0.06102 e s
0 0 2.4492025 0.878873 T 0.00984 0.06102 e s
0 0 2.5673125 0.878873 T 0.00984 0.06102 e s
0 0 2.5476325 0.878873 T 0.00984 0.06102 e s
0 0 2.5279425 0.878873 T 0.00984 0.06102 e s
0 0 2.4885725 0.878873 T 0.00984 0.06102 e s
0 0 2.3901525 0.878873 T 0.00984 0.06102 e s
0 0 2.2917225 0.878873 T 0.00984 0.06102 e s
0 0 2.3310925 0.878873 T 0.00984 0.06102 e s
0 0 2.3507825 0.878873 T 0.00984 0.06102 e s
0 0 2.3704625 0.878873 T 0.00984 0.06102 e s
0 0 2.4295225 0.878873 T 0.00984 0.06102 e s
0 0 2.2326725 0.878873 T 0.00984 0.06102 e s
0 0 2.5870025 1.038313 T 0.00984 0.06102 e s
0 0 2.5870025 0.878873 T 0.00984 0.06102 e s
0 0 1.6968325 2.131683 T 0.06693 0.05315 e s
0 0 1.6968325 1.275383 T 0.06693 0.05315 e s
0 0 1.7765525 2.048023 T 0.06102 0.00984 e s
0 0 1.6171125 2.048023 T 0.06102 0.00984 e s
0 0 1.6171125 1.654323 T 0.06102 0.00984 e s
0 0 1.6171125 1.713373 T 0.06102 0.00984 e s
0 0 1.7765525 1.477153 T 0.06102 0.00984 e s
0 0 1.7765525 1.418103 T 0.06102 0.00984 e s
0 0 1.7765525 1.378733 T 0.06102 0.00984 e s
0 0 1.6171125 1.772433 T 0.06102 0.00984 e s
0 0 1.6171125 1.634633 T 0.06102 0.00984 e s
0 0 1.6171125 1.339363 T 0.06102 0.00984 e s
0 0 1.7765525 1.359043 T 0.06102 0.00984 e s
0 0 1.6171125 1.752743 T 0.06102 0.00984 e s
0 0 1.6171125 1.418103 T 0.06102 0.00984 e s
0 0 1.6171125 1.477153 T 0.06102 0.00984 e s
0 0 1.6171125 1.378733 T 0.06102 0.00984 e s
0 0 1.6171125 1.674003 T 0.06102 0.00984 e s
0 0 1.6171125 1.733063 T 0.06102 0.00984 e s
0 0 1.6171125 1.614953 T 0.06102 0.00984 e s
0 0 1.6171125 1.555893 T 0.06102 0.00984 e s
0 0 1.6171125 1.536213 T 0.06102 0.00984 e s
0 0 1.6171125 1.437783 T 0.06102 0.00984 e s
0 0 1.6171125 1.575583 T 0.06102 0.00984 e s
0 0 1.7765525 1.339363 T 0.06102 0.00984 e s
0 0 1.6171125 1.359043 T 0.06102 0.00984 e s
0 0 1.7765525 1.437783 T 0.06102 0.00984 e s
0 0 1.6171125 1.831483 T 0.06102 0.00984 e s
0 0 1.6171125 1.811803 T 0.06102 0.00984 e s
0 0 1.6171125 1.457473 T 0.06102 0.00984 e s
0 0 1.6171125 1.516523 T 0.06102 0.00984 e s
0 0 1.7765525 1.575583 T 0.06102 0.00984 e s
0 0 1.7765525 1.555893 T 0.06102 0.00984 e s
0 0 1.6171125 1.949593 T 0.06102 0.00984 e s
0 0 1.7765525 1.713373 T 0.06102 0.00984 e s
0 0 1.7765525 1.752743 T 0.06102 0.00984 e s
0 0 1.6171125 2.008653 T 0.06102 0.00984 e s
0 0 1.7765525 1.654323 T 0.06102 0.00984 e s
0 0 1.7765525 1.851173 T 0.06102 0.00984 e s
0 0 1.7765525 1.929913 T 0.06102 0.00984 e s
0 0 1.6171125 1.969283 T 0.06102 0.00984 e s
0 0 1.6171125 1.870853 T 0.06102 0.00984 e s
0 0 1.7765525 1.457473 T 0.06102 0.00984 e s
0 0 1.7765525 1.969283 T 0.06102 0.00984 e s
0 0 1.7765525 2.008653 T 0.06102 0.00984 e s
0 0 1.6171125 2.028333 T 0.06102 0.00984 e s
0 0 1.6171125 1.910223 T 0.06102 0.00984 e s
0 0 1.6171125 1.851173 T 0.06102 0.00984 e s
0 0 1.6171125 1.929913 T 0.06102 0.00984 e s
0 0 1.7765525 1.772433 T 0.06102 0.00984 e s
0 0 1.7765525 1.733063 T 0.06102 0.00984 e s
0 0 1.7765525 1.949593 T 0.06102 0.00984 e s
0 0 1.7765525 1.831483 T 0.06102 0.00984 e s
0 0 1.7765525 1.910223 T 0.06102 0.00984 e s
0 0 1.7765525 2.028333 T 0.06102 0.00984 e s
0 0 1.7765525 1.870853 T 0.06102 0.00984 e s
0 0 1.7765525 1.634633 T 0.06102 0.00984 e s
0 0 2.3310825 2.518253 T 0.00984 0.06102 e s
0 0 2.3114025 2.518253 T 0.00984 0.06102 e s
0 0 2.2720325 2.358813 T 0.00984 0.06102 e s
0 0 2.2523425 2.358813 T 0.00984 0.06102 e s
0 0 2.9610025 2.518253 T 0.00984 0.06102 e s
0 0 2.9413225 2.518253 T 0.00984 0.06102 e s
0 0 2.8625825 2.518253 T 0.00984 0.06102 e s
0 0 2.8428925 2.518253 T 0.00984 0.06102 e s
0 0 2.7641525 2.518253 T 0.00984 0.06102 e s
0 0 2.7444725 2.518253 T 0.00984 0.06102 e s
0 0 2.8035225 2.518253 T 0.00984 0.06102 e s
0 0 2.6657325 2.518253 T 0.00984 0.06102 e s
0 0 2.6460425 2.518253 T 0.00984 0.06102 e s
0 0 2.7247825 2.518253 T 0.00984 0.06102 e s
0 0 2.7051025 2.518253 T 0.00984 0.06102 e s
0 0 2.5673025 2.518253 T 0.00984 0.06102 e s
0 0 2.6263625 2.518253 T 0.00984 0.06102 e s
0 0 2.5476225 2.518253 T 0.00984 0.06102 e s
0 0 2.6066725 2.518253 T 0.00984 0.06102 e s
0 0 2.5082525 2.518253 T 0.00984 0.06102 e s
0 0 2.3704525 2.518253 T 0.00984 0.06102 e s
0 0 2.4295125 2.518253 T 0.00984 0.06102 e s
0 0 2.4098225 2.518253 T 0.00984 0.06102 e s
0 0 2.2129725 2.358813 T 0.00984 0.06102 e s
0 0 2.2326625 2.358813 T 0.00984 0.06102 e s
0 0 2.2326625 2.518253 T 0.00984 0.06102 e s
0 0 2.2129725 2.518253 T 0.00984 0.06102 e s
0 0 2.3704525 2.358813 T 0.00984 0.06102 e s
0 0 2.3507725 2.358813 T 0.00984 0.06102 e s
0 0 2.5082525 2.358813 T 0.00984 0.06102 e s
0 0 2.7641525 2.358813 T 0.00984 0.06102 e s
0 0 2.7444725 2.358813 T 0.00984 0.06102 e s
0 0 2.8232125 2.358813 T 0.00984 0.06102 e s
0 0 2.8428925 2.358813 T 0.00984 0.06102 e s
0 0 2.9216325 2.358813 T 0.00984 0.06102 e s
0 0 2.9413225 2.358813 T 0.00984 0.06102 e s
0 0 2.1686825 2.438533 T 0.05315 0.06693 e s
0 0 3.4920225 1.595223 T 0.06102 0.00984 e s
0 0 3.4920225 1.575543 T 0.06102 0.00984 e s
0 0 3.6514625 1.536173 T 0.06102 0.00984 e s
0 0 3.4920225 1.733023 T 0.06102 0.00984 e s
0 0 3.5717425 1.275343 T 0.06693 0.05315 e s
0 0 3.5717425 2.131643 T 0.06693 0.05315 e s
0 0 3.6514625 1.319633 T 0.06102 0.00984 e s
0 0 3.4920225 1.319633 T 0.06102 0.00984 e s
0 0 3.6514625 1.339323 T 0.06102 0.00984 e s
0 0 3.6514625 1.359003 T 0.06102 0.00984 e s
0 0 3.6514625 1.378693 T 0.06102 0.00984 e s
0 0 3.6514625 1.398373 T 0.06102 0.00984 e s
0 0 3.6514625 1.437743 T 0.06102 0.00984 e s
0 0 3.6514625 1.457433 T 0.06102 0.00984 e s
0 0 3.4920225 1.536173 T 0.06102 0.00984 e s
0 0 3.6514625 1.595223 T 0.06102 0.00984 e s
0 0 3.4920225 1.949553 T 0.06102 0.00984 e s
0 0 3.4920225 1.555853 T 0.06102 0.00984 e s
0 0 3.4920225 1.929873 T 0.06102 0.00984 e s
0 0 3.6514625 1.673963 T 0.06102 0.00984 e s
0 0 3.6514625 1.752703 T 0.06102 0.00984 e s
0 0 3.6514625 1.733023 T 0.06102 0.00984 e s
0 0 3.4920225 1.693653 T 0.06102 0.00984 e s
0 0 3.4920225 1.634593 T 0.06102 0.00984 e s
0 0 3.6514625 1.693653 T 0.06102 0.00984 e s
0 0 3.4920225 1.969243 T 0.06102 0.00984 e s
0 0 3.4920225 1.988923 T 0.06102 0.00984 e s
0 0 3.6514625 1.969243 T 0.06102 0.00984 e s
0 0 3.6514625 1.988923 T 0.06102 0.00984 e s
0 0 3.6514625 1.949553 T 0.06102 0.00984 e s
0 0 3.6514625 1.831443 T 0.06102 0.00984 e s
0 0 3.6514625 1.851133 T 0.06102 0.00984 e s
0 0 3.6514625 1.929873 T 0.06102 0.00984 e s
0 0 3.6514625 1.870813 T 0.06102 0.00984 e s
0 0 3.4920225 1.792073 T 0.06102 0.00984 e s
0 0 3.4920225 1.496803 T 0.06102 0.00984 e s
0 0 3.4920225 1.772393 T 0.06102 0.00984 e s
0 0 3.4920225 1.477113 T 0.06102 0.00984 e s
0 0 3.4920225 1.457433 T 0.06102 0.00984 e s
0 0 3.772559 3.833563 T 0.0570866 0.0177165 e s
0 0 3.772559 3.733563 T 0.0570866 0.0177165 e s
0 0 3.772559 3.708563 T 0.0570866 0.0177165 e s
0 0 3.9871259 3.858563 T 0.0570866 0.0177165 e s
0 0 3.9871259 3.833563 T 0.0570866 0.0177165 e s
0 0 3.9871259 3.808563 T 0.0570866 0.0177165 e s
0 0.0177166 3.7848425 4.126063 B e e staggered 0 0 0
0 0.0177166 3.9580709 4.126063 B e e staggered 0 0 0
0 0.0329922 2.9948425 4.0861024 B e e staggered 0 0 0
0 0.0329922 3.2948425 4.0861024 B e e staggered 0 0 0
0 0.0149606 2.4223425 3.2396929 B e e staggered 0 0 0
0 0.0149606 2.4223425 3.0822126 B e e staggered 0 0 0
0 0.0206693 4.3277559 1.0074803 B e e staggered 0 0 0
0 0.01083 2.9905325 2.438533 B e e staggered 0 0 0
0 0.01083 2.9905425 0.958593 B e e staggered 0 0 0
0 0.01083 2.2031425 0.958593 B e e staggered 0 0 0
0 0.01083 1.6968325 2.097233 B e e staggered 0 0 0
0 0.01083 1.6968325 1.309833 B e e staggered 0 0 0
0 0.01083 2.2031325 2.438533 B e e staggered 0 0 0
0 0.01083 3.5717425 1.309793 B e e staggered 0 0 0
0 0.01083 3.5717425 2.097193 B e e staggered 0 0 0
0 0.059055 3.6179425 0.916293 B e e staggered 0 0 0
0 0.059055 1.6519425 2.486293 B e e staggered 0 0 0
0 0.059055 1.6529425 0.916293 B e e staggered 0 0 0
0 0.059055 3.6179425 2.486293 B e e staggered 0 0 0
0 0.0590551 6.5694882 4.0934646 B e e staggered 0 0 0
0 0.0590551 6.9001969 4.0934646 B e e staggered 0 0 0
0 0.0149606 2.4223425 3.4438977 B e e staggered 0 0 0
0 0.0149606 2.4223425 3.601378 B e e staggered 0 0 0
0 0.0625984 0.285433 4.152063 B e e staggered 0 0 0
0 0.0625984 0.2854331 0.3681102 B e e staggered 0 0 0
0 0 3.0964551 0.1377953 D 0.028 0.165 e p
0 0 1.9547251 0.1377953 D 0.028 0.165 e p
0 0 1.9940951 0.1377953 D 0.028 0.165 e p
0 0 2.0334651 0.1377953 D 0.028 0.165 e p
0 0 2.0728351 0.1377953 D 0.028 0.165 e p
0 0 2.5846451 0.1377953 D 0.028 0.165 e p
0 0.004 2.2317425 2.584163 B e e staggered 0 0 0 v
0 0.004 2.2348425 3.506063 B e e staggered 0 0 0 v
0 0.004 3.5298425 3.481063 B e e staggered 0 0 0 v
1 0 3.444252 3.7503543 T 0.019685 0.0354331 e s
1 0 3.1448425 4.2211417 T 0.05 0.2 e s
1 0 3.0448425 4.2211417 T 0.05 0.2 e s
1 0 6.5113582 3.1721654 T 0.0265748 0.0098425 e s
1 0 6.4598425 3.1500197 T 0.0098425 0.0226378 e s
1 0 6.6798425 2.8020079 T 0.2125984 0.1141732 e s
1 0 1.2498423 4.2546063 T 0.0334646 0.0393701 e s
1 0 6.253937 2.7559055 T 0.0570866 0.0452756 e s
1 0 6.3720472 2.7559055 T 0.0570866 0.0452756 e s
1 0 6.3279134 2.656063 T 0.0267717 0.0251969 e s
1 0 6.3279134 2.501063 T 0.0267717 0.0251969 e s
1 0 6.3279134 2.556063 T 0.0267717 0.0251969 e s
1 0 6.3279134 2.611063 T 0.0267717 0.0251969 e s
1 0 6.5102756 3.071063 T 0.0452756 0.0570866 e s
1 0 6.5848425 3.0729921 T 0.0251969 0.0267717 e s
1 0 2.2098425 3.6456299 T 0.0570866 0.0452756 e s
1 0 2.1398425 3.6641339 T 0.0251969 0.0267717 e s
1 0 4.3326771 3.6033465 T 0.0393701 0.0334646 e s
1 0 2.809252 3.7503543 T 0.019685 0.0354331 e s
1 0 2.694252 3.7503543 T 0.019685 0.0354331 e s
1 0 3.219252 3.7503543 T 0.019685 0.0354331 e s
1 0 3.5898425 3.8525197 T 0.0334646 0.0393701 e s
1 0 3.5898425 3.7846063 T 0.0334646 0.0393701 e s
1 0 0.6448425 4.2546063 T 0.0334646 0.0393701 e s
1 0 0.8465091 4.2546063 T 0.0334646 0.0393701 e s
1 0 1.0481757 4.2546063 T 0.0334646 0.0393701 e s
1 0 4.4348425 2.7898819 T 0.0385827 0.034252 e s
1 0 2.1468425 2.6792283 T 0.0393701 0.0283465 e s
1 0 4.7070078 4.206063 T 0.0283465 0.0393701 e s
1 0 5.2670078 4.206063 T 0.0283465 0.0393701 e s
1 0 2.3348425 3.640748 T 0.082874 0.0440945 e s
1 0 6.1228425 2.4882283 T 0.0393701 0.0283465 e s
1 0 2.3348425 3.0428426 D 0.082874 0.0440945 e p
1 0 2.3519134 2.854063 D 0.0267717 0.0251969 e p
1 0 2.3274094 2.944063 D 0.0452756 0.0570866 e p
1 0.004 2.1468425 2.753063 B e e staggered 0 0 0 v
1 0.004 4.5036614 2.7898819 B e e staggered 0 0 0 v
1 0.004 2.5708425 4.283063 B e e staggered 0 0 0 v
1 0.004 3.5398425 3.806063 B e e staggered 0 0 0 v
1 0.004 3.2198425 3.806063 B e e staggered 0 0 0 v
1 0.004 2.7224094 3.7860709 B e e staggered 0 0 0 v
1 0.004 2.1398425 3.611063 B e e staggered 0 0 0 v
1 0.004 1.2948425 4.256063 B e e staggered 0 0 0 v
1 0.004 5.2748425 3.511063 B e e staggered 0 0 0 v
1 0.004 6.2848425 2.501063 B e e staggered 0 0 0 v
2 0 2.7568898 3.2372047 T 0.0787402 0.023622 e s
2 0 3.5693307 3.2062205 T 0.0393701 0.0708661 e s
2 0 3.5311023 3.0517874 T 0.0413386 0.0452756 e s
2 0 3.5320078 2.797063 T 0.0283465 0.0393701 e s
2 0 4.1498425 2.8422441 T 0.0385827 0.034252 e s
2 0 4.0398425 3.029567 T 0.0374016 0.0393701 e s
2 0 4.1098425 3.0441338 T 0.0251969 0.0267717 e s
2 0 3.2691732 2.8346456 T 0.0108268 0.0098425 e s
2 0 3.2293307 2.7849212 T 0.0098425 0.0108268 e s
2 0 3.2490157 2.845 T 0.0098425 0.0108268 e s
2 0 3.6938425 3.1884961 T 0.0570866 0.0452756 e s
2 0 3.7698425 3.2349922 T 0.0251969 0.0267717 e s
2 0 3.6888425 3.266567 T 0.0374016 0.0393701 e s
2 0 4.2802756 3.246063 T 0.0452756 0.0570866 e s
2 0 4.4548425 3.0441338 T 0.0251969 0.0267717 e s
2 0 4.3948425 3.0441338 T 0.0251969 0.0267717 e s
2 0 4.3348425 3.0441338 T 0.0251969 0.0267717 e s
2 0 4.2748425 3.0441338 T 0.0251969 0.0267717 e s
2 0 4.2198425 3.0441338 T 0.0251969 0.0267717 e s
2 0 4.1648425 3.0441338 T 0.0251969 0.0267717 e s
2 0 4.0648425 2.8514961 T 0.0570866 0.0452756 e s
2 0 3.9598425 2.8514961 T 0.0570866 0.0452756 e s
2 0.0206693 5.3277559 2.3074803 B e e staggered 0 0 0
3 0 2.0728351 0.1377953 T 0.028 0.165 e s
3 0 2.1122051 0.1377953 D 0.028 0.165 e p
3 0 2.1515751 0.1377953 D 0.028 0.165 e p
3 0.004 2.0767716 0.2559055 B e e staggered 0 0 0 v
3 0.004 2.0767716 0.2874016 B e e staggered 0 0 0 v
3 0.004 2.1122047 0.2874016 B e e staggered 0 0 0 v
3 0.004 2.1515748 0.2874016 B e e staggered 0 0 0 v
3 0.004 2.1122047 0.2559055 B e e staggered 0 0 0 v
3 0.004 2.1515748 0.2559055 B e e staggered 0 0 0 v
4 0 1.8461259 4.099563 T 0.0570866 0.0177165 e s
4 0 3.4920225 2.087353 T 0.06102 0.00984 e s
4 0 3.4920225 2.067663 T 0.06102 0.00984 e s
4 0 3.4920225 2.047983 T 0.06102 0.00984 e s
4 0 3.4920225 2.028293 T 0.06102 0.00984 e s
4 0 3.6514625 2.087353 T 0.06102 0.00984 e s
4 0 3.6514625 2.067663 T 0.06102 0.00984 e s
4 0 3.6514625 2.047983 T 0.06102 0.00984 e s
4 0 3.6514625 2.028293 T 0.06102 0.00984 e s
4 0 6.7002756 1.421063 T 0.0452756 0.0570866 e s
4 0 6.7002756 1.531063 T 0.0452756 0.0570866 e s
4 0 6.6767716 1.611063 T 0.0267717 0.0251969 e s
4 0 6.6767716 1.671063 T 0.0267717 0.0251969 e s
4 0 6.6767716 1.721063 T 0.0267717 0.0251969 e s
4 0 6.6767716 1.776063 T 0.0267717 0.0251969 e s
4 0 2.6398425 3.6064961 T 0.0570866 0.0452756 e s
4 0 2.7248425 3.5929921 T 0.0251969 0.0267717 e s
4 0 3.7302756 0.726063 T 0.0452756 0.0570866 e s
4 0 3.7167716 0.636063 T 0.0267717 0.0251969 e s
4 0 6.3198425 1.4601181 T 0.2125984 0.1141732 e s
4 0 6.8426771 1.816063 T 0.0283465 0.0393701 e s
4 0 2.5098425 3.640748 T 0.082874 0.0440945 e s
4 0 1.9338425 4.1292284 T 0.0393701 0.0283465 e s
4 0 1.6643465 4.273063 T 0.0393701 0.0374016 e s
4 0 1.8732756 4.276063 T 0.0452756 0.0570866 e s
4 0.025 3.9797272 0.8906186 B e e staggered 0 0 0
4 0 2.5098425 3.0428426 D 0.082874 0.0440945 e p
4 0 2.7118425 3.0369921 D 0.0251969 0.0267717 e p
4 0 2.6328425 3.0424961 D 0.0570866 0.0452756 e p
4 0.004 3.5718425 2.033063 B e e staggered 0 0 0 v
4 0.004 3.5718425 2.058063 B e e staggered 0 0 0 v
4 0.004 1.5578425 4.229063 B e e staggered 0 0 0 v
4 0.004 2.7748425 3.566063 B e e staggered 0 0 0 v
4 0.004 4.2548425 3.776063 B e e staggered 0 0 0 v
4 0.004 6.8448425 1.661063 B e e staggered 0 0 0 v
5 0 6.3522834 2.291063 T 0.0775591 0.0224409 e s
5 0 6.0356772 3.556063 T 0.0283465 0.0393701 e s
5 0 5.8120079 3.3612205 T 0.0452756 0.0570866 e s
5 0 5.6344488 3.359252 T 0.0267717 0.0251969 e s
5 0 6.3348425 2.1814961 T 0.0570866 0.0452756 e s
5 0 6.6598425 2.0956299 T 0.0570866 0.0452756 e s
5 0 6.7498425 2.1432283 T 0.0393701 0.0283465 e s
5 0 6.2348425 2.1288977 T 0.0393701 0.0283465 e s
5 0 6.6374016 1.981063 T 0.0775591 0.0224409 e s
5 0.004 5.9948425 3.552063 B e e staggered 0 0 0 v
5 0.004 6.4248425 2.181063 B e e staggered 0 0 0 v
6 0 6.3416929 3.701063 T 0.0255906 0.0413386 e s
6 0 1.7972451 0.1377953 T 0.028 0.165 e s
6 0 1.8366151 0.1377953 T 0.028 0.165 e s
6 0 1.8759851 0.1377953 T 0.028 0.165 e s
6 0 1.8366151 0.1377953 D 0.028 0.165 e p
6 0 1.8759851 0.1377953 D 0.028 0.165 e p
6 0.004 1.8326771 0.2559055 B e e staggered 0 0 0 v
6 0.004 1.8523622 0.2559055 B e e staggered 0 0 0 v
6 0.004 1.8720472 0.2559055 B e e staggered 0 0 0 v
6 0.004 1.8326771 0.2874016 B e e staggered 0 0 0 v
6 0.004 1.8523622 0.2874016 B e e staggered 0 0 0 v
6 0.004 1.8720472 0.2874016 B e e staggered 0 0 0 v
6 0.004 1.8498425 3.701063 B e e staggered 0 0 0 v
6 0.004 6.2948425 3.701063 B e e staggered 0 0 0 v
7 0 3.5102756 3.3951969 T 0.0393701 0.0708661 e s
7 0 2.8232125 2.518253 T 0.00984 0.06102 e s
7 0.004 2.8218425 2.601063 B e e staggered 0 0 0 v
7 0.004 3.6238425 2.587063 B e e staggered 0 0 0 v
7 0.004 3.6228425 3.486063 B e e staggered 0 0 0 v
8 0 2.4098225 2.358813 T 0.00984 0.06102 e s
8 0 0.5948031 2.481063 T 0.0413386 0.0393701 e s
8 0 0.9326378 2.481063 T 0.0964567 0.1240157 e s
8 0 0.9084645 2.2844487 T 0.0275591 0.0354331 e s
8 0.03 0.1998425 2.481063 B e e staggered 0 0 0
8 0.004 2.4098425 2.314063 B e e staggered 0 0 0 v
8 0.004 1.0208425 2.481063 B e e staggered 0 0 0 v
9 0 2.4295125 2.358813 T 0.00984 0.06102 e s
9 0 0.5948031 1.956063 T 0.0413386 0.0393701 e s
9 0 0.9326378 1.956063 T 0.0964567 0.1240157 e s
9 0 0.9005905 1.7470472 T 0.0275591 0.0354331 e s
9 0.03 0.1998425 1.956063 B e e staggered 0 0 0
9 0.004 2.4098425 2.283063 B e e staggered 0 0 0 v
9 0.004 2.4098425 1.967063 B e e staggered 0 0 0 v
9 0.004 1.0098425 1.956063 B e e staggered 0 0 0 v
10 0 2.4491925 2.358813 T 0.00984 0.06102 e s
10 0 0.5948031 1.431063 T 0.0413386 0.0393701 e s
10 0 0.9326378 1.431063 T 0.0964567 0.1240157 e s
10 0 0.9045275 1.2244094 T 0.0275591 0.0354331 e s
10 0.03 0.1998425 1.431063 B e e staggered 0 0 0
10 0.004 2.4508425 2.282063 B e e staggered 0 0 0 v
10 0.004 2.4468425 1.437063 B e e staggered 0 0 0 v
10 0.004 1.0088425 1.430063 B e e staggered 0 0 0 v
11 0 0.5948031 0.906063 T 0.0413386 0.0393701 e s
11 0 0.9015747 0.7185038 T 0.0275591 0.0354331 e s
11 0 0.9326378 0.906063 T 0.0964567 0.1240157 e s
11 0 2.4688825 2.358813 T 0.00984 0.06102 e s
11 0.03 0.1998425 0.906063 B e e staggered 0 0 0
11 0.004 2.4758425 2.291063 B e e staggered 0 0 0 v
11 0.004 2.4788425 0.937063 B e e staggered 0 0 0 v
11 0.004 1.0048425 0.906063 B e e staggered 0 0 0 v
12 0 6.459685 3.3321063 T 0.0098425 0.0226378 e s
12 0 3.4920225 1.831443 T 0.06102 0.00984 e s
12 0.004 3.3291721 1.826063 B e e staggered 0 0 0 v
12 0.004 3.3948425 3.447063 B e e staggered 0 0 0 v
12 0.004 6.4475772 3.396063 B e e staggered 0 0 0 v
13 0 3.5311023 2.8923386 T 0.0413386 0.0452756 e s
13 0 2.5279325 2.518253 T 0.00984 0.06102 e s
14 0 3.3331103 3.2062205 T 0.0393701 0.0708661 e s
14 0 2.3507725 2.518253 T 0.00984 0.06102 e s
14 0.004 2.394685 2.7204724 B e e staggered 0 0 0 v
14 0.004 3.2755905 3.1417323 B e e staggered 0 0 0 v
15 0 1.7765525 2.067703 T 0.06102 0.00984 e s
15 0 2.8348425 3.6617716 T 0.019685 0.0354331 e s
15 0 2.9448425 3.6666929 T 0.0570866 0.0374016 e s
15 0.004 1.8848425 2.071063 B e e staggered 0 0 0 v
15 0.004 2.7998425 3.616063 B e e staggered 0 0 0 v
15 0.004 1.8848425 3.601063 B e e staggered 0 0 0 v
16 0 3.4698425 3.6617716 T 0.019685 0.0354331 e s
16 0 3.3498425 3.6666929 T 0.0570866 0.0374016 e s
16 0 1.6171125 2.067703 T 0.06102 0.00984 e s
16 0.004 1.5682025 2.067703 B e e staggered 0 0 0 v
16 0.004 3.4248425 3.636063 B e e staggered 0 0 0 v
16 0.004 1.5498425 3.621063 B e e staggered 0 0 0 v
17 0 1.7765525 2.087393 T 0.06102 0.00984 e s
17 0 2.7198425 3.6617716 T 0.019685 0.0354331 e s
17 0 3.0448425 3.6666929 T 0.0570866 0.0374016 e s
17 0.004 1.7548425 2.126063 B e e staggered 0 0 0 v
17 0.004 1.7548425 3.661063 B e e staggered 0 0 0 v
17 0.004 2.6798425 3.661063 B e e staggered 0 0 0 v
18 0 1.6171125 2.087393 T 0.06102 0.00984 e s
18 0 3.2448425 3.6617716 T 0.019685 0.0354331 e s
18 0 3.1448425 3.6666929 T 0.0570866 0.0374016 e s
18 0.004 1.6198425 2.121063 B e e staggered 0 0 0 v
18 0.004 3.2398425 3.596063 B e e staggered 0 0 0 v
18 0.004 1.5748425 3.596063 B e e staggered 0 0 0 v
19 0 3.1112205 3.1372047 T 0.0787402 0.023622 e s
19 0 2.2813858 4.1703386 T 0.0177165 0.0543307 e s
19 0 3.8084646 4.0237008 T 0.019685 0.0905512 e s
19 0 0.6548425 0.9641339 T 0.0866142 0.0413386 e s
19 0 0.6548425 0.8479921 T 0.0866142 0.0413386 e s
19 0 3.4954331 3.7503543 T 0.019685 0.0354331 e s
19 0 1.8461259 4.124563 T 0.0570866 0.0177165 e s
19 0 1.631559 4.099563 T 0.0570866 0.0177165 e s
19 0 6.3522834 2.391063 T 0.0775591 0.0224409 e s
19 0 3.3331103 3.3951969 T 0.0393701 0.0708661 e s
19 0 3.4385827 2.8923386 T 0.0413386 0.0452756 e s
19 0 3.3448425 4.2211417 T 0.05 0.2 e s
19 0 2.9448425 4.2211417 T 0.05 0.2 e s
19 0 2.5452751 0.1377953 T 0.028 0.165 e s
19 0 2.4665351 0.1377953 T 0.028 0.165 e s
19 0 2.3484251 0.1377953 T 0.028 0.165 e s
19 0 2.8208651 0.1377953 T 0.028 0.165 e s
19 0 1.9153551 0.1377953 T 0.028 0.165 e s
19 0 2.0334651 0.1377953 T 0.028 0.165 e s
19 0 2.6633851 0.1377953 T 0.028 0.165 e s
19 0 2.7027551 0.1377953 T 0.028 0.165 e s
19 0 2.8602351 0.1377953 T 0.028 0.165 e s
19 0 2.9783451 0.1377953 T 0.028 0.165 e s
19 0 3.0964551 0.1377953 T 0.028 0.165 e s
19 0 4.9579134 4.206063 T 0.0314961 0.0669291 e s
19 0 3.9114214 1.6596232 T 0.0708661 0.0098425 e s
19 0 4.0689017 1.6796232 T 0.0708661 0.0098425 e s
19 0 4.0689017 1.7396232 T 0.0708661 0.0098425 e s
19 0 6.5113582 3.2312205 T 0.0265748 0.0098425 e s
19 0 6.4793701 3.1500197 T 0.0098425 0.0226378 e s
19 0 4.9094488 3.9616142 T 0.1653543 0.1259843 e s
19 0 1.1570472 0.906063 T 0.0964567 0.1240157 e s
19 0 4.3398425 2.7806299 T 0.0570866 0.0452756 e s
19 0 4.0398425 3.0925591 T 0.0374016 0.0393701 e s
19 0 4.1098425 3.0779921 T 0.0251969 0.0267717 e s
19 0 3.2691732 2.8149606 T 0.0108268 0.0098425 e s
19 0 3.2691732 2.7952756 T 0.0108268 0.0098425 e s
19 0 3.2091732 2.8346456 T 0.0108268 0.0098425 e s
19 0 3.4920225 2.008613 T 0.06102 0.00984 e s
19 0 3.4920225 1.910183 T 0.06102 0.00984 e s
19 0 3.4920225 1.811763 T 0.06102 0.00984 e s
19 0 3.4920225 1.713333 T 0.06102 0.00984 e s
19 0 3.4920225 1.614913 T 0.06102 0.00984 e s
19 0 3.4920225 1.516483 T 0.06102 0.00984 e s
19 0 3.4920225 1.418063 T 0.06102 0.00984 e s
19 0 3.6514625 2.008613 T 0.06102 0.00984 e s
19 0 3.6514625 1.910183 T 0.06102 0.00984 e s
19 0 3.6514625 1.811763 T 0.06102 0.00984 e s
19 0 3.6514625 1.713333 T 0.06102 0.00984 e s
19 0 3.6514625 1.614913 T 0.06102 0.00984 e s
19 0 3.6514625 1.516483 T 0.06102 0.00984 e s
19 0 3.6514625 1.418063 T 0.06102 0.00984 e s
19 0 2.8822625 2.518253 T 0.00984 0.06102 e s
19 0 2.7838425 2.518253 T 0.00984 0.06102 e s
19 0 2.6854125 2.518253 T 0.00984 0.06102 e s
19 0 2.5869925 2.518253 T 0.00984 0.06102 e s
19 0 2.4885625 2.518253 T 0.00984 0.06102 e s
19 0 2.3901425 2.518253 T 0.00984 0.06102 e s
19 0 2.2917125 2.518253 T 0.00984 0.06102 e s
19 0 2.8822625 2.358813 T 0.00984 0.06102 e s
19 0 2.7838425 2.358813 T 0.00984 0.06102 e s
19 0 2.6854125 2.358813 T 0.00984 0.06102 e s
19 0 2.5869925 2.358813 T 0.00984 0.06102 e s
19 0 2.4885625 2.358813 T 0.00984 0.06102 e s
19 0 2.3901425 2.358813 T 0.00984 0.06102 e s
19 0 2.2917125 2.358813 T 0.00984 0.06102 e s
19 0 1.7765525 1.398413 T 0.06102 0.00984 e s
19 0 1.7765525 1.496843 T 0.06102 0.00984 e s
19 0 1.7765525 1.595263 T 0.06102 0.00984 e s
19 0 1.7765525 1.693693 T 0.06102 0.00984 e s
19 0 1.7765525 1.792113 T 0.06102 0.00984 e s
19 0 1.7765525 1.890543 T 0.06102 0.00984 e s
19 0 1.7765525 1.988963 T 0.06102 0.00984 e s
19 0 1.6171125 1.398413 T 0.06102 0.00984 e s
19 0 1.6171125 1.496843 T 0.06102 0.00984 e s
19 0 1.6171125 1.595263 T 0.06102 0.00984 e s
19 0 1.6171125 1.693693 T 0.06102 0.00984 e s
19 0 1.6171125 1.792113 T 0.06102 0.00984 e s
19 0 1.6171125 1.890543 T 0.06102 0.00984 e s
19 0 1.6171125 1.988963 T 0.06102 0.00984 e s
19 0 2.9019625 1.038313 T 0.00984 0.06102 e s
19 0 2.8429025 1.038313 T 0.00984 0.06102 e s
19 0 2.7838525 1.038313 T 0.00984 0.06102 e s
19 0 2.7247925 1.038313 T 0.00984 0.06102 e s
19 0 2.6657425 1.038313 T 0.00984 0.06102 e s
19 0 2.6066825 1.038313 T 0.00984 0.06102 e s
19 0 2.5082625 1.038313 T 0.00984 0.06102 e s
19 0 2.4098325 1.038313 T 0.00984 0.06102 e s
19 0 2.3114125 1.038313 T 0.00984 0.06102 e s
19 0 2.9019625 0.878873 T 0.00984 0.06102 e s
19 0 2.6066825 0.878873 T 0.00984 0.06102 e s
19 0 2.5082625 0.878873 T 0.00984 0.06102 e s
19 0 2.4098325 0.878873 T 0.00984 0.06102 e s
19 0 2.3114125 0.878873 T 0.00984 0.06102 e s
19 0 0.6548425 1.8979921 T 0.0866142 0.0413386 e s
19 0 0.6548425 2.0141339 T 0.0866142 0.0413386 e s
19 0 0.6548425 2.4229921 T 0.0866142 0.0413386 e s
19 0 0.6548425 2.5391339 T 0.0866142 0.0413386 e s
19 0 0.6548425 1.4891339 T 0.0866142 0.0413386 e s
19 0 0.6548425 1.3729921 T 0.0866142 0.0413386 e s
19 0 5.7411417 3.3612205 T 0.0452756 0.0570866 e s
19 0 5.6683071 3.359252 T 0.0267717 0.0251969 e s
19 0 6.3348425 2.1106299 T 0.0570866 0.0452756 e s
19 0 6.6598425 2.1664961 T 0.0570866 0.0452756 e s
19 0 6.253937 2.8267717 T 0.0570866 0.0452756 e s
19 0 6.3720472 2.8267717 T 0.0570866 0.0452756 e s
19 0 6.3617717 2.656063 T 0.0267717 0.0251969 e s
19 0 6.3617717 2.501063 T 0.0267717 0.0251969 e s
19 0 6.3617717 2.556063 T 0.0267717 0.0251969 e s
19 0 6.3617717 2.611063 T 0.0267717 0.0251969 e s
19 0 6.6294094 1.421063 T 0.0452756 0.0570866 e s
19 0 6.6294094 1.531063 T 0.0452756 0.0570866 e s
19 0 6.6429133 1.611063 T 0.0267717 0.0251969 e s
19 0 6.6429133 1.671063 T 0.0267717 0.0251969 e s
19 0 6.6429133 1.721063 T 0.0267717 0.0251969 e s
19 0 6.6429133 1.776063 T 0.0267717 0.0251969 e s
19 0 6.9063386 2.096063 T 0.0393701 0.0374016 e s
19 0 6.0933464 2.171063 T 0.0393701 0.0374016 e s
19 0 4.1048425 3.8414961 T 0.0570866 0.0452756 e s
19 0 4.1948425 3.8375591 T 0.0374016 0.0393701 e s
19 0 6.4394094 3.071063 T 0.0452756 0.0570866 e s
19 0 6.5848425 3.0391338 T 0.0251969 0.0267717 e s
19 0 2.2098425 3.7164961 T 0.0570866 0.0452756 e s
19 0 2.1398425 3.6979922 T 0.0251969 0.0267717 e s
19 0 2.6398425 3.5356299 T 0.0570866 0.0452756 e s
19 0 2.7248425 3.5591338 T 0.0251969 0.0267717 e s
19 0 3.6594094 0.726063 T 0.0452756 0.0570866 e s
19 0 3.6829133 0.636063 T 0.0267717 0.0251969 e s
19 0 3.6938425 3.1176299 T 0.0570866 0.0452756 e s
19 0 3.7698425 3.2011339 T 0.0251969 0.0267717 e s
19 0 3.6888425 3.3295591 T 0.0374016 0.0393701 e s
19 0 2.8604331 3.7503543 T 0.019685 0.0354331 e s
19 0 2.7454331 3.7503543 T 0.019685 0.0354331 e s
19 0 3.2704331 3.7503543 T 0.019685 0.0354331 e s
19 0 1.1570472 1.956063 T 0.0964567 0.1240157 e s
19 0 1.1570472 2.481063 T 0.0964567 0.1240157 e s
19 0 1.1570472 1.431063 T 0.0964567 0.1240157 e s
19 0 4.1505905 3.6033465 T 0.0283465 0.0393701 e s
19 0 6.7276771 1.816063 T 0.0283465 0.0393701 e s
19 0 6.3670079 2.451063 T 0.0283465 0.0393701 e s
19 0 7.0098425 1.9382284 T 0.0393701 0.0283465 e s
19 0 6.0048425 2.3932284 T 0.0393701 0.0283465 e s
19 0 4.4329134 4.206063 T 0.0314961 0.0669291 e s
19 0 6.6374016 1.881063 T 0.0775591 0.0224409 e s
19 0 3.9871259 3.783563 T 0.0570866 0.0177165 e s
19 0 3.772559 3.758563 T 0.0570866 0.0177165 e s
19 0 2.3348425 3.4045276 T 0.082874 0.0440945 e s
19 0 1.7273386 4.273063 T 0.0393701 0.0374016 e s
19 0 1.8024094 4.276063 T 0.0452756 0.0570866 e s
19 0 6.6048425 3.3275591 T 0.0374016 0.0393701 e s
19 0 6.6048425 3.1295669 T 0.0374016 0.0393701 e s
19 0 4.2094094 3.246063 T 0.0452756 0.0570866 e s
19 0 4.4548425 3.0779921 T 0.0251969 0.0267717 e s
19 0 4.3948425 3.0779921 T 0.0251969 0.0267717 e s
19 0 4.3348425 3.0779921 T 0.0251969 0.0267717 e s
19 0 4.2748425 3.0779921 T 0.0251969 0.0267717 e s
19 0 4.2198425 3.0779921 T 0.0251969 0.0267717 e s
19 0 4.1648425 3.0779921 T 0.0251969 0.0267717 e s
19 0 4.0648425 2.7806299 T 0.0570866 0.0452756 e s
19 0 3.9598425 2.7806299 T 0.0570866 0.0452756 e s
19 0 4.2348425 2.7806299 T 0.0570866 0.0452756 e s
19 0.0206693 5.1277559 2.3074803 B e e staggered 0 0 0
19 0.025 5.5781524 1.6898312 B e e staggered 0 0 0
19 0.025 3.9797272 2.4890438 B e e staggered 0 0 0
19 0.019685 5.9348031 3.9379527 B e e staggered 0 0 0
19 0.019685 6.1198425 4.056063 B e e staggered 0 0 0
19 0.034 0.2998425 1.006063 B e e staggered 0 0 0
19 0.034 0.2998425 0.806063 B e e staggered 0 0 0
19 0.034 0.0998425 0.806063 B e e staggered 0 0 0
19 0.034 0.0998425 1.006063 B e e staggered 0 0 0
19 0.035433 6.9001969 3.5895276 B e e staggered 0 0 0
19 0.035433 6.7348425 3.5895276 B e e staggered 0 0 0
19 0.035433 6.5694882 3.5895276 B e e staggered 0 0 0
19 0.034 0.2998425 2.581063 B e e staggered 0 0 0
19 0.034 0.2998425 2.381063 B e e staggered 0 0 0
19 0.034 0.0998425 2.381063 B e e staggered 0 0 0
19 0.034 0.0998425 2.581063 B e e staggered 0 0 0
19 0.034 0.2998425 2.056063 B e e staggered 0 0 0
19 0.034 0.2998425 1.856063 B e e staggered 0 0 0
19 0.034 0.0998425 1.856063 B e e staggered 0 0 0
19 0.034 0.0998425 2.056063 B e e staggered 0 0 0
19 0.034 0.2998425 1.531063 B e e staggered 0 0 0
19 0.034 0.2998425 1.331063 B e e staggered 0 0 0
19 0.034 0.0998425 1.331063 B e e staggered 0 0 0
19 0.034 0.0998425 1.531063 B e e staggered 0 0 0
19 0 2.3348425 3.279063 D 0.082874 0.0440945 e p
19 0 1.9153551 0.1377953 D 0.028 0.165 e p
19 0 2.5452751 0.1377953 D 0.028 0.165 e p
19 0 2.6240151 0.1377953 D 0.028 0.165 e p
19 0 2.8996051 0.1377953 D 0.028 0.165 e p
19 0 3.0570851 0.1377953 D 0.028 0.165 e p
19 0 2.7421251 0.1377953 D 0.028 0.165 e p
19 0 2.9389751 0.1377953 D 0.028 0.165 e p
19 0 2.7814951 0.1377953 D 0.028 0.165 e p
19 0 2.3090551 0.1377953 D 0.028 0.165 e p
19 0 2.4271651 0.1377953 D 0.028 0.165 e p
19 0 2.7118425 3.0031338 D 0.0251969 0.0267717 e p
19 0 2.6328425 2.9716299 D 0.0570866 0.0452756 e p
19 0 2.3857717 2.854063 D 0.0267717 0.0251969 e p
19 0 2.3982756 2.944063 D 0.0452756 0.0570866 e p
19 0.004 4.0398425 3.784063 B e e staggered 0 0 0 v
19 0.0629922 2.531398 3.853669 B e e staggered 0 0 0 v
19 0.0629922 2.531398 2.830047 B e e staggered 0 0 0 v
19 0.0629922 0.149508 2.830047 B e e staggered 0 0 0 v
19 0.0629922 0.149508 3.853669 B e e staggered 0 0 0 v
19 0.004 2.8782843 0.2495967 B e e staggered 0 0 0 v
19 0.004 2.9574751 0.2519685 B e e staggered 0 0 0 v
19 0.004 2.4470546 0.2425914 B e e staggered 0 0 0 v
19 0.004 2.6066825 0.931903 B e e staggered 0 0 0 v
19 0.004 2.636874 0.2479055 B e e staggered 0 0 0 v
19 0.004 2.7999951 0.2519685 B e e staggered 0 0 0 v
19 0.004 2.4098325 1.088053 B e e staggered 0 0 0 v
19 0.004 2.3114125 1.0900094 B e e staggered 0 0 0 v
19 0.004 2.5082625 0.931483 B e e staggered 0 0 0 v
19 0.004 2.4098325 0.932053 B e e staggered 0 0 0 v
19 0.004 2.7244825 1.093063 B e e staggered 0 0 0 v
19 0.004 2.7841625 1.094063 B e e staggered 0 0 0 v
19 0.004 2.8428425 1.095063 B e e staggered 0 0 0 v
19 0.004 2.5460625 0.244843 B e e staggered 0 0 0 v
19 0.004 3.0974409 0.2519685 B e e staggered 0 0 0 v
19 0.004 2.6068425 1.091063 B e e staggered 0 0 0 v
19 0.004 3.5548425 1.841063 B e e staggered 0 0 0 v
19 0.004 3.7198425 1.996063 B e e staggered 0 0 0 v
19 0.004 1.7218425 1.890063 B e e staggered 0 0 0 v
19 0.004 1.6718425 1.792063 B e e staggered 0 0 0 v
19 0.004 1.6748425 1.989063 B e e staggered 0 0 0 v
19 0.004 2.5088425 1.090063 B e e staggered 0 0 0 v
19 0.004 3.4138425 1.573063 B e e staggered 0 0 0 v
19 0.004 1.6708425 1.595063 B e e staggered 0 0 0 v
19 0.004 2.4098425 2.579063 B e e staggered 0 0 0 v
19 0.004 2.5868425 2.569063 B e e staggered 0 0 0 v
19 0.004 1.7188425 1.792063 B e e staggered 0 0 0 v
19 0.004 2.8818425 2.566063 B e e staggered 0 0 0 v
19 0.004 3.7328425 1.418063 B e e staggered 0 0 0 v
19 0.004 2.2538425 2.279063 B e e staggered 0 0 0 v
19 0.004 2.3118425 0.934063 B e e staggered 0 0 0 v
19 0.004 3.5548425 1.991063 B e e staggered 0 0 0 v
19 0.004 1.6758425 1.891063 B e e staggered 0 0 0 v
19 0.004 2.7838425 2.429063 B e e staggered 0 0 0 v
19 0.004 3.7198425 1.921063 B e e staggered 0 0 0 v
19 0.004 2.6658425 1.092063 B e e staggered 0 0 0 v
19 0.004 2.4758425 2.456063 B e e staggered 0 0 0 v
19 0.004 3.4144661 1.805063 B e e staggered 0 0 0 v
19 0.004 2.6858425 2.311063 B e e staggered 0 0 0 v
19 0.004 3.5908425 1.662063 B e e staggered 0 0 0 v
19 0.004 2.4048425 2.412063 B e e staggered 0 0 0 v
19 0.004 1.7168425 1.399063 B e e staggered 0 0 0 v
19 0.004 1.7218425 1.989063 B e e staggered 0 0 0 v
19 0.004 3.5498425 1.413063 B e e staggered 0 0 0 v
19 0.004 2.4888425 2.413063 B e e staggered 0 0 0 v
19 0.004 1.6708425 1.694063 B e e staggered 0 0 0 v
19 0.004 2.9018425 1.095063 B e e staggered 0 0 0 v
19 0.004 3.5948425 1.514063 B e e staggered 0 0 0 v
19 0.004 3.4068425 1.461063 B e e staggered 0 0 0 v
19 0.004 3.4108425 1.7136509 B e e staggered 0 0 0 v
19 0.004 2.9338425 0.953063 B e e staggered 0 0 0 v
19 0.004 2.8718425 2.297063 B e e staggered 0 0 0 v
19 0.004 2.6858425 2.568063 B e e staggered 0 0 0 v
19 0.004 3.5548425 1.941063 B e e staggered 0 0 0 v
19 0.004 2.7838425 2.568063 B e e staggered 0 0 0 v
19 0.004 3.7188425 1.713063 B e e staggered 0 0 0 v
19 0.004 1.7218425 1.694063 B e e staggered 0 0 0 v
19 0.004 1.6718425 1.399063 B e e staggered 0 0 0 v
19 0.004 2.5818425 2.308063 B e e staggered 0 0 0 v
19 0.004 1.7188425 1.497063 B e e staggered 0 0 0 v
19 0.004 1.7148425 1.595063 B e e staggered 0 0 0 v
19 0.004 1.6718425 1.497063 B e e staggered 0 0 0 v
19 0.004 2.3215354 2.586063 B e e staggered 0 0 0 v
19 0.004 2.0348425 0.246063 B e e staggered 0 0 0 v
19 0.004 1.9161425 0.244763 B e e staggered 0 0 0 v
19 0.004 2.3098425 0.246063 B e e staggered 0 0 0 v
19 0.004 3.3308425 3.301063 B e e staggered 0 0 0 v
19 0.004 4.1203866 3.5941508 B e e staggered 0 0 0 v
19 0.004 3.1830708 3.1358268 B e e staggered 0 0 0 v
19 0.004 3.277559 2.9635827 B e e staggered 0 0 0 v
19 0.004 2.4192759 2.7886295 B e e staggered 0 0 0 v
19 0.004 2.4138425 3.295063 B e e staggered 0 0 0 v
19 0.004 2.3215354 3.361063 B e e staggered 0 0 0 v
19 0.004 2.6318425 2.876063 B e e staggered 0 0 0 v
19 0.004 2.4738425 2.980063 B e e staggered 0 0 0 v
19 0.004 0.9370078 2.3179133 B e e staggered 0 0 0 v
19 0.004 1.7268425 4.329374 B e e staggered 0 0 0 v
19 0.004 1.7888425 4.329374 B e e staggered 0 0 0 v
19 0.004 4.4778425 3.135063 B e e staggered 0 0 0 v
19 0.004 4.0648425 2.722063 B e e staggered 0 0 0 v
19 0.004 6.6288425 1.372063 B e e staggered 0 0 0 v
19 0.004 6.9744094 1.9399606 B e e staggered 0 0 0 v
19 0.004 3.9688425 1.671063 B e e staggered 0 0 0 v
19 0.004 4.1318425 1.686063 B e e staggered 0 0 0 v
19 0.004 3.9968425 1.711063 B e e staggered 0 0 0 v
19 0.004 3.9608425 2.724063 B e e staggered 0 0 0 v
19 0.004 6.253937 2.9094488 B e e staggered 0 0 0 v
19 0.004 6.6476378 3.1299213 B e e staggered 0 0 0 v
19 0.004 4.3398425 2.725063 B e e staggered 0 0 0 v
19 0.004 3.8308425 3.762063 B e e staggered 0 0 0 v
19 0.004 3.3958425 4.222063 B e e staggered 0 0 0 v
19 0.004 4.2728425 3.135063 B e e staggered 0 0 0 v
19 0.004 2.1398425 3.738063 B e e staggered 0 0 0 v
19 0.004 4.2088425 3.135063 B e e staggered 0 0 0 v
19 0.004 6.6268425 3.032063 B e e staggered 0 0 0 v
19 0.004 4.1528425 3.135063 B e e staggered 0 0 0 v
19 0.004 2.7248425 3.521063 B e e staggered 0 0 0 v
19 0.004 1.2488425 2.000063 B e e staggered 0 0 0 v
19 0.004 4.0688425 3.135063 B e e staggered 0 0 0 v
19 0.004 2.6748425 3.501063 B e e staggered 0 0 0 v
19 0.004 4.2348425 2.725063 B e e staggered 0 0 0 v
19 0.004 6.4568425 3.009063 B e e staggered 0 0 0 v
19 0.004 1.6918425 4.079063 B e e staggered 0 0 0 v
19 0.004 3.6428425 0.636063 B e e staggered 0 0 0 v
19 0.004 6.4768425 3.231063 B e e staggered 0 0 0 v
19 0.004 4.3338425 3.135063 B e e staggered 0 0 0 v
19 0.004 1.2618425 2.482063 B e e staggered 0 0 0 v
19 0.004 4.1148425 3.135063 B e e staggered 0 0 0 v
19 0.004 6.6488425 3.341063 B e e staggered 0 0 0 v
19 0.004 2.8888425 4.221063 B e e staggered 0 0 0 v
19 0.004 3.3708425 2.888063 B e e staggered 0 0 0 v
19 0.004 2.2588425 3.741063 B e e staggered 0 0 0 v
19 0.004 1.7498425 4.110063 B e e staggered 0 0 0 v
19 0.004 2.2908425 4.217063 B e e staggered 0 0 0 v
19 0.004 3.8808425 3.109063 B e e staggered 0 0 0 v
19 0.004 3.7448425 3.342063 B e e staggered 0 0 0 v
19 0.004 3.7178425 3.072063 B e e staggered 0 0 0 v
19 0.004 5.7338425 3.556063 B e e staggered 0 0 0 v
19 0.004 5.6768425 3.546063 B e e staggered 0 0 0 v
19 0.004 3.6038425 0.682063 B e e staggered 0 0 0 v
19 0.004 6.5488425 1.531063 B e e staggered 0 0 0 v
19 0.004 6.6028425 1.612063 B e e staggered 0 0 0 v
19 0.004 6.6028425 1.672063 B e e staggered 0 0 0 v
19 0.004 6.6028425 1.722063 B e e staggered 0 0 0 v
19 0.004 6.6018425 1.777063 B e e staggered 0 0 0 v
19 0.004 6.6858425 1.828063 B e e staggered 0 0 0 v
19 0.004 6.6998425 1.881063 B e e staggered 0 0 0 v
19 0.004 6.9498425 2.095063 B e e staggered 0 0 0 v
19 0.004 6.6078425 2.176063 B e e staggered 0 0 0 v
19 0.004 6.3958425 2.111063 B e e staggered 0 0 0 v
19 0.004 6.0488425 2.171063 B e e staggered 0 0 0 v
19 0.004 6.0048425 2.434063 B e e staggered 0 0 0 v
19 0.004 6.2748425 2.391063 B e e staggered 0 0 0 v
19 0.004 6.3988425 2.453063 B e e staggered 0 0 0 v
19 0.004 6.3978425 2.501063 B e e staggered 0 0 0 v
19 0.004 6.3968425 2.556063 B e e staggered 0 0 0 v
19 0.004 6.3978425 2.610063 B e e staggered 0 0 0 v
19 0.004 6.3988425 2.657063 B e e staggered 0 0 0 v
19 0.004 6.3720472 2.9094488 B e e staggered 0 0 0 v
19 0.004 4.9108425 4.203063 B e e staggered 0 0 0 v
19 0.004 4.3878425 4.206063 B e e staggered 0 0 0 v
19 0.004 3.7778425 4.023063 B e e staggered 0 0 0 v
19 0.004 4.0858425 3.892063 B e e staggered 0 0 0 v
19 0.004 4.1948425 3.884063 B e e staggered 0 0 0 v
19 0.004 4.4318425 3.135063 B e e staggered 0 0 0 v
19 0.004 2.8608425 3.787063 B e e staggered 0 0 0 v
19 0.004 2.7248425 3.729063 B e e staggered 0 0 0 v
19 0.004 3.5318425 3.660063 B e e staggered 0 0 0 v
19 0.004 3.2698425 3.788063 B e e staggered 0 0 0 v
19 0.004 1.2428425 1.472063 B e e staggered 0 0 0 v
19 0.004 1.2568425 0.942063 B e e staggered 0 0 0 v
19 0.004 0.6548425 0.790063 B e e staggered 0 0 0 v
19 0.004 0.6558425 1.028063 B e e staggered 0 0 0 v
19 0.004 0.6548425 1.314063 B e e staggered 0 0 0 v
19 0.004 0.6538425 1.551063 B e e staggered 0 0 0 v
19 0.004 0.6548425 1.839063 B e e staggered 0 0 0 v
19 0.004 0.6548425 2.073063 B e e staggered 0 0 0 v
19 0.004 0.6548425 2.365063 B e e staggered 0 0 0 v
19 0.004 0.6539669 2.5938902 B e e staggered 0 0 0 v
20 0 3.6514625 1.890503 T 0.06102 0.00984 e s
20 0 2.3348425 3.5620079 T 0.082874 0.0440945 e s
20 0.004 3.5548425 1.891063 B e e staggered 0 0 0 v
20 0.004 2.2548425 3.536063 B e e staggered 0 0 0 v
20 0.004 2.2998425 1.916063 B e e staggered 0 0 0 v
21 0 2.9806925 2.358813 T 0.00984 0.06102 e s
21 0 2.5098425 3.4832677 T 0.082874 0.0440945 e s
21 0.015 2.0433071 4.257874 B e e staggered 0 0 0
21 0.004 2.9488425 2.456063 B e e staggered 0 0 0 v
21 0.004 2.5798425 3.486063 B e e staggered 0 0 0 v
21 0.004 2.5258425 2.463063 B e e staggered 0 0 0 v
22 0 0.9606298 0.7185038 T 0.0275591 0.0354331 e s
22 0 3.6514625 1.792073 T 0.06102 0.00984 e s
22 0 2.3348425 3.4832677 T 0.082874 0.0440945 e s
22 0 2.3877954 2.9586614 T 0.0354331 0.0275591 e s
22 0.004 3.8048425 1.840063 B e e staggered 0 0 0 v
22 0.004 1.3937008 1.8169291 B e e staggered 0 0 0 v
22 0.004 0.9901575 0.6870079 B e e staggered 0 0 0 v
22 0.004 2.3898425 3.481063 B e e staggered 0 0 0 v
22 0.004 2.3848425 1.941063 B e e staggered 0 0 0 v
23 0 3.6514625 1.772393 T 0.06102 0.00984 e s
23 0 2.5098425 3.4045276 T 0.082874 0.0440945 e s
23 0.004 3.7198425 1.766063 B e e staggered 0 0 0 v
23 0.004 2.6348425 3.406063 B e e staggered 0 0 0 v
23 0.004 2.5498425 1.755063 B e e staggered 0 0 0 v
24 0 2.9806925 2.518253 T 0.00984 0.06102 e s
24 0 2.5098425 3.5620079 T 0.082874 0.0440945 e s
24 0.015 1.4576771 4.253937 B e e staggered 0 0 0
24 0.004 2.9588425 2.621063 B e e staggered 0 0 0 v
24 0.004 2.4348425 3.546063 B e e staggered 0 0 0 v
24 0.004 1.4408425 3.557063 B e e staggered 0 0 0 v
24 0.004 2.4291925 2.621063 B e e staggered 0 0 0 v
25 0 3.4920225 1.752703 T 0.06102 0.00984 e s
25 0 2.3348425 3.1215827 D 0.082874 0.0440945 e p
25 0.004 3.1972633 1.714063 B e e staggered 0 0 0 v
25 0.004 3.1978425 2.970063 B e e staggered 0 0 0 v
25 0.004 2.4187174 3.1185066 B e e staggered 0 0 0 v
26 0 1.7765525 1.319673 T 0.06102 0.00984 e s
26 0 2.1515748 4.0748032 T 0.0354331 0.0275591 e s
26 0 2.5098425 3.2003229 D 0.082874 0.0440945 e p
26 0.004 1.7982283 1.3041339 B e e staggered 0 0 0 v
26 0.004 2.462374 3.1722441 B e e staggered 0 0 0 v
26 0.004 2.1460663 4.1037909 B e e staggered 0 0 0 v
26 0.004 1.4598425 3.147063 B e e staggered 0 0 0 v
26 0.004 2.5028425 1.316063 B e e staggered 0 0 0 v
27 0 3.4920225 1.673963 T 0.06102 0.00984 e s
27 0 2.3348425 3.2003229 D 0.082874 0.0440945 e p
27 0.004 3.2248425 1.6613472 B e e staggered 0 0 0 v
27 0.004 3.2308425 3.235063 B e e staggered 0 0 0 v
27 0.004 2.4140551 3.1998504 B e e staggered 0 0 0 v
28 0 3.4920225 1.654283 T 0.06102 0.00984 e s
28 0 2.5098425 3.279063 D 0.082874 0.0440945 e p
28 0.004 3.2528425 1.661063 B e e staggered 0 0 0 v
28 0.004 2.5908425 3.288063 B e e staggered 0 0 0 v
28 0.004 3.2636972 3.3039177 B e e staggered 0 0 0 v
29 0 1.6171125 1.319673 T 0.06102 0.00984 e s
29 0 1.3464567 4.1417323 T 0.0354331 0.0275591 e s
29 0 2.5098425 3.1215827 D 0.082874 0.0440945 e p
29 0.004 1.5679134 1.2854331 B e e staggered 0 0 0 v
29 0.004 2.5918425 3.1862205 B e e staggered 0 0 0 v
29 0.004 1.3454724 4.1751969 B e e staggered 0 0 0 v
29 0.004 2.2068425 1.298063 B e e staggered 0 0 0 v
29 0.004 2.2058425 3.200063 B e e staggered 0 0 0 v
30 0 6.44 3.1500197 T 0.0098425 0.0226378 e s
30 0 3.6514625 1.496803 T 0.06102 0.00984 e s
30 0.004 3.8648425 1.511063 B e e staggered 0 0 0 v
30 0.004 3.8298425 3.176063 B e e staggered 0 0 0 v
30 0.004 6.4398425 3.191063 B e e staggered 0 0 0 v
31 0 6.3883268 3.2312205 T 0.0265748 0.0098425 e s
31 0 3.6514625 1.477113 T 0.06102 0.00984 e s
31 0.004 3.8348425 1.481063 B e e staggered 0 0 0 v
31 0.004 6.3094161 3.199063 B e e staggered 0 0 0 v
31 0.004 3.7998425 3.201063 B e e staggered 0 0 0 v
32 0 6.3883268 3.3296457 T 0.0265748 0.0098425 e s
32 0 1.7765525 1.614953 T 0.06102 0.00984 e s
32 0.004 1.8938425 1.693063 B e e staggered 0 0 0 v
32 0.004 3.542865 3.3190405 B e e staggered 0 0 0 v
32 0.004 3.5898425 1.711063 B e e staggered 0 0 0 v
32 0.004 6.3547483 3.3311384 B e e staggered 0 0 0 v
33 0 6.4203149 3.3321063 T 0.0098425 0.0226378 e s
33 0 1.7765525 1.674003 T 0.06102 0.00984 e s
33 0.004 1.8227825 1.674003 B e e staggered 0 0 0 v
33 0.004 3.6538425 3.293063 B e e staggered 0 0 0 v
33 0.004 3.7248425 1.675063 B e e staggered 0 0 0 v
33 0.004 6.4448425 3.291063 B e e staggered 0 0 0 v
34 0 6.3883268 3.3099606 T 0.0265748 0.0098425 e s
34 0 3.6514625 1.654283 T 0.06102 0.00984 e s
34 0.004 3.7738632 1.6661021 B e e staggered 0 0 0 v
34 0.004 6.3348425 3.266063 B e e staggered 0 0 0 v
34 0.004 3.7448425 3.261063 B e e staggered 0 0 0 v
35 0 6.3883268 3.2509055 T 0.0265748 0.0098425 e s
35 0 3.6514625 1.634593 T 0.06102 0.00984 e s
35 0.004 3.8038425 1.691063 B e e staggered 0 0 0 v
35 0.004 6.2824161 3.226063 B e e staggered 0 0 0 v
35 0.004 3.8068425 3.235063 B e e staggered 0 0 0 v
36 0 6.3883268 3.1524803 T 0.0265748 0.0098425 e s
36 0 3.6514625 1.575543 T 0.06102 0.00984 e s
36 0.004 3.8948425 1.566063 B e e staggered 0 0 0 v
36 0.004 6.3398425 3.151063 B e e staggered 0 0 0 v
36 0.004 3.8548425 3.151063 B e e staggered 0 0 0 v
37 0 6.4203149 3.1500197 T 0.0098425 0.0226378 e s
37 0 3.6514625 1.555853 T 0.06102 0.00984 e s
37 0.004 3.9248425 1.536063 B e e staggered 0 0 0 v
37 0.004 6.3048425 3.121063 B e e staggered 0 0 0 v
37 0.004 3.9398425 3.121063 B e e staggered 0 0 0 v
38 0 1.7765525 1.536213 T 0.06102 0.00984 e s
38 0 4.7070079 4.121063 T 0.0283465 0.0393701 e s
38 0.004 1.7198425 1.536063 B e e staggered 0 0 0 v
38 0.004 4.7547119 4.1159324 B e e staggered 0 0 0 v
38 0.004 1.7798425 4.156063 B e e staggered 0 0 0 v
39 0 3.4920225 1.437743 T 0.06102 0.00984 e s
39 0 5.2670079 4.126063 T 0.0283465 0.0393701 e s
39 0.004 3.5498425 1.441063 B e e staggered 0 0 0 v
39 0.004 5.2670079 4.0888976 B e e staggered 0 0 0 v
39 0.004 3.5048425 4.086063 B e e staggered 0 0 0 v
40 0 3.4920225 1.339323 T 0.06102 0.00984 e s
40 0 0.6389685 4.0388976 T 0.0393701 0.0283465 e s
40 0.004 3.3798425 1.336063 B e e staggered 0 0 0 v
40 0.004 2.0048425 1.336063 B e e staggered 0 0 0 v
40 0.004 2.0048425 3.816063 B e e staggered 0 0 0 v
41 0 3.4920225 1.359003 T 0.06102 0.00984 e s
41 0 0.8406351 4.0388976 T 0.0393701 0.0283465 e s
41 0.004 3.4048425 1.363323 B e e staggered 0 0 0 v
41 0.004 2.0288425 1.361663 B e e staggered 0 0 0 v
41 0.004 2.0298425 3.836063 B e e staggered 0 0 0 v
42 0 3.4920225 1.378693 T 0.06102 0.00984 e s
42 0 1.0423017 4.0388976 T 0.0393701 0.0283465 e s
42 0.004 3.3798425 1.386063 B e e staggered 0 0 0 v
42 0.004 2.0598425 1.386063 B e e staggered 0 0 0 v
42 0.004 2.0598425 3.871063 B e e staggered 0 0 0 v
43 0 3.4920225 1.398373 T 0.06102 0.00984 e s
43 0 1.2439683 4.0388976 T 0.0393701 0.0283465 e s
43 0.004 3.4072822 1.411323 B e e staggered 0 0 0 v
43 0.004 2.0848425 3.896063 B e e staggered 0 0 0 v
43 0.004 2.0838425 1.411663 B e e staggered 0 0 0 v
44 0 2.5279325 2.358813 T 0.00984 0.06102 e s
44 0 2.3114025 2.358813 T 0.00984 0.06102 e s
44 0 2.3310825 2.358813 T 0.00984 0.06102 e s
44 0 0.9635826 1.2244094 T 0.0275591 0.0354331 e s
44 0.0206693 4.3277559 2.3074803 B e e staggered 0 0 0
44 0.025 5.5781524 0.8906186 B e e staggered 0 0 0
44 0.025 5.5781524 2.4890438 B e e staggered 0 0 0
44 0.004 2.3308425 2.215063 B e e staggered 0 0 0 v
44 0.004 2.4998425 2.236063 B e e staggered 0 0 0 v
44 0.004 0.996063 1.1870079 B e e staggered 0 0 0 v
44 0.004 5.5778425 2.214063 B e e staggered 0 0 0 v
44 0.004 5.6348425 2.236063 B e e staggered 0 0 0 v
45 0 3.9114214 1.7796232 T 0.0708661 0.0098425 e s
45 0 2.5476225 2.358813 T 0.00984 0.06102 e s
45 0.004 2.5798425 2.281063 B e e staggered 0 0 0 v
45 0.004 3.9448425 1.816063 B e e staggered 0 0 0 v
45 0.004 2.5798425 1.790063 B e e staggered 0 0 0 v
46 0 2.5673025 2.358813 T 0.00984 0.06102 e s
46 0.0206693 4.9277559 1.0074803 B e e staggered 0 0 0
46 0.025 4.0624044 2.595343 B e e staggered 0 0 0
46 0.004 2.5758425 2.412063 B e e staggered 0 0 0 v
46 0.004 4.0398425 2.406063 B e e staggered 0 0 0 v
47 0 4.0689017 1.6396232 T 0.0708661 0.0098425 e s
47 0 2.6460425 2.358813 T 0.00984 0.06102 e s
47 0 2.3877954 2.8996063 T 0.0354331 0.0275591 e s
47 0 0.9675196 2.2844487 T 0.0275591 0.0354331 e s
47 0.0206693 4.9277559 2.3074803 B e e staggered 0 0 0
47 0.004 2.6929134 2.7214567 B e e staggered 0 0 0 v
47 0.004 2.6458425 2.274063 B e e staggered 0 0 0 v
47 0.004 0.9968357 2.256036 B e e staggered 0 0 0 v
47 0.004 4.1513063 1.6236232 B e e staggered 0 0 0 v
47 0.004 2.6438425 1.616063 B e e staggered 0 0 0 v
48 0 4.0689017 1.6596232 T 0.0708661 0.0098425 e s
48 0 2.6657325 2.358813 T 0.00984 0.06102 e s
48 0.004 2.6658425 2.291063 B e e staggered 0 0 0 v
48 0.004 4.1348425 1.651063 B e e staggered 0 0 0 v
48 0.004 2.6668425 1.640063 B e e staggered 0 0 0 v
49 0 4.0689017 1.5996232 T 0.0708661 0.0098425 e s
49 0 2.7051025 2.358813 T 0.00984 0.06102 e s
49 0.004 2.7028425 2.289063 B e e staggered 0 0 0 v
49 0.004 4.0648425 1.511063 B e e staggered 0 0 0 v
49 0.004 2.6948425 1.481063 B e e staggered 0 0 0 v
50 0 4.0689017 1.6196232 T 0.0708661 0.0098425 e s
50 0 2.7247825 2.358813 T 0.00984 0.06102 e s
50 0.004 2.7268425 2.293063 B e e staggered 0 0 0 v
50 0.004 4.1798425 1.601063 B e e staggered 0 0 0 v
50 0.004 2.7198425 1.591063 B e e staggered 0 0 0 v
51 0 4.0689017 1.7596232 T 0.0708661 0.0098425 e s
51 0 2.6066725 2.358813 T 0.00984 0.06102 e s
51 0 0.9596456 1.7470472 T 0.0275591 0.0354331 e s
51 0.0206693 4.7277559 2.3074803 B e e staggered 0 0 0
51 0.004 2.5998425 2.436063 B e e staggered 0 0 0 v
51 0.004 0.988189 1.7175197 B e e staggered 0 0 0 v
51 0.004 4.1348425 1.751063 B e e staggered 0 0 0 v
51 0.004 2.6048425 1.734063 B e e staggered 0 0 0 v
52 0 4.0689017 1.7796232 T 0.0708661 0.0098425 e s
52 0 2.6263625 2.358813 T 0.00984 0.06102 e s
52 0.004 2.6248425 2.461063 B e e staggered 0 0 0 v
52 0.004 4.0648425 1.796063 B e e staggered 0 0 0 v
52 0.004 2.6268425 1.770063 B e e staggered 0 0 0 v
53 0 2.4688825 2.518253 T 0.00984 0.06102 e s
53 0 2.2125984 4.0748032 T 0.0354331 0.0275591 e s
53 0.0206693 5.3277559 1.0074803 B e e staggered 0 0 0
53 0.025 4.1805146 2.595343 B e e staggered 0 0 0
53 0.004 2.4948425 2.661063 B e e staggered 0 0 0 v
53 0.004 2.253937 4.0866142 B e e staggered 0 0 0 v
54 0 2.4491925 2.518253 T 0.00984 0.06102 e s
54 0 1.3464567 3.9783465 T 0.0354331 0.0275591 e s
54 0.0206693 5.1277559 1.0074803 B e e staggered 0 0 0
54 0.025 4.2986248 2.595343 B e e staggered 0 0 0
54 0.004 2.4948425 2.696063 B e e staggered 0 0 0 v
54 0.004 1.4084645 3.980315 B e e staggered 0 0 0 v
55 0 3.9114214 1.6396232 T 0.0708661 0.0098425 e s
55 0 2.2720325 2.518253 T 0.00984 0.06102 e s
55 0.004 2.2720325 2.463873 B e e staggered 0 0 0 v
55 0.004 4.0348425 1.546063 B e e staggered 0 0 0 v
55 0.004 2.2748425 1.506063 B e e staggered 0 0 0 v
56 0 3.9114214 1.5996232 T 0.0708661 0.0098425 e s
56 0 2.9019525 2.518253 T 0.00984 0.06102 e s
56 0.004 2.8948425 2.431063 B e e staggered 0 0 0 v
56 0.004 3.9698425 1.552063 B e e staggered 0 0 0 v
56 0.004 2.8948425 1.561063 B e e staggered 0 0 0 v
57 0 3.9114214 1.6196232 T 0.0708661 0.0098425 e s
57 0 2.9216325 2.518253 T 0.00984 0.06102 e s
57 0.004 2.9208425 2.428063 B e e staggered 0 0 0 v
57 0.004 3.9948425 1.551063 B e e staggered 0 0 0 v
57 0.004 2.9198425 1.536063 B e e staggered 0 0 0 v
58 0 6.5113582 3.3296457 T 0.0265748 0.0098425 e s
58 0 3.4920225 1.870813 T 0.06102 0.00984 e s
58 0.004 3.4392507 1.870938 B e e staggered 0 0 0 v
58 0.004 6.5098425 3.456063 B e e staggered 0 0 0 v
58 0.004 3.4698425 3.456063 B e e staggered 0 0 0 v
59 0 6.44 3.3321063 T 0.0098425 0.0226378 e s
59 0 3.4920225 1.890503 T 0.06102 0.00984 e s
59 0.004 3.2988425 1.971063 B e e staggered 0 0 0 v
59 0.004 3.3028425 3.344063 B e e staggered 0 0 0 v
59 0.004 6.4098425 3.371063 B e e staggered 0 0 0 v
60 0 3.1112205 3.1872047 T 0.0787402 0.023622 e s
60 0 4.9094488 2.8080708 T 0.1653543 0.1259843 e s
60 0.004 4.7942913 2.8080709 B e e staggered 0 0 0 v
60 0.004 3.1889764 3.1870079 B e e staggered 0 0 0 v
61 0 6.3522834 2.241063 T 0.0775591 0.0224409 e s
61 0 6.4698425 2.2395669 T 0.0374016 0.0393701 e s
62 0 6.3522834 2.341063 T 0.0775591 0.0224409 e s
62 0 6.6798425 2.4201181 T 0.2125984 0.1141732 e s
62 0 6.4698425 2.302559 T 0.0374016 0.0393701 e s
63 0 6.5198425 2.0175591 T 0.0374016 0.0393701 e s
63 0 6.6374016 2.031063 T 0.0775591 0.0224409 e s
64 0 6.5198425 1.954567 T 0.0374016 0.0393701 e s
64 0 6.3198425 1.8420079 T 0.2125984 0.1141732 e s
64 0 6.6374016 1.931063 T 0.0775591 0.0224409 e s
65 0 6.8433465 2.096063 T 0.0393701 0.0374016 e s
65 0 6.8322834 2.031063 T 0.0775591 0.0224409 e s
66 0 6.9398425 1.9229921 T 0.0251969 0.0267717 e s
66 0 6.8322834 1.931063 T 0.0775591 0.0224409 e s
67 0 6.9398425 1.8891338 T 0.0251969 0.0267717 e s
67 0 7.0098425 1.8838977 T 0.0393701 0.0283465 e s
68 0 6.1574016 2.241063 T 0.0775591 0.0224409 e s
68 0 6.1563385 2.171063 T 0.0393701 0.0374016 e s
69 0 6.1574016 2.341063 T 0.0775591 0.0224409 e s
69 0 6.0648425 2.3441339 T 0.0251969 0.0267717 e s
70 0 6.0648425 2.3779922 T 0.0251969 0.0267717 e s
70 0 6.0048425 2.3388977 T 0.0393701 0.0283465 e s
71 0 2.3484251 0.1377953 D 0.028 0.165 e p
71 0 2.3498425 0.3291339 D 0.0251969 0.0267717 e p
72 0 2.3877951 0.1377953 D 0.028 0.165 e p
72 0 2.3898425 0.3291339 D 0.0251969 0.0267717 e p
73 0 2.4665351 0.1377953 D 0.028 0.165 e p
73 0 2.4688425 0.3291339 D 0.0251969 0.0267717 e p
74 0 2.5059051 0.1377953 D 0.028 0.165 e p
74 0 2.5118425 0.3291339 D 0.0251969 0.0267717 e p
75 0 2.6633851 0.1377953 D 0.028 0.165 e p
75 0 2.6648425 0.3291339 D 0.0251969 0.0267717 e p
76 0 2.7027551 0.1377953 D 0.028 0.165 e p
76 0 2.7048425 0.3291339 D 0.0251969 0.0267717 e p
77 0 2.8208651 0.1377953 D 0.028 0.165 e p
77 0 2.8198425 0.3291339 D 0.0251969 0.0267717 e p
78 0 2.8602351 0.1377953 D 0.028 0.165 e p
78 0 2.8548425 0.3291339 D 0.0251969 0.0267717 e p
79 0 2.9783451 0.1377953 D 0.028 0.165 e p
79 0 2.9798425 0.3291339 D 0.0251969 0.0267717 e p
80 0 3.0177151 0.1377953 D 0.028 0.165 e p
80 0 3.0198425 0.3291339 D 0.0251969 0.0267717 e p
81 0 3.9344488 4.0237008 T 0.019685 0.0905512 e s
81 0 4.1048425 3.7706299 T 0.0570866 0.0452756 e s
81 0 4.1948425 3.774567 T 0.0374016 0.0393701 e s
81 0 4.1670079 3.701063 T 0.0283465 0.0393701 e s
81 0 3.9871259 3.758563 T 0.0570866 0.0177165 e s
82 0 4.1498425 2.7898819 T 0.0385827 0.034252 e s
82 0 4.3398425 2.8514961 T 0.0570866 0.0452756 e s
82 0 4.4348425 2.8422441 T 0.0385827 0.034252 e s
82 0 4.2348425 2.8514961 T 0.0570866 0.0452756 e s
83 0 6.7265748 3.1680709 T 0.0511811 0.0748031 e s
83 0 6.5113582 3.1918504 T 0.0265748 0.0098425 e s
83 0 6.6048425 3.192559 T 0.0374016 0.0393701 e s
84 0 6.7265748 3.2940551 T 0.0511811 0.0748031 e s
84 0 6.5113582 3.2115354 T 0.0265748 0.0098425 e s
84 0 6.6048425 3.264567 T 0.0374016 0.0393701 e s
85 0 5.8879921 3.701063 T 0.0255906 0.0413386 e s
85 0.0324803 5.7234252 3.8444882 B e e staggered 0 0 0
86 0 6.0316929 3.701063 T 0.0255906 0.0413386 e s
86 0.019685 6.1198425 3.8198425 B e e staggered 0 0 0
87 0 6.1979921 3.701063 T 0.0255906 0.0413386 e s
87 0 6.0900079 3.556063 T 0.0283465 0.0393701 e s
87 0 6.2029921 3.566063 T 0.0255906 0.0413386 e s
87 0.0324803 5.7234252 4.0255906 B e e staggered 0 0 0
88 0 6.3466929 3.566063 T 0.0255906 0.0413386 e s
88 0.035433 6.9001969 3.806063 B e e staggered 0 0 0
88 0.035433 6.7348425 3.806063 B e e staggered 0 0 0
88 0.035433 6.5694882 3.806063 B e e staggered 0 0 0
89 0 4.2755905 3.6033465 T 0.0393701 0.0334646 e s
89 0 4.2049212 3.6033465 T 0.0283465 0.0393701 e s
90 0 3.5898425 3.9096063 T 0.0334646 0.0393701 e s
90 0 3.6681102 3.861063 T 0.0255906 0.023622 e s
91 0 3.6681102 3.786063 T 0.0255906 0.023622 e s
91 0 3.5898425 3.7275197 T 0.0334646 0.0393701 e s
92 0 0.6448425 4.1975197 T 0.0334646 0.0393701 e s
92 0 0.6389685 4.0932283 T 0.0393701 0.0283465 e s
93 0 0.8465091 4.1975197 T 0.0334646 0.0393701 e s
93 0 0.8406351 4.0932283 T 0.0393701 0.0283465 e s
94 0 1.0481757 4.1975197 T 0.0334646 0.0393701 e s
94 0 1.0423017 4.0932283 T 0.0393701 0.0283465 e s
95 0 1.2498423 4.1975197 T 0.0334646 0.0393701 e s
95 0 1.2439683 4.0932283 T 0.0393701 0.0283465 e s
96 0 3.9029528 4.0237008 T 0.019685 0.0905512 e s
96 0 3.9871259 3.683563 T 0.0570866 0.0177165 e s
97 0 3.8714567 4.0237008 T 0.019685 0.0905512 e s
97 0 3.772559 3.683563 T 0.0570866 0.0177165 e s
98 0 2.3581575 4.1703386 T 0.0177165 0.0543307 e s
98 0 1.8461259 4.024563 T 0.0570866 0.0177165 e s
98 0.004 2.3533464 4.0177165 B e e staggered 0 0 0 v
98 0.004 1.9038425 4.018063 B e e staggered 0 0 0 v
99 0 2.3325669 4.1703386 T 0.0177165 0.0543307 e s
99 0 1.631559 4.024563 T 0.0570866 0.0177165 e s
100 0 1.631559 4.124563 T 0.0570866 0.0177165 e s
100 0.015 1.4576771 4.153937 B e e staggered 0 0 0
101 0 1.3464567 4.0826772 T 0.0354331 0.0275591 e s
101 0 1.3464567 4.0374016 T 0.0354331 0.0275591 e s
101 0.015 1.4576771 4.053937 B e e staggered 0 0 0
102 0 1.631559 4.199563 T 0.0570866 0.0177165 e s
102 0.015 2.0433071 4.157874 B e e staggered 0 0 0
102 0.004 1.5698819 4.1712599 B e e staggered 0 0 0 v
103 0 2.1515748 4.0157481 T 0.0354331 0.0275591 e s
103 0 2.2125984 4.0157481 T 0.0354331 0.0275591 e s
103 0.015 2.0433071 4.057874 B e e staggered 0 0 0
104 0 2.5059051 0.1377953 T 0.028 0.165 e s
104 0 2.503937 0.5738189 T 0.023622 0.0255906 e s
105 0 3.0570851 0.1572953 T 0.028 0.126 e s
105 0 3.0551181 0.5738189 T 0.023622 0.0255906 e s
106 0 6.7498425 2.0888976 T 0.0393701 0.0283465 e s
106 0 6.8322834 1.981063 T 0.0775591 0.0224409 e s
107 0 6.1574016 2.291063 T 0.0775591 0.0224409 e s
107 0 6.2348425 2.1832284 T 0.0393701 0.0283465 e s
108 0 6.8970078 1.816063 T 0.0283465 0.0393701 e s
108 0 6.7820078 1.816063 T 0.0283465 0.0393701 e s
108 0 6.8322834 1.881063 T 0.0775591 0.0224409 e s
109 0 6.1574016 2.391063 T 0.0775591 0.0224409 e s
109 0 6.3126772 2.451063 T 0.0283465 0.0393701 e s
109 0 6.1228425 2.4338976 T 0.0393701 0.0283465 e s
110 0 2.9448425 3.951063 T 0.05 0.2 e s
110 0 2.9448425 3.7454331 T 0.0570866 0.0374016 e s
111 0 3.0448425 3.951063 T 0.05 0.2 e s
111 0 3.0448425 3.7454331 T 0.0570866 0.0374016 e s
112 0 3.1448425 3.951063 T 0.05 0.2 e s
112 0 3.1448425 3.7454331 T 0.0570866 0.0374016 e s
113 0 3.3448425 3.951063 T 0.05 0.2 e s
113 0 3.3498425 3.7454331 T 0.0570866 0.0374016 e s
114 0 4.1126772 3.701063 T 0.0283465 0.0393701 e s
114 0 3.9871259 3.733563 T 0.0570866 0.0177165 e s
115 0 4.6526771 4.206063 T 0.0283465 0.0393701 e s
115 0 4.6526772 4.121063 T 0.0283465 0.0393701 e s
115 0 4.5667716 4.206063 T 0.0314961 0.0669291 e s
116 0 5.0917716 4.206063 T 0.0314961 0.0669291 e s
116 0 5.2126771 4.206063 T 0.0283465 0.0393701 e s
116 0 5.2126772 4.126063 T 0.0283465 0.0393701 e s
117 0 3.4848425 2.8923386 T 0.0275591 0.0452756 e s
117 0 3.4776771 2.797063 T 0.0283465 0.0393701 e s
118 0 1.8461259 4.074563 T 0.0570866 0.0177165 e s
118 0 1.9338425 4.0748977 T 0.0393701 0.0283465 e s
119 0 3.9871259 3.708563 T 0.0570866 0.0177165 e s
119 0 3.772559 3.808563 T 0.0570866 0.0177165 e s
119 0.004 4.0498425 3.665063 B e e staggered 0 0 0 v
119 0.004 3.8298425 3.806063 B e e staggered 0 0 0 v
120 0 1.8461259 4.049563 T 0.0570866 0.0177165 e s
120 0 1.631559 4.149563 T 0.0570866 0.0177165 e s
121 0 3.4385827 3.0517874 T 0.0413386 0.0452756 e s
121 0 2.2523425 2.518253 T 0.00984 0.06102 e s
121 0.004 2.2523425 2.613563 B e e staggered 0 0 0 v
121 0.004 2.2598425 3.261063 B e e staggered 0 0 0 v
121 0.004 3.3748425 3.273063 B e e staggered 0 0 0 v
121 0.004 3.3688425 3.050063 B e e staggered 0 0 0 v
122 0 2.6263725 0.878873 T 0.00984 0.06102 e s
122 0 2.3898425 0.3629922 D 0.0251969 0.0267717 e p
122 0.004 2.3897638 0.4055118 B e e staggered 0 0 0 v
122 0.004 2.5984252 0.7952756 B e e staggered 0 0 0 v
123 0 2.6460525 0.878873 T 0.00984 0.06102 e s
123 0 2.3498425 0.3629922 D 0.0251969 0.0267717 e p
123 0.004 2.3503937 0.4055118 B e e staggered 0 0 0 v
123 0.004 2.6259843 0.7952756 B e e staggered 0 0 0 v
124 0 1.7765525 1.516523 T 0.06102 0.00984 e s
124 0 2.1468425 2.6248976 T 0.0393701 0.0283465 e s
124 0 2.1909451 0.1377953 D 0.028 0.165 e p
124 0.004 1.8973025 1.516523 B e e staggered 0 0 0 v
125 0 2.4271651 0.1377953 T 0.028 0.165 e s
125 0 2.6263725 1.038313 T 0.00984 0.06102 e s
125 0.004 2.4448819 0.2795276 B e e staggered 0 0 0 v
125 0.004 2.6220472 0.976378 B e e staggered 0 0 0 v
126 0 2.3877951 0.1377953 T 0.028 0.165 e s
126 0 2.6460525 1.038313 T 0.00984 0.06102 e s
126 0.004 2.4133858 0.2795276 B e e staggered 0 0 0 v
126 0.004 2.6496063 0.976378 B e e staggered 0 0 0 v
127 0 2.6240151 0.1377953 T 0.028 0.165 e s
127 0 2.6854225 0.878873 T 0.00984 0.06102 e s
127 0.004 2.6102362 0.2795276 B e e staggered 0 0 0 v
127 0.004 2.6653543 0.7952756 B e e staggered 0 0 0 v
128 0 2.5846451 0.1377953 T 0.028 0.165 e s
128 0 2.7051125 0.878873 T 0.00984 0.06102 e s
128 0.004 2.5787402 0.2795276 B e e staggered 0 0 0 v
128 0.004 2.6929134 0.7952756 B e e staggered 0 0 0 v
129 0 2.7814951 0.1377953 T 0.028 0.165 e s
129 0 2.8035325 0.878873 T 0.00984 0.06102 e s
129 0.004 2.7795276 0.2795276 B e e staggered 0 0 0 v
129 0.004 2.7992126 0.7952756 B e e staggered 0 0 0 v
130 0 2.7421251 0.1377953 T 0.028 0.165 e s
130 0 2.8232225 0.878873 T 0.00984 0.06102 e s
130 0.004 2.74882 0.282312 B e e staggered 0 0 0 v
130 0.004 2.8267717 0.7952756 B e e staggered 0 0 0 v
131 0 2.9389751 0.1377953 T 0.028 0.165 e s
131 0 2.7444825 1.038313 T 0.00984 0.06102 e s
131 0.004 2.9370079 0.2795276 B e e staggered 0 0 0 v
131 0.004 2.7401575 0.976378 B e e staggered 0 0 0 v
132 0 2.8996051 0.1377953 T 0.028 0.165 e s
132 0 2.7641625 1.038313 T 0.00984 0.06102 e s
132 0.004 2.9054946 0.2795104 B e e staggered 0 0 0 v
132 0.004 2.7677165 0.976378 B e e staggered 0 0 0 v
133 0 2.6854225 1.038313 T 0.00984 0.06102 e s
133 0 2.5118425 0.3629922 D 0.0251969 0.0267717 e p
133 0.004 2.511811 0.4055118 B e e staggered 0 0 0 v
133 0.004 2.6811024 0.976378 B e e staggered 0 0 0 v
134 0 2.7051125 1.038313 T 0.00984 0.06102 e s
134 0 2.4688425 0.3629922 D 0.0251969 0.0267717 e p
134 0.004 2.4698827 0.4109883 B e e staggered 0 0 0 v
134 0.004 2.7086614 0.976378 B e e staggered 0 0 0 v
135 0 2.7444825 0.878873 T 0.00984 0.06102 e s
135 0 2.7048425 0.3629922 D 0.0251969 0.0267717 e p
135 0.004 2.7047244 0.4055118 B e e staggered 0 0 0 v
135 0.004 2.7322835 0.7952756 B e e staggered 0 0 0 v
136 0 2.7641625 0.878873 T 0.00984 0.06102 e s
136 0 2.6648425 0.3629922 D 0.0251969 0.0267717 e p
136 0.004 2.6653543 0.4055118 B e e staggered 0 0 0 v
136 0.004 2.7598425 0.7952756 B e e staggered 0 0 0 v
137 0 2.8625925 0.878873 T 0.00984 0.06102 e s
137 0 2.8548425 0.3629922 D 0.0251969 0.0267717 e p
137 0.004 2.8543307 0.4055118 B e e staggered 0 0 0 v
137 0.004 2.8622047 0.7952756 B e e staggered 0 0 0 v
138 0 2.8822725 0.878873 T 0.00984 0.06102 e s
138 0 2.8198425 0.3629922 D 0.0251969 0.0267717 e p
138 0.004 2.8219832 0.4078519 B e e staggered 0 0 0 v
138 0.004 2.8937008 0.7952756 B e e staggered 0 0 0 v
139 0 2.8035325 1.038313 T 0.00984 0.06102 e s
139 0 3.0198425 0.3629922 D 0.0251969 0.0267717 e p
139 0.004 3.019685 0.4055118 B e e staggered 0 0 0 v
139 0.004 2.7992126 0.976378 B e e staggered 0 0 0 v
140 0 2.8232225 1.038313 T 0.00984 0.06102 e s
140 0 2.9798425 0.3629922 D 0.0251969 0.0267717 e p
140 0.004 2.980457 0.4091539 B e e staggered 0 0 0 v
140 0.004 2.8267717 0.976378 B e e staggered 0 0 0 v
141 0 2.503937 0.6072835 T 0.023622 0.0255906 e s
141 0 3.0551181 0.6072835 T 0.023622 0.0255906 e s
141 0 1.7972451 0.1572953 D 0.028 0.126 e p
141 0.004 1.7978425 0.355063 B e e staggered 0 0 0 v
142 0 2.7568898 3.1872047 T 0.0787402 0.023622 e s
142 0 1.7765525 1.811803 T 0.06102 0.00984 e s
142 0.004 1.8799377 1.811803 B e e staggered 0 0 0 v
142 0.004 3.0688976 3.3956693 B e e staggered 0 0 0 v
142 0.004 3.0568817 1.811803 B e e staggered 0 0 0 v
143 0 6.4793701 3.3321063 T 0.0098425 0.0226378 e s
143 0 3.4920225 1.851133 T 0.06102 0.00984 e s
143 0.004 3.3928425 1.871063 B e e staggered 0 0 0 v
143 0.004 3.4368425 3.457063 B e e staggered 0 0 0 v
143 0.004 6.4798425 3.426063 B e e staggered 0 0 0 v
144 0 3.1112205 3.2872047 T 0.0787402 0.023622 e s
144 0 3.4512205 3.3951969 T 0.0393701 0.0708661 e s
144 0 3.4444882 2.995685 T 0.0531496 0.0275591 e s
144 0 3.2293307 2.845 T 0.0098425 0.0108268 e s
144 0 2.8625825 2.358813 T 0.00984 0.06102 e s
144 0.004 2.8418425 2.263063 B e e staggered 0 0 0 v
144 0.004 3.3588425 3.448063 B e e staggered 0 0 0 v
144 0.004 3.3448425 2.996063 B e e staggered 0 0 0 v
144 0.004 3.3428425 2.263063 B e e staggered 0 0 0 v
145 0 3.1112205 3.2372047 T 0.0787402 0.023622 e s
145 0 3.3921654 3.3951969 T 0.0393701 0.0708661 e s
145 0 3.4848425 3.0517874 T 0.0275591 0.0452756 e s
145 0 3.2091732 2.8149606 T 0.0108268 0.0098425 e s
145 0 2.8035225 2.358813 T 0.00984 0.06102 e s
145 0.004 2.8038425 2.307063 B e e staggered 0 0 0 v
145 0.004 3.4918425 3.103063 B e e staggered 0 0 0 v
145 0.004 3.4918425 3.297063 B e e staggered 0 0 0 v
145 0.004 3.4988425 2.341063 B e e staggered 0 0 0 v
146 0 2.9610025 2.358813 T 0.00984 0.06102 e s
146 0 3.7015748 3.861063 T 0.0255906 0.023622 e s
146 0 3.772559 3.858563 T 0.0570866 0.0177165 e s
146 0.004 2.9858425 2.287063 B e e staggered 0 0 0 v
146 0.004 3.0148425 3.831063 B e e staggered 0 0 0 v
146 0.004 3.6998425 3.836063 B e e staggered 0 0 0 v
147 0 3.7015748 3.786063 T 0.0255906 0.023622 e s
147 0 2.9019525 2.358813 T 0.00984 0.06102 e s
147 0 3.772559 3.783563 T 0.0570866 0.0177165 e s
147 0.004 2.9428425 2.286063 B e e staggered 0 0 0 v
147 0.004 2.9933858 3.751063 B e e staggered 0 0 0 v
147 0.004 3.6998425 3.751063 B e e staggered 0 0 0 v

### steps/pcb/layers/bottom/features
#Layer_Physical_Order=6
#Layer_Color=16711680
#
#Feature symbol names
#
$0 r5
$1 r20
$2 rect82.874x44.0945
$3 rect28x165
$4 rect28x126
$5 rect25.1969x26.7717
$6 rect57.0866x45.2756
$7 rect26.7717x25.1969
$8 rect45.2756x57.0866
$9 r8
$10 r10
$11 rect73.8189x67.9134
$12 r3.937
$13 r1
$14 r31.4961
$15 r65.9843
$16 r61.0236
$17 s61.0236
$18 r75
$19 r98.4252
$20 oval88.5827x177.1654
$21 oval177.1654x88.5827
$22 oval196.8504x98.4252
$23 r112
$24 r120
$25 r21.66
$26 r55
$27 s55
$28 r50
$29 r250
$30 r16
$31 r200

#
#Feature attribute names
#
@0 .geometry
@1 .pad_usage
@2 .smd

#
#Feature attribute text strings
#
&0 SMD_RoundX82.8740Y44.0945
&1 SMD_RoundX28.0000Y165.0000
&2 SMD_RoundX28.0000Y126.0000
&3 SMD_RoundX25.1969Y26.7717
&4 SMD_RoundX57.0866Y45.2756
&5 SMD_RoundX26.7717Y25.1969
&6 SMD_RoundX45.2756Y57.0866
&7 Pad_Simple_X31.4961Y31.4961H35.4331C75.4331
&8 Pad_Simple_X65.9843Y65.9843H65.9843C105.9843
&9 Pad_Simple_X61.0236Y61.0236H41.3386C81.3386
&10 Pad_Simple_X75.0000Y75.0000H50.0000C90.0000
&11 Pad_Simple_X98.4252Y98.4252H64.9606C104.9606
&12 Pad_Simple_X88.5827Y177.1654H39.3701C79.3701
&13 Pad_Simple_X177.1654Y88.5827H39.3701C79.3701
&14 Pad_Simple_X196.8504Y98.4252H39.3701C79.3701
&15 Pad_Simple_X112.0000Y112.0000H60.0000C100.0000
&16 Pad_Simple_X120.0000Y120.0000H68.0000C108.0000
&17 Pad_Simple_X21.6600Y21.6600H21.6600C61.6600
&18 Pad_Simple_X55.0000Y55.0000H30.0000C70.0000
&19 Pad_Simple_X50.0000Y50.0000H118.1102C158.1102
&20 Pad_Simple_X98.4252Y98.4252H70.8661C110.8661
&21 Pad_Complex_X50.0000Y50.0000H118.1102C158.1102
&22 Pad_Simple_X250.0000Y250.0000H125.1969C165.1969
&23 VIA_RoundD16.0000H8.0000C48.0000
&24 VIA_RoundD200.0000H125.9843C165.9843

#
#Layer features
#
A 1.7712204 0.4310709 1.6275196 0.4310709 1.69937 0.4310709 12 P 0 N
A 2.3484251 0.1377953 2.3498425 0.1412172 2.3450032 0.1412172 0 P 0 N
A 2.3498425 0.3291339 2.3492125 0.3276129 2.3513635 0.3276129 0 P 0 N
A 2.3498425 0.3629922 2.3503937 0.3643229 2.3485118 0.3643229 0 P 0 N
A 2.3877951 0.1377953 2.3898425 0.1427382 2.3828522 0.1427382 0 P 0 N
A 2.4365786 0.2353319 2.4279525 0.2188809 2.4479528 0.2188808 1 P 0 N
A 2.4665351 0.1377953 2.4688425 0.1433659 2.4609645 0.1433659 0 P 0 N
A 2.4673225 0.111063 2.4673256 0.1110661 2.4636529 0.1147326 0 P 0 N
A 2.4673256 0.1110661 2.4688425 0.1147326 2.4636529 0.1147326 0 P 0 N
A 2.4698188 0.4109188 2.4685313 0.4076215 2.473531 0.4075692 0 P 0 N
A 2.5059051 0.1377953 2.5118425 0.1521295 2.4915709 0.1521295 0 P 0 N
A 2.6633851 0.1377953 2.6648425 0.1413138 2.6598666 0.1413138 0 P 0 N
A 2.6641725 0.111063 2.6648425 0.1126805 2.662555 0.1126805 0 P 0 N
A 2.6648425 0.3629922 2.6653543 0.3642278 2.6636069 0.3642278 0 P 0 N
A 2.7027551 0.1377953 2.7048425 0.1428347 2.6977157 0.1428347 0 P 0 N
A 2.7035425 0.111063 2.7048425 0.1142015 2.700404 0.1142015 0 P 0 N
A 2.8188976 0.3652734 2.8198425 0.3629922 2.8221237 0.3652734 0 P 0 N
A 2.8198425 0.1402641 2.8208651 0.1377953 2.8233339 0.1402641 0 P 0 N
A 2.8216525 0.3247642 2.8198425 0.3291339 2.8154728 0.3247642 0 P 0 N
A 2.8219832 0.407852 2.8188977 0.4032734 2.8238976 0.4032329 0 P 0 N
A 2.8543307 0.3642278 2.8548425 0.3629922 2.8560781 0.3642278 0 P 0 N
A 2.8548425 0.1259828 2.8610038 0.1110817 2.8759423 0.1259828 0 P 0 N
A 2.8548425 0.1508142 2.8602351 0.1377953 2.873254 0.1508142 0 P 0 N
A 2.8610038 0.1110817 2.8610225 0.111063 2.8759423 0.1259828 0 P 0 N
A 2.8910408 0.2438013 2.878307 0.249595 2.8769142 0.2296433 1 P 0 N
A 2.9783451 0.1377953 2.9798425 0.1414103 2.9747301 0.1414103 0 P 0 N
A 2.9791325 0.111063 2.9798425 0.1127771 2.9774184 0.1127771 0 P 0 N
A 2.9798425 0.3291339 2.9791325 0.3274198 2.9815566 0.3274198 0 P 0 N
A 2.9798425 0.3629922 2.980315 0.3641329 2.9787018 0.3641329 0 P 0 N
A 2.9803932 0.4088515 2.980315 0.4079707 2.985315 0.4079707 0 P 0 N
A 3.0177151 0.1377953 3.0198425 0.1429313 3.0125791 0.1429313 0 P 0 N
A 3.0198425 0.3291339 3.0185025 0.3258989 3.0230775 0.3258989 0 P 0 N
L -0.0001175 0.177913 0.5908825 0.177913 13 P 0
L -0.0004331 0.1781182 0.5901181 0.1781182 12 P 0
L 0.5901181 0.1781182 0.5901181 0.5029213 12 P 0
L 0.5901181 0.5029213 1.312559 0.5029213 12 P 0
L 0.5908825 0.177913 0.5908825 0.502913 13 P 0
L 1.312559 0.313945 1.312559 0.5029213 12 P 0
L 1.312559 0.313945 1.6275197 0.313945 12 P 0
L 1.6275197 0.313945 1.6275197 0.4310709 12 P 0
L 1.7980325 0.130563 1.7980325 0.355063 9 P 0
L 1.8374025 0.111063 1.8374025 0.2575406 1 P 0
L 1.8374025 0.2575406 1.8498425 0.2699806 1 P 0
L 1.8498425 0.2699806 1.8767725 0.2430506 1 P 0
L 1.8767725 0.111063 1.8767725 0.2430506 1 P 0
L 1.8968425 0.735063 1.8968425 1.516063 9 P 0
L 1.8968425 0.735063 2.1917325 0.440173 9 P 0
L 1.8968425 1.516063 1.8973025 1.516523 9 P 0
L 1.9161425 0.111063 1.9161425 0.244763 1 P 0
L 2.1122047 0.2559055 2.1122051 0.2559051 1 P 0
L 2.1122051 0.1377953 2.1122051 0.2559051 1 P 0
L 2.1148425 0.2887008 2.1511393 0.252404 1 P 0
L 2.1398425 3.611063 2.3428838 3.611063 1 P 0
L 2.1511393 0.1122862 2.1511393 0.252404 1 P 0
L 2.1511393 0.1122862 2.1523625 0.111063 1 P 0
L 2.1906078 0.1121877 2.1917325 0.111063 1 P 0
L 2.1917325 0.111063 2.1917325 0.440173 9 P 0
L 2.3098425 0.111063 2.3098425 0.246063 1 P 0
L 2.3348425 3.1215827 2.4156413 3.1215827 9 P 0
L 2.3348425 3.2003229 2.335315 3.1998504 9 P 0
L 2.3348425 3.279063 2.3978425 3.279063 10 P 0
L 2.335315 3.1998504 2.4140551 3.1998504 9 P 0
L 2.3492125 0.111063 2.3498425 0.111693 9 P 0
L 2.3498425 0.1412172 2.3498425 0.3291339 0 P 0
L 2.3503937 0.3643229 2.3503937 0.4055118 0 P 0
L 2.3857717 2.854063 2.3865591 2.854063 10 P 0
L 2.3865591 2.854063 2.3941576 2.8464645 10 P 0
L 2.3897638 0.3630709 2.3897638 0.4055118 0 P 0
L 2.3897638 0.3630709 2.3898425 0.3629922 0 P 0
L 2.3898425 0.1427382 2.3898425 0.3291339 0 P 0
L 2.3941576 2.8456771 2.3941576 2.8464645 10 P 0
L 2.3941576 2.8456771 2.4158425 2.8239922 10 P 0
L 2.3978425 3.279063 2.4138425 3.295063 10 P 0
L 2.3982756 2.944063 2.3982756 2.9499685 10 P 0
L 2.3982756 2.9499685 2.4159134 2.9676063 10 P 0
L 2.4156413 3.1215827 2.4187174 3.1185066 9 P 0
L 2.4158425 2.7920629 2.4158425 2.8239922 10 P 0
L 2.4158425 2.7920629 2.4192759 2.7886295 10 P 0
L 2.4159134 2.9676063 2.4218189 2.9676063 10 P 0
L 2.4218189 2.9676063 2.4342756 2.980063 10 P 0
L 2.4279525 0.111063 2.4279525 0.2188809 1 P 0
L 2.4342756 2.980063 2.4738425 2.980063 10 P 0
L 2.4365786 0.2353319 2.4470546 0.2425914 1 P 0
L 2.462374 3.1722441 2.4904528 3.2003229 9 P 0
L 2.4685039 0.3633308 2.4685039 0.4050067 0 P 0
L 2.4685039 0.3633308 2.4688425 0.3629922 0 P 0
L 2.4685039 0.4050067 2.4685312 0.4076215 0 P 0
L 2.4688425 0.1433659 2.4688425 0.3291339 0 P 0
L 2.4698188 0.4109188 2.4698709 0.4109765 0 P 0
L 2.4698709 0.4109765 2.4698827 0.4109883 0 P 0
L 2.4904528 3.2003229 2.5098425 3.2003229 9 P 0
L 2.5098425 3.0428426 2.632496 3.0428426 1 P 0
L 2.5098425 3.1215827 2.5292322 3.1215827 9 P 0
L 2.5098425 3.279063 2.5838425 3.279063 9 P 0
L 2.511811 0.3630237 2.511811 0.4055118 0 P 0
L 2.511811 0.3630237 2.5118425 0.3629922 0 P 0
L 2.5118425 0.1521295 2.5118425 0.3291339 0 P 0
L 2.5292322 3.1215827 2.5918425 3.184193 9 P 0
L 2.5460625 0.111063 2.5460625 0.244843 1 P 0
L 2.5838425 3.279063 2.5898425 3.285063 9 P 0
L 2.5898425 3.285063 2.5898425 3.287063 9 P 0
L 2.5898425 3.287063 2.5908425 3.288063 9 P 0
L 2.5903118 3.1877512 2.5918425 3.1862205 9 P 0
L 2.5918425 3.184193 2.5918425 3.1862205 9 P 0
L 2.6248025 0.111063 2.6248025 0.235834 1 P 0
L 2.6248025 0.235834 2.636874 0.2479055 1 P 0
L 2.6318425 2.876063 2.6328425 2.877063 10 P 0
L 2.632496 3.0428426 2.6328425 3.0424961 1 P 0
L 2.6328425 2.877063 2.6328425 2.9716299 10 P 0
L 2.6328425 2.9716299 2.681126 2.9716299 9 P 0
L 2.6328425 3.0424961 2.6383465 3.0369921 1 P 0
L 2.6383465 3.0369921 2.7118425 3.0369921 1 P 0
L 2.6648425 0.1413138 2.6648425 0.3291339 0 P 0
L 2.6653543 0.3642278 2.6653543 0.4055118 0 P 0
L 2.681126 2.9716299 2.7118425 3.0023464 9 P 0
L 2.7035425 0.111063 2.7048425 0.112363 9 P 0
L 2.7047244 0.3631103 2.7047244 0.4055118 0 P 0
L 2.7047244 0.3631103 2.7048425 0.3629922 0 P 0
L 2.7048425 0.1428347 2.7048425 0.3291339 0 P 0
L 2.7118425 3.0023464 2.7118425 3.0031338 9 P 0
L 2.7198425 3.786063 2.7198504 3.7860709 1 P 0
L 2.7198504 3.7860709 2.7224094 3.7860709 1 P 0
L 2.7224094 3.7860709 2.7845147 3.7860709 1 P 0
L 2.7421251 0.1377953 2.7421251 0.2402527 1 P 0
L 2.7421251 0.2402527 2.7538409 0.2519685 1 P 0
L 2.7538409 0.2519685 2.7992126 0.2519685 1 P 0
L 2.7748425 3.5627559 2.7748425 3.566063 1 P 0
L 2.7748425 3.5627559 3.1570708 3.1805276 1 P 0
L 2.7748425 3.566063 4.0448425 3.566063 1 P 0
L 2.7814951 0.1377953 2.7827304 0.1390306 1 P 0
L 2.7827304 0.1390306 2.7827304 0.2354863 1 P 0
L 2.7827304 0.2354863 2.7992126 0.2519685 1 P 0
L 2.7845147 3.7860709 2.8095068 3.811063 1 P 0
L 2.7992126 0.2519685 2.7999951 0.2519685 1 P 0
L 2.8188976 0.3652734 2.8188976 0.4032734 0 P 0
L 2.8198425 0.1402641 2.8198425 0.3291339 0 P 0
L 2.8543307 0.3642278 2.8543307 0.4055118 0 P 0
L 2.8548425 0.1508142 2.8548425 0.3291339 0 P 0
L 2.8782843 0.2495967 2.878307 0.249595 1 P 0
L 2.8910408 0.2438013 2.8910565 0.2437858 1 P 0
L 2.8910565 0.2437858 2.898863 0.2359795 1 P 0
L 2.898863 0.1385374 2.898863 0.2359795 1 P 0
L 2.898863 0.1385374 2.8996051 0.1377953 1 P 0
L 2.898863 0.2359795 2.9232593 0.2359795 1 P 0
L 2.9232593 0.2359795 2.9349751 0.2242637 1 P 0
L 2.9349751 0.1417953 2.9349751 0.2242637 1 P 0
L 2.9349751 0.1417953 2.9357625 0.1410079 1 P 0
L 2.9357625 0.1410079 2.9389751 0.1377953 1 P 0
L 2.9798425 0.1414103 2.9798425 0.3291339 0 P 0
L 2.980315 0.3641329 2.980315 0.4079707 0 P 0
L 2.9803931 0.4088515 2.9804452 0.4091421 0 P 0
L 2.9804452 0.4091421 2.980457 0.4091539 0 P 0
L 2.998073 3.811063 3.004073 3.805063 1 P 0
L 3.004073 3.805063 3.2188425 3.805063 1 P 0
L 3.0185025 0.111063 3.0198425 0.112403 9 P 0
L 3.019685 0.3631497 3.019685 0.4055118 0 P 0
L 3.019685 0.3631497 3.0198425 0.3629922 0 P 0
L 3.0198425 0.1429313 3.0198425 0.3291339 0 P 0
L 3.0570851 0.1377953 3.0583207 0.1390309 1 P 0
L 3.0578725 0.111063 3.0583207 0.1115112 1 P 0
L 3.0583207 0.1115112 3.0583207 0.1390309 1 P 0
L 3.0583207 0.1390309 3.0593049 0.1400151 1 P 0
L 3.0593049 0.1400151 3.0593049 0.2313944 1 P 0
L 3.0593049 0.2313944 3.079879 0.2519685 1 P 0
L 3.079879 0.2519685 3.0974409 0.2519685 1 P 0
L 3.1570708 2.4856042 3.1570708 3.1805276 1 P 0
L 3.1570708 2.4856042 3.3688425 2.2738325 1 P 0
L 3.2188425 3.805063 3.2198425 3.806063 1 P 0
L 3.2198425 3.806063 3.2248425 3.811063 1 P 0
L 3.3688425 2.2520629 3.3688425 2.2738325 1 P 0
L 3.3688425 2.2520629 3.5498425 2.0710629 1 P 0
L 3.5348425 3.811063 3.5398425 3.806063 1 P 0
L 3.5598425 1.4734894 3.5598425 1.7392351 1 P 0
L 3.5598425 1.4734894 3.6005725 1.4327594 1 P 0
L 3.5598425 1.7392351 3.6398425 1.8192351 1 P 0
L 3.5718425 2.0108325 3.5718425 2.033063 1 P 0
L 3.5718425 2.0108325 3.5808425 2.0018325 1 P 0
L 3.5718425 2.033063 3.5718425 2.058063 1 P 0
L 3.5808425 1.8782351 3.5808425 2.0018325 1 P 0
L 3.5808425 1.8782351 3.6398425 1.8192351 1 P 0
L 3.6005725 1.060333 3.6005725 1.4327594 1 P 0
L 3.6005725 1.060333 3.8898425 0.771063 1 P 0
L 3.8298425 3.806063 3.9448425 3.806063 9 P 0
L 3.8898425 0.771063 4.3397218 1.2209423 1 P 0
L 3.9448425 3.806063 4.0498425 3.701063 9 P 0
L 4.0448425 3.566063 4.2548425 3.776063 1 P 0
L 4.0498425 3.665063 4.0498425 3.701063 9 P 0
L 4.3397218 1.2209423 6.4047218 1.2209423 1 P 0
L 4.5036614 2.7898819 4.5114724 2.7820709 1 P 0
L 4.5114724 2.7820709 5.9858504 2.7820709 1 P 0
L 5.2748425 3.511063 5.9948425 2.791063 1 P 0
L 5.9858504 2.7820709 5.9948425 2.791063 1 P 0
L 5.9948425 2.791063 6.2848425 2.501063 1 P 0
L 5.9948425 3.556063 6.4248425 3.126063 1 P 0
L 6.4047218 1.2209423 6.8448425 1.661063 1 P 0
L 6.4248425 2.181063 6.4248425 3.126063 1 P 0
L 6.4248425 3.126063 7.0048425 2.546063 1 P 0
L 6.7298425 1.336063 7.0048425 1.611063 1 P 0
L 7.0048425 1.611063 7.0048425 2.546063 1 P 0
P 0.0998425 0.806063 24 P 0 0 ;0=16,1=0
P 0.0998425 1.006063 24 P 0 0 ;0=16,1=0
P 0.0998425 1.331063 24 P 0 0 ;0=16,1=0
P 0.0998425 1.531063 24 P 0 0 ;0=16,1=0
P 0.0998425 1.856063 24 P 0 0 ;0=16,1=0
P 0.0998425 2.056063 24 P 0 0 ;0=16,1=0
P 0.0998425 2.381063 24 P 0 0 ;0=16,1=0
P 0.0998425 2.581063 24 P 0 0 ;0=16,1=0
P 0.1998425 0.906063 23 P 0 0 ;0=15,1=0
P 0.1998425 1.431063 23 P 0 0 ;0=15,1=0
P 0.1998425 1.956063 23 P 0 0 ;0=15,1=0
P 0.1998425 2.481063 23 P 0 0 ;0=15,1=0
P 0.285433 4.152063 29 P 0 0 ;0=22,1=0
P 0.2854331 0.3681102 29 P 0 0 ;0=22,1=0
P 0.2998425 0.806063 24 P 0 0 ;0=16,1=0
P 0.2998425 1.006063 24 P 0 0 ;0=16,1=0
P 0.2998425 1.331063 24 P 0 0 ;0=16,1=0
P 0.2998425 1.531063 24 P 0 0 ;0=16,1=0
P 0.2998425 1.856063 24 P 0 0 ;0=16,1=0
P 0.2998425 2.056063 24 P 0 0 ;0=16,1=0
P 0.2998425 2.381063 24 P 0 0 ;0=16,1=0
P 0.2998425 2.581063 24 P 0 0 ;0=16,1=0
P 1.4576771 4.053937 26 P 0 0 ;0=18,1=0
P 1.4576771 4.153937 26 P 0 0 ;0=18,1=0
P 1.4576771 4.253937 27 P 0 0 ;0=18,1=0
P 1.6968325 1.309833 25 P 0 0 ;0=17,1=0
P 1.6968325 2.097233 25 P 0 0 ;0=17,1=0
P 1.7972451 0.1572953 4 P 0 0 ;0=2,1=0,2
P 1.8366151 0.1377953 3 P 0 0 ;0=1,1=0,2
P 1.85187 0.2691929 11 P 0 0
P 1.8759851 0.1377953 3 P 0 0 ;0=1,1=0,2
P 1.9153551 0.1377953 3 P 0 0 ;0=1,1=0,2
P 1.9547251 0.1377953 3 P 0 0 ;0=1,1=0,2
P 1.9940951 0.1377953 3 P 0 0 ;0=1,1=0,2
P 2.0334651 0.1377953 3 P 0 0 ;0=1,1=0,2
P 2.0433071 4.057874 26 P 0 0 ;0=18,1=0
P 2.0433071 4.157874 26 P 0 0 ;0=18,1=0
P 2.0433071 4.257874 27 P 0 0 ;0=18,1=0
P 2.0728351 0.1377953 3 P 0 0 ;0=1,1=0,2
P 2.1122051 0.1377953 3 P 0 0 ;0=1,1=0,2
P 2.1306094 0.2685243 11 P 0 0
P 2.1515751 0.1377953 3 P 0 0 ;0=1,1=0,2
P 2.1909451 0.1377953 3 P 0 0 ;0=1,1=0,2
P 2.2031325 2.438533 25 P 0 0 ;0=17,1=0
P 2.2031425 0.958593 25 P 0 0 ;0=17,1=0
P 2.3090551 0.1377953 3 P 0 0 ;0=1,1=0,2
P 2.3274094 2.944063 8 P 0 0 ;0=6,1=0,2
P 2.3348425 3.0428426 2 P 0 0 ;0=0,1=0,2
P 2.3348425 3.1215827 2 P 0 0 ;0=0,1=0,2
P 2.3348425 3.2003229 2 P 0 0 ;0=0,1=0,2
P 2.3348425 3.279063 2 P 0 0 ;0=0,1=0,2
P 2.3484251 0.1377953 3 P 0 0 ;0=1,1=0,2
P 2.3498425 0.3291339 5 P 0 0 ;0=3,1=0,2
P 2.3498425 0.3629922 5 P 0 0 ;0=3,1=0,2
P 2.3519134 2.854063 7 P 0 0 ;0=5,1=0,2
P 2.3857717 2.854063 7 P 0 0 ;0=5,1=0,2
P 2.3877951 0.1377953 3 P 0 0 ;0=1,1=0,2
P 2.3898425 0.3291339 5 P 0 0 ;0=3,1=0,2
P 2.3898425 0.3629922 5 P 0 0 ;0=3,1=0,2
P 2.3982756 2.944063 8 P 0 0 ;0=6,1=0,2
P 2.4271651 0.1377953 3 P 0 0 ;0=1,1=0,2
P 2.4665351 0.1377953 3 P 0 0 ;0=1,1=0,2
P 2.4688425 0.3291339 5 P 0 0 ;0=3,1=0,2
P 2.4688425 0.3629922 5 P 0 0 ;0=3,1=0,2
P 2.5059051 0.1377953 3 P 0 0 ;0=1,1=0,2
P 2.5098425 3.0428426 2 P 0 0 ;0=0,1=0,2
P 2.5098425 3.1215827 2 P 0 0 ;0=0,1=0,2
P 2.5098425 3.2003229 2 P 0 0 ;0=0,1=0,2
P 2.5098425 3.279063 2 P 0 0 ;0=0,1=0,2
P 2.5118425 0.3291339 5 P 0 0 ;0=3,1=0,2
P 2.5118425 0.3629922 5 P 0 0 ;0=3,1=0,2
P 2.5452751 0.1377953 3 P 0 0 ;0=1,1=0,2
P 2.5846451 0.1377953 3 P 0 0 ;0=1,1=0,2
P 2.6240151 0.1377953 3 P 0 0 ;0=1,1=0,2
P 2.6328425 2.9716299 6 P 0 0 ;0=4,1=0,2
P 2.6328425 3.0424961 6 P 0 0 ;0=4,1=0,2
P 2.6633851 0.1377953 3 P 0 0 ;0=1,1=0,2
P 2.6648425 0.3291339 5 P 0 0 ;0=3,1=0,2
P 2.6648425 0.3629922 5 P 0 0 ;0=3,1=0,2
P 2.7027551 0.1377953 3 P 0 0 ;0=1,1=0,2
P 2.7048425 0.3291339 5 P 0 0 ;0=3,1=0,2
P 2.7048425 0.3629922 5 P 0 0 ;0=3,1=0,2
P 2.7118425 3.0031338 5 P 0 0 ;0=3,1=0,2
P 2.7118425 3.0369921 5 P 0 0 ;0=3,1=0,2
P 2.7421251 0.1377953 3 P 0 0 ;0=1,1=0,2
P 2.7814951 0.1377953 3 P 0 0 ;0=1,1=0,2
P 2.8198425 0.3291339 5 P 0 0 ;0=3,1=0,2
P 2.8198425 0.3629922 5 P 0 0 ;0=3,1=0,2
P 2.8208651 0.1377953 3 P 0 0 ;0=1,1=0,2
P 2.8548425 0.3291339 5 P 0 0 ;0=3,1=0,2
P 2.8548425 0.3629922 5 P 0 0 ;0=3,1=0,2
P 2.8602351 0.1377953 3 P 0 0 ;0=1,1=0,2
P 2.8996051 0.1377953 3 P 0 0 ;0=1,1=0,2
P 2.9389751 0.1377953 3 P 0 0 ;0=1,1=0,2
P 2.9783451 0.1377953 3 P 0 0 ;0=1,1=0,2
P 2.9798425 0.3291339 5 P 0 0 ;0=3,1=0,2
P 2.9798425 0.3629922 5 P 0 0 ;0=3,1=0,2
P 2.9905325 2.438533 25 P 0 0 ;0=17,1=0
P 2.9905425 0.958593 25 P 0 0 ;0=17,1=0
P 2.9948425 4.0861024 15 P 0 0 ;0=8,1=0
P 3.0177151 0.1377953 3 P 0 0 ;0=1,1=0,2
P 3.0198425 0.3291339 5 P 0 0 ;0=3,1=0,2
P 3.0198425 0.3629922 5 P 0 0 ;0=3,1=0,2
P 3.0570851 0.1377953 3 P 0 0 ;0=1,1=0,2
P 3.0964551 0.1377953 3 P 0 0 ;0=1,1=0,2
P 3.2948425 4.0861024 15 P 0 0 ;0=8,1=0
P 3.5717425 1.309793 25 P 0 0 ;0=17,1=0
P 3.5717425 2.097193 25 P 0 0 ;0=17,1=0
P 3.7848425 4.126063 14 P 0 0 ;0=7,1=0
P 3.9580709 4.126063 14 P 0 0 ;0=7,1=0
P 3.9797272 0.8906186 18 P 0 0 ;0=10,1=0
P 3.9797272 2.4890438 18 P 0 0 ;0=10,1=0
P 4.0624044 2.595343 18 P 0 0 ;0=10,1=0
P 4.1805146 2.595343 18 P 0 0 ;0=10,1=0
P 4.2986248 2.595343 18 P 0 0 ;0=10,1=0
P 4.3277559 1.0074803 17 P 0 0 ;0=9,1=0
P 4.3277559 2.3074803 16 P 0 0 ;0=9,1=0
P 4.7277559 2.3074803 16 P 0 0 ;0=9,1=0
P 4.9277559 1.0074803 16 P 0 0 ;0=9,1=0
P 4.9277559 2.3074803 16 P 0 0 ;0=9,1=0
P 5.1277559 1.0074803 16 P 0 0 ;0=9,1=0
P 5.1277559 2.3074803 16 P 0 0 ;0=9,1=0
P 5.3277559 1.0074803 16 P 0 0 ;0=9,1=0
P 5.3277559 2.3074803 16 P 0 0 ;0=9,1=0
P 5.5781524 0.8906186 18 P 0 0 ;0=10,1=0
P 5.5781524 1.6898312 18 P 0 0 ;0=10,1=0
P 5.5781524 2.4890438 18 P 0 0 ;0=10,1=0
P 5.7234252 3.8444882 19 P 0 0 ;0=11,1=0
P 5.7234252 4.0255906 19 P 0 0 ;0=11,1=0
P 5.9348031 3.9379527 20 P 0 0 ;0=12,1=0
P 6.1198425 3.8198425 22 P 0 0 ;0=14,1=0
P 6.1198425 4.056063 21 P 0 0 ;0=13,1=0
P 6.5694882 3.5895276 19 P 0 0 ;0=20,1=0
P 6.5694882 3.806063 19 P 0 0 ;0=20,1=0
P 6.5694882 4.0934646 28 P 0 0 ;0=21,1=0
P 6.7348425 3.5895276 19 P 0 0 ;0=20,1=0
P 6.7348425 3.806063 19 P 0 0 ;0=20,1=0
P 6.9001969 3.5895276 19 P 0 0 ;0=20,1=0
P 6.9001969 3.806063 19 P 0 0 ;0=20,1=0
P 6.9001969 4.0934646 28 P 0 0 ;0=19,1=0
S P 0
OB 4.3498425 4.3342197 I
OS 2.0148425 4.3342197
OS 2.0117211 4.3335988
OS 2.0090748 4.3318307
OS 2.0073067 4.3291844
OS 2.0066858 4.326063
OS 2.0066858 4.293374
OS 2.0073067 4.2902526
OS 2.0078071 4.2895037
OS 2.0078071 4.2262443
OS 2.0073067 4.2254954
OS 2.0066858 4.222374
OS 2.0066858 4.1869833
OS 2.0069573 4.1856183
OS 2.0071613 4.1842387
OS 2.0072668 4.1840625
OS 2.0073067 4.1838619
OS 2.0080802 4.1827043
OS 2.0087964 4.1815082
OS 2.0089609 4.1813861
OS 2.0090748 4.1812156
OS 2.0097978 4.1807325
OS 2.0104583 4.1799335
OS 2.0122979 4.1757771
OS 2.0087209 4.1671414
OS 2.0075008 4.157874
OS 2.0087209 4.1486066
OS 2.0122979 4.1399709
OS 2.0104583 4.1358145
OS 2.0097978 4.1350155
OS 2.0090748 4.1345324
OS 2.0089609 4.1343619
OS 2.0087964 4.1342398
OS 2.0080806 4.1330444
OS 2.0073067 4.1318861
OS 2.0072667 4.1316852
OS 2.0071614 4.1315093
OS 2.0069575 4.1301308
OS 2.0066858 4.1287647
OS 2.0066858 4.0869833
OS 2.0069573 4.0856183
OS 2.0071613 4.0842387
OS 2.0072668 4.0840625
OS 2.0073067 4.0838619
OS 2.0080802 4.0827043
OS 2.0087964 4.0815082
OS 2.0089609 4.0813861
OS 2.0090748 4.0812156
OS 2.0097978 4.0807325
OS 2.0104583 4.0799335
OS 2.0122979 4.0757771
OS 2.0087209 4.0671414
OS 2.0075008 4.057874
OS 2.0087209 4.0486066
OS 2.0122979 4.0399709
OS 2.0104583 4.0358145
OS 2.0097978 4.0350155
OS 2.0090748 4.0345324
OS 2.0089609 4.0343619
OS 2.0087964 4.0342398
OS 2.0080806 4.0330444
OS 2.0073067 4.0318861
OS 2.0072667 4.0316852
OS 2.0071614 4.0315093
OS 2.0069575 4.0301308
OS 2.0066858 4.0287647
OS 2.0066858 3.850728
OS 2.0069918 3.8491898
OS 2.0072894 3.8476485
OS 2.0073022 3.8476291
OS 2.0073067 3.8476066
OS 2.008179 3.846301
OS 2.0090429 3.8449925
OS 2.0090618 3.8449797
OS 2.0090748 3.8449603
OS 2.0103831 3.8440861
OS 2.0116793 3.8432096
OS 2.0146979 3.8419396
OS 2.013529 3.836063
OS 2.0136749 3.8353296
OS 2.0130932 3.8343873
OS 2.0093423 3.8314814
OS 2.0048425 3.8323765
OS 1.9985996 3.8311347
OS 1.9933071 3.8275984
OS 1.9897708 3.8223059
OS 1.988529 3.816063
OS 1.9897708 3.8098201
OS 1.9933071 3.8045276
OS 1.9985996 3.8009913
OS 2.0048424 3.7997495
OS 2.0066858 3.7982367
OS 2.0066858 2.718063
OS 2.0073067 2.7149416
OS 2.0090748 2.7122953
OS 2.0117211 2.7105272
OS 2.0148425 2.7099063
OS 2.3498425 2.7099063
OS 2.3529639 2.7105272
OS 2.3556102 2.7122953
OS 2.3573783 2.7149416
OS 2.3579992 2.718063
OS 2.3579992 2.8334646
OS 2.3876251 2.8334646
OS 2.4025878 2.8185019
OS 2.4025878 2.7920629
OS 2.4031166 2.7894046
OS 2.4029624 2.7886295
OS 2.4042042 2.7823866
OS 2.4077405 2.7770941
OS 2.413033 2.7735578
OS 2.4192759 2.772316
OS 2.4255188 2.7735578
OS 2.4308113 2.7770941
OS 2.4310756 2.7774896
OS 2.4370112 2.7773731
OS 2.443754 2.7663699
OS 2.4547943 2.7534433
OS 2.4677209 2.742403
OS 2.4822154 2.7335207
OS 2.497921 2.7270152
OS 2.5144508 2.7230468
OS 2.531398 2.721713
OS 2.5483452 2.7230468
OS 2.564875 2.7270152
OS 2.5805806 2.7335207
OS 2.5950751 2.742403
OS 2.6080017 2.7534433
OS 2.619042 2.7663699
OS 2.6279243 2.7808644
OS 2.6344298 2.79657
OS 2.6383982 2.8130998
OS 2.639732 2.830047
OS 2.6383982 2.8469942
OS 2.6358691 2.857529
OS 2.6380855 2.8609914
OS 2.6433779 2.8645276
OS 2.6469142 2.8698201
OS 2.648156 2.876063
OS 2.6469142 2.8823059
OS 2.6460972 2.8835286
OS 2.6460972 2.9409921
OS 2.6693858 2.9409921
OS 2.6693858 2.9593948
OS 2.681126 2.9593948
OS 2.6858082 2.9603261
OS 2.6897775 2.9629784
OS 2.7085471 2.981748
OS 2.7324409 2.981748
OS 2.7324409 3.0245196
OS 2.6912441 3.0245196
OS 2.6912441 2.999051
OS 2.6760581 2.983865
OS 2.6693858 2.983865
OS 2.6693858 3.0022677
OS 2.5962992 3.0022677
OS 2.5962992 2.9409921
OS 2.6195878 2.9409921
OS 2.6195878 2.900784
OS 2.6145878 2.8989394
OS 2.6080017 2.9066507
OS 2.5950751 2.917691
OS 2.5805806 2.9265733
OS 2.564875 2.9330788
OS 2.5483452 2.9370472
OS 2.531398 2.938381
OS 2.5144508 2.9370472
OS 2.497921 2.9330788
OS 2.4822154 2.9265733
OS 2.4677209 2.917691
OS 2.4547943 2.9066507
OS 2.443754 2.8937241
OS 2.4348717 2.8792296
OS 2.4283662 2.863524
OS 2.4243978 2.8469942
OS 2.4239315 2.8410698
OS 2.4192405 2.8393392
OS 2.4071575 2.8514222
OS 2.4071575 2.8746614
OS 2.3579992 2.8746614
OS 2.3579992 2.9075197
OS 2.3580472 2.9075197
OS 2.3580472 2.9806063
OS 2.3579992 2.9806063
OS 2.3579992 3.0127954
OS 2.3842795 3.0127954
OS 2.3842795 3.0728898
OS 2.3579992 3.0728898
OS 2.3579992 3.0915355
OS 2.3842795 3.0915355
OS 2.3842795 3.1093476
OS 2.4055942 3.1093476
OS 2.407182 3.1069712
OS 2.4081253 3.1063409
OS 2.4081253 3.1003275
OS 2.4057888 3.0987663
OS 2.4007141 3.0911714
OS 2.3989321 3.0822126
OS 2.4007141 3.0732538
OS 2.4057888 3.0656589
OS 2.4133837 3.0605842
OS 2.4223425 3.0588022
OS 2.4313013 3.0605842
OS 2.4388962 3.0656589
OS 2.4439709 3.0732538
OS 2.4457529 3.0822126
OS 2.4439709 3.0911714
OS 2.4388962 3.0987663
OS 2.4329346 3.1027496
OS 2.4313655 3.1052197
OS 2.4315364 3.1088922
OS 2.4337891 3.1122637
OS 2.4350309 3.1185066
OS 2.4337891 3.1247495
OS 2.4302528 3.130042
OS 2.4249603 3.1335783
OS 2.4187174 3.1348201
OS 2.4136785 3.1338178
OS 2.3842795 3.1338178
OS 2.3842795 3.1516299
OS 2.3579992 3.1516299
OS 2.3579992 3.1702757
OS 2.3842795 3.1702757
OS 2.3842795 3.1876153
OS 2.4035669 3.1876153
OS 2.4078122 3.1847787
OS 2.4140551 3.1835369
OS 2.420298 3.1847787
OS 2.4255905 3.188315
OS 2.4291268 3.1936075
OS 2.4303686 3.1998504
OS 2.4291268 3.2060933
OS 2.4255905 3.2113858
OS 2.4250776 3.2117285
OS 2.4261334 3.2170365
OS 2.4313013 3.2180645
OS 2.4388962 3.2231392
OS 2.4439709 3.2307341
OS 2.4457529 3.2396929
OS 2.4439709 3.2486517
OS 2.4388962 3.2562466
OS 2.4313013 3.2613213
OS 2.4223425 3.2631033
OS 2.4133837 3.2613213
OS 2.4057888 3.2562466
OS 2.4007141 3.2486517
OS 2.3989321 3.2396929
OS 2.4007141 3.2307341
OS 2.4057888 3.2231392
OS 2.4098502 3.2204255
OS 2.4087944 3.2151175
OS 2.4078122 3.2149221
OS 2.4035669 3.2120855
OS 2.3842795 3.2120855
OS 2.3842795 3.2303701
OS 2.3579992 3.2303701
OS 2.3579992 3.2490158
OS 2.3842795 3.2490158
OS 2.3842795 3.2658083
OS 2.3978425 3.2658083
OS 2.4029149 3.2668173
OS 2.407215 3.2696905
OS 2.4168778 3.2793533
OS 2.4200854 3.2799913
OS 2.4253779 3.2835276
OS 2.4289142 3.2888201
OS 2.430156 3.295063
OS 2.4289142 3.3013059
OS 2.4253779 3.3065984
OS 2.4200854 3.3101347
OS 2.4138425 3.3113765
OS 2.4075996 3.3101347
OS 2.4023071 3.3065984
OS 2.3987708 3.3013059
OS 2.3981328 3.2980983
OS 2.3923522 3.2923177
OS 2.3842795 3.2923177
OS 2.3842795 3.3091102
OS 2.3579992 3.3091102
OS 2.3579992 3.3226844
OS 2.6745231 3.6392082
OS 2.674748 3.6395448
OS 2.6750608 3.6398015
OS 2.6756255 3.6408581
OS 2.6762912 3.6418544
OS 2.6763702 3.6422515
OS 2.6765609 3.6426082
OS 2.6798424 3.6447494
OS 2.6860854 3.6459913
OS 2.6913779 3.6495276
OS 2.6949142 3.6548201
OS 2.6957968 3.659257
OS 2.6961561 3.661063
OS 2.6982973 3.6643446
OS 2.698654 3.6645353
OS 2.6990511 3.6646143
OS 2.7000469 3.6652797
OS 2.7011041 3.6658447
OS 2.7013611 3.6661578
OS 2.7016973 3.6663825
OS 2.7132212 3.6779063
OS 3.5207477 3.6779063
OS 3.5222645 3.6729063
OS 3.5203071 3.6715984
OS 3.5167708 3.6663059
OS 3.515529 3.660063
OS 3.5167708 3.6538201
OS 3.5203071 3.6485276
OS 3.5255996 3.6449913
OS 3.5318425 3.6437495
OS 3.5380854 3.6449913
OS 3.5433779 3.6485276
OS 3.5469142 3.6538201
OS 3.548156 3.660063
OS 3.5469142 3.6663059
OS 3.5433779 3.6715984
OS 3.5414205 3.6729063
OS 3.5429373 3.6779063
OS 3.804842 3.6779063
OS 3.8048425 3.6779062
OS 3.8079639 3.6785272
OS 3.8106102 3.6802953
OS 3.8106104 3.6802956
OS 3.9137557 3.7834408
OS 3.9155239 3.7860872
OS 3.9161448 3.7892084
OS 3.9200787 3.7938279
OS 3.9397746 3.7938279
OS 4.0376074 3.6959951
OS 4.0376074 3.6755512
OS 4.0347708 3.6713059
OS 4.033529 3.665063
OS 4.0347708 3.6588201
OS 4.0383071 3.6535276
OS 4.0435996 3.6499913
OS 4.0498425 3.6487495
OS 4.0560854 3.6499913
OS 4.0613779 3.6535276
OS 4.0649142 3.6588201
OS 4.066156 3.665063
OS 4.0649142 3.6713059
OS 4.0620776 3.6755512
OS 4.0620776 3.701063
OS 4.0611463 3.7057452
OS 4.058494 3.7097145
OS 3.953494 3.8147145
OS 3.9526586 3.8152727
OS 3.9519159 3.8216011
OS 4.0682212 3.9379063
OS 4.1814639 3.9379063
OS 4.3416858 3.7776843
OS 4.3416858 3.6629063
OS 3.8503629 3.1715834
OS 3.8457549 3.1740465
OS 3.846156 3.176063
OS 3.8449142 3.1823059
OS 3.8413779 3.1875984
OS 3.8360854 3.1911347
OS 3.8298425 3.1923765
OS 3.8235996 3.1911347
OS 3.8183071 3.1875984
OS 3.8147708 3.1823059
OS 3.813529 3.176063
OS 3.8147708 3.1698201
OS 3.8183071 3.1645276
OS 3.8235996 3.1609913
OS 3.8298425 3.1597495
OS 3.831859 3.1601506
OS 3.8343221 3.1555426
OS 3.8248425 3.146063
OS 3.8248425 2.201063
OS 4.1548425 1.871063
OS 6.6872812 1.871063
OS 6.6883071 1.8695276
OS 6.6935996 1.8659913
OS 6.6998425 1.8647495
OS 6.7060854 1.8659913
OS 6.7113779 1.8695276
OS 6.7124038 1.871063
OS 6.9016858 1.871063
OS 6.9016858 1.6494416
OS 6.6376591 1.385415
OS 6.6350854 1.3871347
OS 6.6288425 1.3883765
OS 6.6225996 1.3871347
OS 6.6173071 1.3835984
OS 6.6137708 1.3783059
OS 6.612529 1.372063
OS 6.6137708 1.3658201
OS 6.6154905 1.3632463
OS 6.5840748 1.3318307
OS 6.5823067 1.3291845
OS 6.5816857 1.326063
OS 6.5816858 1.3260625
OS 6.5816858 1.241063
OS 6.5823067 1.2379415
OS 6.5840748 1.2352953
OS 6.5840751 1.2352951
OS 6.6440748 1.1752953
OS 6.646721 1.1735272
OS 6.6498425 1.1729062
OS 6.649843 1.1729063
OS 6.779842 1.1729063
OS 6.7798425 1.1729062
OS 6.7829639 1.1735272
OS 6.7856102 1.1752953
OS 6.9302231 1.3199082
OS 6.9348425 1.3179947
OS 6.9348425 1.216063
OS 6.3298425 0.611063
OS 3.7848425 0.611063
OS 2.6382883 1.7576175
OS 2.638378 1.7585277
OS 2.6419142 1.7638201
OS 2.643156 1.770063
OS 2.6419142 1.7763059
OS 2.6383779 1.7815984
OS 2.6330854 1.7851347
OS 2.6268425 1.7863765
OS 2.6205996 1.7851347
OS 2.6153072 1.7815985
OS 2.614397 1.7815088
OS 2.4254888 1.970417
OS 2.4249142 1.9733059
OS 2.4213779 1.9785984
OS 2.4160854 1.9821347
OS 2.4131965 1.9827093
OS 1.3558428 3.0400633
OS 1.3558428 4.1628831
OS 1.3570078 4.1636615
OS 1.3605441 4.168954
OS 1.3617859 4.1751969
OS 1.3605441 4.1814398
OS 1.3570078 4.1867323
OS 1.3558428 4.1875107
OS 1.3558428 4.341063
OS 1.7093962 4.341063
OS 1.7120688 4.336063
OS 1.7117708 4.3356169
OS 1.710529 4.329374
OS 1.7117708 4.3231311
OS 1.7153071 4.3178386
OS 1.7205996 4.3143023
OS 1.7268425 4.3130605
OS 1.7330854 4.3143023
OS 1.7383779 4.3178386
OS 1.7419142 4.3231311
OS 1.743156 4.329374
OS 1.7419142 4.3356169
OS 1.7416162 4.336063
OS 1.7442888 4.341063
OS 1.7713962 4.341063
OS 1.7740688 4.336063
OS 1.7737708 4.3356169
OS 1.772529 4.329374
OS 1.7737708 4.3231311
OS 1.7773071 4.3178386
OS 1.7825996 4.3143023
OS 1.7888425 4.3130605
OS 1.7950854 4.3143023
OS 1.8003779 4.3178386
OS 1.8039142 4.3231311
OS 1.805156 4.329374
OS 1.8039142 4.3356169
OS 1.8036162 4.336063
OS 1.8062888 4.341063
OS 4.3498425 4.341063
OS 4.3498425 4.3342197
OE
OB 1.4931771 4.289437 H
OS 1.4221771 4.289437
OS 1.4221771 4.218437
OS 1.4931771 4.218437
OS 1.4931771 4.289437
OE
OB 1.5698819 4.1875734 H
OS 1.563639 4.1863316
OS 1.5583465 4.1827953
OS 1.5548102 4.1775028
OS 1.5535684 4.1712599
OS 1.5548102 4.165017
OS 1.5583465 4.1597245
OS 1.563639 4.1561882
OS 1.5698819 4.1549464
OS 1.5761248 4.1561882
OS 1.5814173 4.1597245
OS 1.5849536 4.165017
OS 1.5861954 4.1712599
OS 1.5849536 4.1775028
OS 1.5814173 4.1827953
OS 1.5761248 4.1863316
OS 1.5698819 4.1875734
OE
OB 1.7798425 4.1723765 H
OS 1.7735996 4.1711347
OS 1.7683071 4.1675984
OS 1.7647708 4.1623059
OS 1.763529 4.156063
OS 1.7647708 4.1498201
OS 1.7683071 4.1445276
OS 1.7735996 4.1409913
OS 1.7798425 4.1397495
OS 1.7860854 4.1409913
OS 1.7913779 4.1445276
OS 1.7949142 4.1498201
OS 1.796156 4.156063
OS 1.7949142 4.1623059
OS 1.7913779 4.1675984
OS 1.7860854 4.1711347
OS 1.7798425 4.1723765
OE
OB 1.4576771 4.1897433 H
OS 1.4484097 4.1885232
OS 1.4397739 4.1849462
OS 1.4323582 4.1792559
OS 1.4266679 4.1718402
OS 1.4230909 4.1632044
OS 1.4218708 4.153937
OS 1.4230909 4.1446696
OS 1.4266679 4.1360338
OS 1.4323582 4.1286181
OS 1.4397739 4.1229278
OS 1.4484097 4.1193508
OS 1.4576771 4.1181307
OS 1.4669445 4.1193508
OS 1.4755803 4.1229278
OS 1.482996 4.1286181
OS 1.4886863 4.1360338
OS 1.4922633 4.1446696
OS 1.4934834 4.153937
OS 1.4922633 4.1632044
OS 1.4886863 4.1718402
OS 1.482996 4.1792559
OS 1.4755803 4.1849462
OS 1.4669445 4.1885232
OS 1.4576771 4.1897433
OE
OB 1.7498425 4.1263765 H
OS 1.7435996 4.1251347
OS 1.7383071 4.1215984
OS 1.7347708 4.1163059
OS 1.733529 4.110063
OS 1.7347708 4.1038201
OS 1.7383071 4.0985276
OS 1.7435996 4.0949913
OS 1.7498425 4.0937495
OS 1.7560854 4.0949913
OS 1.7613779 4.0985276
OS 1.7649142 4.1038201
OS 1.766156 4.110063
OS 1.7649142 4.1163059
OS 1.7613779 4.1215984
OS 1.7560854 4.1251347
OS 1.7498425 4.1263765
OE
OB 1.6918425 4.0953765 H
OS 1.6855996 4.0941347
OS 1.6803071 4.0905984
OS 1.6767708 4.0853059
OS 1.675529 4.079063
OS 1.6767708 4.0728201
OS 1.6803071 4.0675276
OS 1.6855996 4.0639913
OS 1.6918425 4.0627495
OS 1.6980854 4.0639913
OS 1.7033779 4.0675276
OS 1.7069142 4.0728201
OS 1.708156 4.079063
OS 1.7069142 4.0853059
OS 1.7033779 4.0905984
OS 1.6980854 4.0941347
OS 1.6918425 4.0953765
OE
OB 1.4576771 4.0897433 H
OS 1.4484097 4.0885232
OS 1.4397739 4.0849462
OS 1.4323582 4.0792559
OS 1.4266679 4.0718402
OS 1.4230909 4.0632044
OS 1.4218708 4.053937
OS 1.4230909 4.0446696
OS 1.4266679 4.0360338
OS 1.4323582 4.0286181
OS 1.4397739 4.0229278
OS 1.4484097 4.0193508
OS 1.4576771 4.0181307
OS 1.4669445 4.0193508
OS 1.4755803 4.0229278
OS 1.482996 4.0286181
OS 1.4886863 4.0360338
OS 1.4922633 4.0446696
OS 1.4934834 4.053937
OS 1.4922633 4.0632044
OS 1.4886863 4.0718402
OS 1.482996 4.0792559
OS 1.4755803 4.0849462
OS 1.4669445 4.0885232
OS 1.4576771 4.0897433
OE
OB 1.9038425 4.0343765 H
OS 1.8975996 4.0331347
OS 1.8923071 4.0295984
OS 1.8887708 4.0243059
OS 1.887529 4.018063
OS 1.8887708 4.0118201
OS 1.8923071 4.0065276
OS 1.8975996 4.0029913
OS 1.9038425 4.0017495
OS 1.9100854 4.0029913
OS 1.9153779 4.0065276
OS 1.9189142 4.0118201
OS 1.920156 4.018063
OS 1.9189142 4.0243059
OS 1.9153779 4.0295984
OS 1.9100854 4.0331347
OS 1.9038425 4.0343765
OE
OB 1.4084645 3.9966285 H
OS 1.4022216 3.9953867
OS 1.3969291 3.9918504
OS 1.3933928 3.9865579
OS 1.392151 3.980315
OS 1.3933928 3.9740721
OS 1.3969291 3.9687796
OS 1.4022216 3.9652433
OS 1.4084645 3.9640015
OS 1.4147074 3.9652433
OS 1.4199999 3.9687796
OS 1.4235362 3.9740721
OS 1.424778 3.980315
OS 1.4235362 3.9865579
OS 1.4199999 3.9918504
OS 1.4147074 3.9953867
OS 1.4084645 3.9966285
OE
OB 4.0858425 3.9083765 H
OS 4.0795996 3.9071347
OS 4.0743071 3.9035984
OS 4.0707708 3.8983059
OS 4.069529 3.892063
OS 4.0707708 3.8858201
OS 4.0743071 3.8805276
OS 4.0795996 3.8769913
OS 4.0858425 3.8757495
OS 4.0920854 3.8769913
OS 4.0973779 3.8805276
OS 4.1009142 3.8858201
OS 4.102156 3.892063
OS 4.1009142 3.8983059
OS 4.0973779 3.9035984
OS 4.0920854 3.9071347
OS 4.0858425 3.9083765
OE
OB 4.1948425 3.9003765 H
OS 4.1885996 3.8991347
OS 4.1833071 3.8955984
OS 4.1797708 3.8903059
OS 4.178529 3.884063
OS 4.1797708 3.8778201
OS 4.1833071 3.8725276
OS 4.1885996 3.8689913
OS 4.1948425 3.8677495
OS 4.2010854 3.8689913
OS 4.2063779 3.8725276
OS 4.2099142 3.8778201
OS 4.211156 3.884063
OS 4.2099142 3.8903059
OS 4.2063779 3.8955984
OS 4.2010854 3.8991347
OS 4.1948425 3.9003765
OE
OB 4.0398425 3.8003765 H
OS 4.0335996 3.7991347
OS 4.0283071 3.7955984
OS 4.0247708 3.7903059
OS 4.023529 3.784063
OS 4.0247708 3.7778201
OS 4.0283071 3.7725276
OS 4.0335996 3.7689913
OS 4.0398425 3.7677495
OS 4.0460854 3.7689913
OS 4.0513779 3.7725276
OS 4.0549142 3.7778201
OS 4.056156 3.784063
OS 4.0549142 3.7903059
OS 4.0513779 3.7955984
OS 4.0460854 3.7991347
OS 4.0398425 3.8003765
OE
OB 1.8498425 3.7173765 H
OS 1.8435996 3.7161347
OS 1.8383071 3.7125984
OS 1.8347708 3.7073059
OS 1.833529 3.701063
OS 1.8347708 3.6948201
OS 1.8383071 3.6895276
OS 1.8435996 3.6859913
OS 1.8498425 3.6847495
OS 1.8560854 3.6859913
OS 1.8613779 3.6895276
OS 1.8649142 3.6948201
OS 1.866156 3.701063
OS 1.8649142 3.7073059
OS 1.8613779 3.7125984
OS 1.8560854 3.7161347
OS 1.8498425 3.7173765
OE
OB 1.7548425 3.6773765 H
OS 1.7485996 3.6761347
OS 1.7433071 3.6725984
OS 1.7397708 3.6673059
OS 1.738529 3.661063
OS 1.7397708 3.6548201
OS 1.7433071 3.6495276
OS 1.7485996 3.6459913
OS 1.7548425 3.6447495
OS 1.7610854 3.6459913
OS 1.7663779 3.6495276
OS 1.7699142 3.6548201
OS 1.771156 3.661063
OS 1.7699142 3.6673059
OS 1.7663779 3.6725984
OS 1.7610854 3.6761347
OS 1.7548425 3.6773765
OE
OB 3.4248425 3.6523765 H
OS 3.4185996 3.6511347
OS 3.4133071 3.6475984
OS 3.4097708 3.6423059
OS 3.408529 3.636063
OS 3.4097708 3.6298201
OS 3.4133071 3.6245276
OS 3.4185996 3.6209913
OS 3.4248425 3.6197495
OS 3.4310854 3.6209913
OS 3.4363779 3.6245276
OS 3.4399142 3.6298201
OS 3.441156 3.636063
OS 3.4399142 3.6423059
OS 3.4363779 3.6475984
OS 3.4310854 3.6511347
OS 3.4248425 3.6523765
OE
OB 2.7998425 3.6323765 H
OS 2.7935996 3.6311347
OS 2.7883071 3.6275984
OS 2.7847708 3.6223059
OS 2.783529 3.616063
OS 2.7847708 3.6098201
OS 2.7883071 3.6045276
OS 2.7935996 3.6009913
OS 2.7998425 3.5997495
OS 2.8060854 3.6009913
OS 2.8113779 3.6045276
OS 2.8149142 3.6098201
OS 2.816156 3.616063
OS 2.8149142 3.6223059
OS 2.8113779 3.6275984
OS 2.8060854 3.6311347
OS 2.7998425 3.6323765
OE
OB 1.8848425 3.6173765 H
OS 1.8785996 3.6161347
OS 1.8733071 3.6125984
OS 1.8697708 3.6073059
OS 1.868529 3.601063
OS 1.8697708 3.5948201
OS 1.8733071 3.5895276
OS 1.8785996 3.5859913
OS 1.8848425 3.5847495
OS 1.8910854 3.5859913
OS 1.8963779 3.5895276
OS 1.8999142 3.5948201
OS 1.901156 3.601063
OS 1.8999142 3.6073059
OS 1.8963779 3.6125984
OS 1.8910854 3.6161347
OS 1.8848425 3.6173765
OE
OB 3.2398425 3.6123765 H
OS 3.2335996 3.6111347
OS 3.2283071 3.6075984
OS 3.2247708 3.6023059
OS 3.223529 3.596063
OS 3.2247708 3.5898201
OS 3.2283071 3.5845276
OS 3.2335996 3.5809913
OS 3.2398425 3.5797495
OS 3.2460854 3.5809913
OS 3.2513779 3.5845276
OS 3.2549142 3.5898201
OS 3.256156 3.596063
OS 3.2549142 3.6023059
OS 3.2513779 3.6075984
OS 3.2460854 3.6111347
OS 3.2398425 3.6123765
OE
OB 1.5498425 3.6373765 H
OS 1.5435996 3.6361347
OS 1.5383071 3.6325984
OS 1.5347708 3.6273059
OS 1.533529 3.621063
OS 1.5347708 3.6148201
OS 1.5383071 3.6095276
OS 1.5435996 3.6059913
OS 1.5498425 3.6047495
OS 1.5560854 3.6059913
OS 1.5563282 3.6061536
OS 1.5599331 3.6025487
OS 1.5597708 3.6023059
OS 1.558529 3.596063
OS 1.5597708 3.5898201
OS 1.5633071 3.5845276
OS 1.5685996 3.5809913
OS 1.5748425 3.5797495
OS 1.5810854 3.5809913
OS 1.5863779 3.5845276
OS 1.5899142 3.5898201
OS 1.591156 3.596063
OS 1.5899142 3.6023059
OS 1.5863779 3.6075984
OS 1.5810854 3.6111347
OS 1.5748425 3.6123765
OS 1.5685996 3.6111347
OS 1.5683568 3.6109724
OS 1.5647519 3.6145773
OS 1.5649142 3.6148201
OS 1.566156 3.621063
OS 1.5649142 3.6273059
OS 1.5613779 3.6325984
OS 1.5560854 3.6361347
OS 1.5498425 3.6373765
OE
OB 4.1203866 3.6104643 H
OS 4.1141437 3.6092225
OS 4.1088512 3.6056862
OS 4.1053149 3.6003937
OS 4.1040731 3.5941508
OS 4.1053149 3.5879079
OS 4.1088512 3.5826154
OS 4.1141437 3.5790791
OS 4.1203866 3.5778373
OS 4.1266295 3.5790791
OS 4.131922 3.5826154
OS 4.1354583 3.5879079
OS 4.1367001 3.5941508
OS 4.1354583 3.6003937
OS 4.131922 3.6056862
OS 4.1266295 3.6092225
OS 4.1203866 3.6104643
OE
OB 1.4408425 3.5733765 H
OS 1.4345996 3.5721347
OS 1.4293071 3.5685984
OS 1.4257708 3.5633059
OS 1.424529 3.557063
OS 1.4257708 3.5508201
OS 1.4293071 3.5455276
OS 1.4345996 3.5419913
OS 1.4408425 3.5407495
OS 1.4470854 3.5419913
OS 1.4523779 3.5455276
OS 1.4559142 3.5508201
OS 1.457156 3.557063
OS 1.4559142 3.5633059
OS 1.4523779 3.5685984
OS 1.4470854 3.5721347
OS 1.4408425 3.5733765
OE
OB 2.7248425 3.5373765 H
OS 2.7185996 3.5361347
OS 2.7133071 3.5325984
OS 2.7097708 3.5273059
OS 2.708529 3.521063
OS 2.7097708 3.5148201
OS 2.7133071 3.5095276
OS 2.7185996 3.5059913
OS 2.7248425 3.5047495
OS 2.7310854 3.5059913
OS 2.7363779 3.5095276
OS 2.7399142 3.5148201
OS 2.741156 3.521063
OS 2.7399142 3.5273059
OS 2.7363779 3.5325984
OS 2.7310854 3.5361347
OS 2.7248425 3.5373765
OE
OB 2.6748425 3.5173765 H
OS 2.6685996 3.5161347
OS 2.6633071 3.5125984
OS 2.6597708 3.5073059
OS 2.658529 3.501063
OS 2.6597708 3.4948201
OS 2.6633071 3.4895276
OS 2.6685996 3.4859913
OS 2.6748425 3.4847495
OS 2.6810854 3.4859913
OS 2.6863779 3.4895276
OS 2.6899142 3.4948201
OS 2.691156 3.501063
OS 2.6899142 3.5073059
OS 2.6863779 3.5125984
OS 2.6810854 3.5161347
OS 2.6748425 3.5173765
OE
OB 3.6228425 3.5023765 H
OS 3.6165996 3.5011347
OS 3.6113071 3.4975984
OS 3.6077708 3.4923059
OS 3.606529 3.486063
OS 3.6077708 3.4798201
OS 3.6113071 3.4745276
OS 3.6165996 3.4709913
OS 3.6228425 3.4697495
OS 3.6290854 3.4709913
OS 3.6343779 3.4745276
OS 3.6379142 3.4798201
OS 3.639156 3.486063
OS 3.6379142 3.4923059
OS 3.6343779 3.4975984
OS 3.6290854 3.5011347
OS 3.6228425 3.5023765
OE
OB 2.5798425 3.5023765 H
OS 2.5735996 3.5011347
OS 2.5683071 3.4975984
OS 2.5647708 3.4923059
OS 2.563529 3.486063
OS 2.5647708 3.4798201
OS 2.5683071 3.4745276
OS 2.5735996 3.4709913
OS 2.5798425 3.4697495
OS 2.5860854 3.4709913
OS 2.5913779 3.4745276
OS 2.5949142 3.4798201
OS 2.596156 3.486063
OS 2.5949142 3.4923059
OS 2.5913779 3.4975984
OS 2.5860854 3.5011347
OS 2.5798425 3.5023765
OE
OB 3.5298425 3.4973765 H
OS 3.5235996 3.4961347
OS 3.5183071 3.4925984
OS 3.5147708 3.4873059
OS 3.513529 3.481063
OS 3.5147708 3.4748201
OS 3.5183071 3.4695276
OS 3.5235996 3.4659913
OS 3.5298425 3.4647495
OS 3.5360854 3.4659913
OS 3.5413779 3.4695276
OS 3.5449142 3.4748201
OS 3.546156 3.481063
OS 3.5449142 3.4873059
OS 3.5413779 3.4925984
OS 3.5360854 3.4961347
OS 3.5298425 3.4973765
OE
OB 3.4368425 3.4733765 H
OS 3.4305996 3.4721347
OS 3.4253071 3.4685984
OS 3.4217708 3.4633059
OS 3.420529 3.457063
OS 3.4217708 3.4508201
OS 3.4253071 3.4455276
OS 3.4305996 3.4419913
OS 3.4368425 3.4407495
OS 3.4430854 3.4419913
OS 3.4483779 3.4455276
OS 3.4502305 3.4483003
OS 3.4506142 3.4484287
OS 3.4560152 3.4479578
OS 3.4583071 3.4445276
OS 3.4635996 3.4409913
OS 3.4698425 3.4397495
OS 3.4760854 3.4409913
OS 3.4813779 3.4445276
OS 3.4849142 3.4498201
OS 3.486156 3.456063
OS 3.4849142 3.4623059
OS 3.4813779 3.4675984
OS 3.4760854 3.4711347
OS 3.4698425 3.4723765
OS 3.4635996 3.4711347
OS 3.4583071 3.4675984
OS 3.4564545 3.4648257
OS 3.4560708 3.4646973
OS 3.4506698 3.4651682
OS 3.4483779 3.4685984
OS 3.4430854 3.4721347
OS 3.4368425 3.4733765
OE
OB 3.3588425 3.4643765 H
OS 3.3525996 3.4631347
OS 3.3473071 3.4595984
OS 3.3437708 3.4543059
OS 3.342529 3.448063
OS 3.3437708 3.4418201
OS 3.3473071 3.4365276
OS 3.3525996 3.4329913
OS 3.3588425 3.4317495
OS 3.3650854 3.4329913
OS 3.3703779 3.4365276
OS 3.3739142 3.4418201
OS 3.3741941 3.443227
OS 3.379292 3.443227
OS 3.3797708 3.4408201
OS 3.3833071 3.4355276
OS 3.3885996 3.4319913
OS 3.3948425 3.4307495
OS 3.4010854 3.4319913
OS 3.4063779 3.4355276
OS 3.4099142 3.4408201
OS 3.411156 3.447063
OS 3.4099142 3.4533059
OS 3.4063779 3.4585984
OS 3.4010854 3.4621347
OS 3.3948425 3.4633765
OS 3.3885996 3.4621347
OS 3.3833071 3.4585984
OS 3.3797708 3.4533059
OS 3.3794909 3.451899
OS 3.374393 3.451899
OS 3.3739142 3.4543059
OS 3.3703779 3.4595984
OS 3.3650854 3.4631347
OS 3.3588425 3.4643765
OE
OB 2.6348425 3.4223765 H
OS 2.6285996 3.4211347
OS 2.6233071 3.4175984
OS 2.6197708 3.4123059
OS 2.618529 3.406063
OS 2.6197708 3.3998201
OS 2.6233071 3.3945276
OS 2.6285996 3.3909913
OS 2.6348425 3.3897495
OS 2.6410854 3.3909913
OS 2.6463779 3.3945276
OS 2.6499142 3.3998201
OS 2.651156 3.406063
OS 2.6499142 3.4123059
OS 2.6463779 3.4175984
OS 2.6410854 3.4211347
OS 2.6348425 3.4223765
OE
OB 3.0688976 3.4119828 H
OS 3.0626547 3.410741
OS 3.0573622 3.4072047
OS 3.0538259 3.4019122
OS 3.0525841 3.3956693
OS 3.0538259 3.3894264
OS 3.0573622 3.3841339
OS 3.0626547 3.3805976
OS 3.0688976 3.3793558
OS 3.0751405 3.3805976
OS 3.080433 3.3841339
OS 3.0839693 3.3894264
OS 3.0852111 3.3956693
OS 3.0839693 3.4019122
OS 3.080433 3.4072047
OS 3.0751405 3.410741
OS 3.0688976 3.4119828
OE
OB 3.3028425 3.3603765 H
OS 3.2965996 3.3591347
OS 3.2913071 3.3555984
OS 3.2877708 3.3503059
OS 3.286529 3.344063
OS 3.2877708 3.3378201
OS 3.2913071 3.3325276
OS 3.2965996 3.3289913
OS 3.3028425 3.3277495
OS 3.3090854 3.3289913
OS 3.3143779 3.3325276
OS 3.3179142 3.3378201
OS 3.319156 3.344063
OS 3.3179142 3.3503059
OS 3.3143779 3.3555984
OS 3.3090854 3.3591347
OS 3.3028425 3.3603765
OE
OB 3.7448425 3.3583765 H
OS 3.7385996 3.3571347
OS 3.7333071 3.3535984
OS 3.7297708 3.3483059
OS 3.728529 3.342063
OS 3.7297708 3.3358201
OS 3.7333071 3.3305276
OS 3.7385996 3.3269913
OS 3.7448425 3.3257495
OS 3.7510854 3.3269913
OS 3.7563779 3.3305276
OS 3.7599142 3.3358201
OS 3.761156 3.342063
OS 3.7599142 3.3483059
OS 3.7563779 3.3535984
OS 3.7510854 3.3571347
OS 3.7448425 3.3583765
OE
OB 3.542865 3.335354 H
OS 3.5366221 3.3341122
OS 3.5313296 3.3305759
OS 3.5277933 3.3252834
OS 3.5265515 3.3190405
OS 3.5277933 3.3127976
OS 3.5313296 3.3075051
OS 3.5366221 3.3039688
OS 3.542865 3.302727
OS 3.5491079 3.3039688
OS 3.5544004 3.3075051
OS 3.5579367 3.3127976
OS 3.5591785 3.3190405
OS 3.5579367 3.3252834
OS 3.5544004 3.3305759
OS 3.5491079 3.3341122
OS 3.542865 3.335354
OE
OB 3.2636972 3.3202312 H
OS 3.2574543 3.3189894
OS 3.2521618 3.3154531
OS 3.2486255 3.3101606
OS 3.2473837 3.3039177
OS 3.2486255 3.2976748
OS 3.2521618 3.2923823
OS 3.2574543 3.288846
OS 3.2636972 3.2876042
OS 3.2699401 3.288846
OS 3.2752326 3.2923823
OS 3.2787689 3.2976748
OS 3.2800107 3.3039177
OS 3.2787689 3.3101606
OS 3.2752326 3.3154531
OS 3.2699401 3.3189894
OS 3.2636972 3.3202312
OE
OB 3.3308425 3.3173765 H
OS 3.3245996 3.3161347
OS 3.3193071 3.3125984
OS 3.3157708 3.3073059
OS 3.314529 3.301063
OS 3.3157708 3.2948201
OS 3.3193071 3.2895276
OS 3.3245996 3.2859913
OS 3.3308425 3.2847495
OS 3.3370854 3.2859913
OS 3.3423779 3.2895276
OS 3.3459142 3.2948201
OS 3.347156 3.301063
OS 3.3459142 3.3073059
OS 3.3423779 3.3125984
OS 3.3370854 3.3161347
OS 3.3308425 3.3173765
OE
OB 3.4918425 3.3133765 H
OS 3.4855996 3.3121347
OS 3.4803071 3.3085984
OS 3.4767708 3.3033059
OS 3.475529 3.297063
OS 3.4767708 3.2908201
OS 3.4803071 3.2855276
OS 3.4855996 3.2819913
OS 3.4918425 3.2807495
OS 3.4980854 3.2819913
OS 3.5033779 3.2855276
OS 3.5069142 3.2908201
OS 3.508156 3.297063
OS 3.5069142 3.3033059
OS 3.5033779 3.3085984
OS 3.4980854 3.3121347
OS 3.4918425 3.3133765
OE
OB 3.6538425 3.3093765 H
OS 3.6475996 3.3081347
OS 3.6423071 3.3045984
OS 3.6387708 3.2993059
OS 3.637529 3.293063
OS 3.6387708 3.2868201
OS 3.6423071 3.2815276
OS 3.6475996 3.2779913
OS 3.6538425 3.2767495
OS 3.6600854 3.2779913
OS 3.6653779 3.2815276
OS 3.6689142 3.2868201
OS 3.670156 3.293063
OS 3.6689142 3.2993059
OS 3.6653779 3.3045984
OS 3.6600854 3.3081347
OS 3.6538425 3.3093765
OE
OB 3.3748425 3.2893765 H
OS 3.3685996 3.2881347
OS 3.3633071 3.2845984
OS 3.3597708 3.2793059
OS 3.358529 3.273063
OS 3.3597708 3.2668201
OS 3.3633071 3.2615276
OS 3.3685996 3.2579913
OS 3.3748425 3.2567495
OS 3.3810854 3.2579913
OS 3.3863779 3.2615276
OS 3.3899142 3.2668201
OS 3.391156 3.273063
OS 3.3899142 3.2793059
OS 3.3863779 3.2845984
OS 3.3810854 3.2881347
OS 3.3748425 3.2893765
OE
OB 2.5592795 3.3091102 H
OS 2.4604055 3.3091102
OS 2.4604055 3.2490158
OS 2.5592795 3.2490158
OS 2.5592795 3.2668279
OS 2.5838425 3.2668279
OS 2.5885247 3.2677592
OS 2.592494 3.2704115
OS 2.5945743 3.2724918
OS 2.5970854 3.2729913
OS 2.6023779 3.2765276
OS 2.6059142 3.2818201
OS 2.607156 3.288063
OS 2.6059142 3.2943059
OS 2.6023779 3.2995984
OS 2.5970854 3.3031347
OS 2.5908425 3.3043765
OS 2.5845996 3.3031347
OS 2.5793071 3.2995984
OS 2.5757708 3.2943059
OS 2.5751725 3.2912981
OS 2.5592795 3.2912981
OS 2.5592795 3.3091102
OE
OB 3.7448425 3.2773765 H
OS 3.7385996 3.2761347
OS 3.7333071 3.2725984
OS 3.7297708 3.2673059
OS 3.728529 3.261063
OS 3.7297708 3.2548201
OS 3.7333071 3.2495276
OS 3.7385996 3.2459913
OS 3.7448425 3.2447495
OS 3.7510854 3.2459913
OS 3.7563779 3.2495276
OS 3.7599142 3.2548201
OS 3.761156 3.261063
OS 3.7599142 3.2673059
OS 3.7563779 3.2725984
OS 3.7510854 3.2761347
OS 3.7448425 3.2773765
OE
OB 3.2308425 3.2513765 H
OS 3.2245996 3.2501347
OS 3.2193071 3.2465984
OS 3.2157708 3.2413059
OS 3.214529 3.235063
OS 3.2157708 3.2288201
OS 3.2193071 3.2235276
OS 3.2245996 3.2199913
OS 3.2308425 3.2187495
OS 3.2370854 3.2199913
OS 3.2423779 3.2235276
OS 3.2459142 3.2288201
OS 3.247156 3.235063
OS 3.2459142 3.2413059
OS 3.2423779 3.2465984
OS 3.2370854 3.2501347
OS 3.2308425 3.2513765
OE
OB 3.8068425 3.2513765 H
OS 3.8005996 3.2501347
OS 3.7953071 3.2465984
OS 3.7917708 3.2413059
OS 3.790529 3.235063
OS 3.7917708 3.2288201
OS 3.7953071 3.2235276
OS 3.7975621 3.2220209
OS 3.7965063 3.2167129
OS 3.7935996 3.2161347
OS 3.7883071 3.2125984
OS 3.7847708 3.2073059
OS 3.783529 3.201063
OS 3.7847708 3.1948201
OS 3.7883071 3.1895276
OS 3.7935996 3.1859913
OS 3.7998425 3.1847495
OS 3.8060854 3.1859913
OS 3.8113779 3.1895276
OS 3.8149142 3.1948201
OS 3.816156 3.201063
OS 3.8149142 3.2073059
OS 3.8113779 3.2125984
OS 3.8091229 3.2141051
OS 3.8101787 3.2194131
OS 3.8130854 3.2199913
OS 3.8183779 3.2235276
OS 3.8219142 3.2288201
OS 3.823156 3.235063
OS 3.8219142 3.2413059
OS 3.8183779 3.2465984
OS 3.8130854 3.2501347
OS 3.8068425 3.2513765
OE
OB 3.1889764 3.2033214 H
OS 3.1827335 3.2020796
OS 3.177441 3.1985433
OS 3.1739047 3.1932508
OS 3.1726629 3.1870079
OS 3.1739047 3.180765
OS 3.177441 3.1754725
OS 3.1827335 3.1719362
OS 3.1889764 3.1706944
OS 3.1952193 3.1719362
OS 3.2005118 3.1754725
OS 3.2040481 3.180765
OS 3.2052899 3.1870079
OS 3.2040481 3.1932508
OS 3.2005118 3.1985433
OS 3.1952193 3.2020796
OS 3.1889764 3.2033214
OE
OB 1.4598425 3.1633765 H
OS 1.4535996 3.1621347
OS 1.4483071 3.1585984
OS 1.4447708 3.1533059
OS 1.443529 3.147063
OS 1.4447708 3.1408201
OS 1.4483071 3.1355276
OS 1.4535996 3.1319913
OS 1.4598425 3.1307495
OS 1.4660854 3.1319913
OS 1.4713779 3.1355276
OS 1.4749142 3.1408201
OS 1.476156 3.147063
OS 1.4749142 3.1533059
OS 1.4713779 3.1585984
OS 1.4660854 3.1621347
OS 1.4598425 3.1633765
OE
OB 3.2755905 3.1580458 H
OS 3.2693476 3.156804
OS 3.2640551 3.1532677
OS 3.2605188 3.1479752
OS 3.259277 3.1417323
OS 3.2605188 3.1354894
OS 3.2640551 3.1301969
OS 3.2693476 3.1266606
OS 3.2755905 3.1254188
OS 3.2818334 3.1266606
OS 3.2871259 3.1301969
OS 3.2906622 3.1354894
OS 3.291904 3.1417323
OS 3.2906622 3.1479752
OS 3.2871259 3.1532677
OS 3.2818334 3.156804
OS 3.2755905 3.1580458
OE
OB 3.1830708 3.1521403 H
OS 3.1768279 3.1508985
OS 3.1715354 3.1473622
OS 3.1679991 3.1420697
OS 3.1667573 3.1358268
OS 3.1679991 3.1295839
OS 3.1715354 3.1242914
OS 3.1768279 3.1207551
OS 3.1830708 3.1195133
OS 3.1893137 3.1207551
OS 3.1946062 3.1242914
OS 3.1981425 3.1295839
OS 3.1993843 3.1358268
OS 3.1981425 3.1420697
OS 3.1946062 3.1473622
OS 3.1893137 3.1508985
OS 3.1830708 3.1521403
OE
OB 2.5592795 3.2303701 H
OS 2.4604055 3.2303701
OS 2.4604055 3.188166
OS 2.4561311 3.1873158
OS 2.4508386 3.1837795
OS 2.4473023 3.178487
OS 2.4460605 3.1722441
OS 2.4473023 3.1660012
OS 2.4508386 3.1607087
OS 2.4561311 3.1571724
OS 2.4599035 3.156422
OS 2.4604054 3.1516299
OS 2.4604055 3.1512242
OS 2.4604055 3.0915355
OS 2.5592795 3.0915355
OS 2.5592795 3.134327
OS 2.5956086 3.1706561
OS 2.5980854 3.1711488
OS 2.6033779 3.1746851
OS 2.6069142 3.1799776
OS 2.608156 3.1862205
OS 2.6069142 3.1924634
OS 2.6033779 3.1977559
OS 2.5980854 3.2012922
OS 2.5918425 3.202534
OS 2.5855996 3.2012922
OS 2.5803071 3.1977559
OS 2.5767708 3.1924634
OS 2.575529 3.1862205
OS 2.5757012 3.1853547
OS 2.5642795 3.173933
OS 2.5592795 3.1760041
OS 2.5592795 3.2303701
OE
OB 3.4918425 3.1193765 H
OS 3.4855996 3.1181347
OS 3.4803071 3.1145984
OS 3.4767708 3.1093059
OS 3.475529 3.103063
OS 3.4767708 3.0968201
OS 3.4803071 3.0915276
OS 3.4855996 3.0879913
OS 3.4918425 3.0867495
OS 3.4980854 3.0879913
OS 3.5033779 3.0915276
OS 3.5069142 3.0968201
OS 3.508156 3.103063
OS 3.5069142 3.1093059
OS 3.5033779 3.1145984
OS 3.4980854 3.1181347
OS 3.4918425 3.1193765
OE
OB 3.7178425 3.0883765 H
OS 3.7115996 3.0871347
OS 3.7063071 3.0835984
OS 3.7027708 3.0783059
OS 3.701529 3.072063
OS 3.7027708 3.0658201
OS 3.7063071 3.0605276
OS 3.7115996 3.0569913
OS 3.7178425 3.0557495
OS 3.7240854 3.0569913
OS 3.7293779 3.0605276
OS 3.7329142 3.0658201
OS 3.734156 3.072063
OS 3.7329142 3.0783059
OS 3.7293779 3.0835984
OS 3.7240854 3.0871347
OS 3.7178425 3.0883765
OE
OB 3.3688425 3.0663765 H
OS 3.3625996 3.0651347
OS 3.3573071 3.0615984
OS 3.3537708 3.0563059
OS 3.352529 3.050063
OS 3.3537708 3.0438201
OS 3.3573071 3.0385276
OS 3.3625996 3.0349913
OS 3.3688425 3.0337495
OS 3.3750854 3.0349913
OS 3.3803779 3.0385276
OS 3.3839142 3.0438201
OS 3.385156 3.050063
OS 3.3839142 3.0563059
OS 3.3803779 3.0615984
OS 3.3750854 3.0651347
OS 3.3688425 3.0663765
OE
OB 3.3448425 3.0123765 H
OS 3.3385996 3.0111347
OS 3.3333071 3.0075984
OS 3.3297708 3.0023059
OS 3.328529 2.996063
OS 3.3297708 2.9898201
OS 3.3333071 2.9845276
OS 3.3385996 2.9809913
OS 3.3448425 2.9797495
OS 3.3510854 2.9809913
OS 3.3563779 2.9845276
OS 3.3599142 2.9898201
OS 3.361156 2.996063
OS 3.3599142 3.0023059
OS 3.3563779 3.0075984
OS 3.3510854 3.0111347
OS 3.3448425 3.0123765
OE
OB 2.4738425 2.9963765 H
OS 2.4675996 2.9951347
OS 2.4648802 2.9933177
OS 2.4342756 2.9933177
OS 2.4292032 2.9923087
OS 2.4249031 2.9894355
OS 2.4163286 2.980861
OS 2.4159134 2.980861
OS 2.414633 2.9806063
OS 2.3676378 2.9806063
OS 2.3676378 2.9075197
OS 2.4289134 2.9075197
OS 2.4289134 2.9567117
OS 2.4311914 2.9582338
OS 2.4397659 2.9668083
OS 2.4648802 2.9668083
OS 2.4675996 2.9649913
OS 2.4738425 2.9637495
OS 2.4800854 2.9649913
OS 2.4853779 2.9685276
OS 2.4889142 2.9738201
OS 2.490156 2.980063
OS 2.4889142 2.9863059
OS 2.4853779 2.9915984
OS 2.4800854 2.9951347
OS 2.4738425 2.9963765
OE
OB 3.1978425 2.9863765 H
OS 3.1915996 2.9851347
OS 3.1863071 2.9815984
OS 3.1827708 2.9763059
OS 3.181529 2.970063
OS 3.1827708 2.9638201
OS 3.1863071 2.9585276
OS 3.1915996 2.9549913
OS 3.1978425 2.9537495
OS 3.2040854 2.9549913
OS 3.2093779 2.9585276
OS 3.2129142 2.9638201
OS 3.214156 2.970063
OS 3.2129142 2.9763059
OS 3.2093779 2.9815984
OS 3.2040854 2.9851347
OS 3.1978425 2.9863765
OE
OB 3.277559 2.9798962 H
OS 3.2713161 2.9786544
OS 3.2660236 2.9751181
OS 3.2624873 2.9698256
OS 3.2612455 2.9635827
OS 3.2624873 2.9573398
OS 3.2660236 2.9520473
OS 3.2713161 2.948511
OS 3.277559 2.9472692
OS 3.2838019 2.948511
OS 3.2890944 2.9520473
OS 3.2926307 2.9573398
OS 3.2938725 2.9635827
OS 3.2926307 2.9698256
OS 3.2890944 2.9751181
OS 3.2838019 2.9786544
OS 3.277559 2.9798962
OE
OB 3.3708425 2.9043765 H
OS 3.3645996 2.9031347
OS 3.3593071 2.8995984
OS 3.3557708 2.8943059
OS 3.354529 2.888063
OS 3.3557708 2.8818201
OS 3.3593071 2.8765276
OS 3.3645996 2.8729913
OS 3.3708425 2.8717495
OS 3.3770854 2.8729913
OS 3.3823779 2.8765276
OS 3.3859142 2.8818201
OS 3.387156 2.888063
OS 3.3859142 2.8943059
OS 3.3823779 2.8995984
OS 3.3770854 2.9031347
OS 3.3708425 2.9043765
OE
OB 2.6929134 2.7377702 H
OS 2.6866705 2.7365284
OS 2.681378 2.7329921
OS 2.6778417 2.7276996
OS 2.6765999 2.7214567
OS 2.6778417 2.7152138
OS 2.681378 2.7099213
OS 2.6866705 2.706385
OS 2.6929134 2.7051432
OS 2.6991563 2.706385
OS 2.7044488 2.7099213
OS 2.7079851 2.7152138
OS 2.7092269 2.7214567
OS 2.7079851 2.7276996
OS 2.7044488 2.7329921
OS 2.6991563 2.7365284
OS 2.6929134 2.7377702
OE
OB 2.394685 2.7367859 H
OS 2.3884421 2.7355441
OS 2.3831496 2.7320078
OS 2.3796133 2.7267153
OS 2.3783715 2.7204724
OS 2.3796133 2.7142295
OS 2.3831496 2.708937
OS 2.3884421 2.7054007
OS 2.394685 2.7041589
OS 2.4009279 2.7054007
OS 2.4062204 2.708937
OS 2.4097567 2.7142295
OS 2.4109985 2.7204724
OS 2.4097567 2.7267153
OS 2.4062204 2.7320078
OS 2.4009279 2.7355441
OS 2.394685 2.7367859
OE
OB 2.4948425 2.7123765 H
OS 2.4885996 2.7111347
OS 2.4833071 2.7075984
OS 2.4797708 2.7023059
OS 2.478529 2.696063
OS 2.4797708 2.6898201
OS 2.4833071 2.6845276
OS 2.4883212 2.6811773
OS 2.4885995 2.6790399
OS 2.4885995 2.6780861
OS 2.4883212 2.6759487
OS 2.4833071 2.6725984
OS 2.4797708 2.6673059
OS 2.478529 2.661063
OS 2.4797708 2.6548201
OS 2.4833071 2.6495276
OS 2.4885996 2.6459913
OS 2.4948425 2.6447495
OS 2.5010854 2.6459913
OS 2.5063779 2.6495276
OS 2.5099142 2.6548201
OS 2.511156 2.661063
OS 2.5099142 2.6673059
OS 2.5063779 2.6725984
OS 2.5013638 2.6759487
OS 2.5010855 2.6780861
OS 2.5010855 2.6790399
OS 2.5013638 2.6811773
OS 2.5063779 2.6845276
OS 2.5099142 2.6898201
OS 2.511156 2.696063
OS 2.5099142 2.7023059
OS 2.5063779 2.7075984
OS 2.5010854 2.7111347
OS 2.4948425 2.7123765
OE
OB 2.9588425 2.6373765 H
OS 2.9525996 2.6361347
OS 2.9473071 2.6325984
OS 2.9437708 2.6273059
OS 2.942529 2.621063
OS 2.9437708 2.6148201
OS 2.9473071 2.6095276
OS 2.9525996 2.6059913
OS 2.9588425 2.6047495
OS 2.9650854 2.6059913
OS 2.9703779 2.6095276
OS 2.9739142 2.6148201
OS 2.975156 2.621063
OS 2.9739142 2.6273059
OS 2.9703779 2.6325984
OS 2.9650854 2.6361347
OS 2.9588425 2.6373765
OE
OB 2.4291925 2.6373765 H
OS 2.4229496 2.6361347
OS 2.4176571 2.6325984
OS 2.4141208 2.6273059
OS 2.412879 2.621063
OS 2.4141208 2.6148201
OS 2.4176571 2.6095276
OS 2.4229496 2.6059913
OS 2.4291925 2.6047495
OS 2.4354354 2.6059913
OS 2.4407279 2.6095276
OS 2.4442642 2.6148201
OS 2.445506 2.621063
OS 2.4442642 2.6273059
OS 2.4407279 2.6325984
OS 2.4354354 2.6361347
OS 2.4291925 2.6373765
OE
OB 2.2523425 2.6298765 H
OS 2.2460996 2.6286347
OS 2.2408071 2.6250984
OS 2.2372708 2.6198059
OS 2.236029 2.613563
OS 2.2372708 2.6073201
OS 2.239748 2.6036127
OS 2.2364566 2.5995388
OS 2.2317425 2.6004765
OS 2.2254996 2.5992347
OS 2.2202071 2.5956984
OS 2.2166708 2.5904059
OS 2.215429 2.584163
OS 2.2166708 2.5779201
OS 2.2202071 2.5726276
OS 2.2254996 2.5690913
OS 2.2317425 2.5678495
OS 2.2379854 2.5690913
OS 2.2432779 2.5726276
OS 2.2468142 2.5779201
OS 2.248056 2.584163
OS 2.2468142 2.5904059
OS 2.244337 2.5941133
OS 2.2476284 2.5981872
OS 2.2523425 2.5972495
OS 2.2585854 2.5984913
OS 2.2638779 2.6020276
OS 2.2674142 2.6073201
OS 2.268656 2.613563
OS 2.2674142 2.6198059
OS 2.2638779 2.6250984
OS 2.2585854 2.6286347
OS 2.2523425 2.6298765
OE
OB 2.8218425 2.6173765 H
OS 2.8155996 2.6161347
OS 2.8103071 2.6125984
OS 2.8067708 2.6073059
OS 2.805529 2.601063
OS 2.8067708 2.5948201
OS 2.8103071 2.5895276
OS 2.8155996 2.5859913
OS 2.8218425 2.5847495
OS 2.8280854 2.5859913
OS 2.8333779 2.5895276
OS 2.8369142 2.5948201
OS 2.838156 2.601063
OS 2.8369142 2.6073059
OS 2.8333779 2.6125984
OS 2.8280854 2.6161347
OS 2.8218425 2.6173765
OE
OB 3.6238425 2.6033765 H
OS 3.6175996 2.6021347
OS 3.6123071 2.5985984
OS 3.6087708 2.5933059
OS 3.607529 2.587063
OS 3.6087708 2.5808201
OS 3.6123071 2.5755276
OS 3.6175996 2.5719913
OS 3.6238425 2.5707495
OS 3.6300854 2.5719913
OS 3.6353779 2.5755276
OS 3.6389142 2.5808201
OS 3.640156 2.587063
OS 3.6389142 2.5933059
OS 3.6353779 2.5985984
OS 3.6300854 2.6021347
OS 3.6238425 2.6033765
OE
OB 2.3215354 2.6023765 H
OS 2.3152925 2.6011347
OS 2.31 2.5975984
OS 2.3064637 2.5923059
OS 2.3052219 2.586063
OS 2.3064637 2.5798201
OS 2.31 2.5745276
OS 2.3152925 2.5709913
OS 2.3215354 2.5697495
OS 2.3277783 2.5709913
OS 2.3330708 2.5745276
OS 2.3366071 2.5798201
OS 2.3378489 2.586063
OS 2.3366071 2.5923059
OS 2.3330708 2.5975984
OS 2.3277783 2.6011347
OS 2.3215354 2.6023765
OE
OB 2.4098425 2.5953765 H
OS 2.4035996 2.5941347
OS 2.3983071 2.5905984
OS 2.3947708 2.5853059
OS 2.393529 2.579063
OS 2.3947708 2.5728201
OS 2.3983071 2.5675276
OS 2.4035996 2.5639913
OS 2.4098425 2.5627495
OS 2.4160854 2.5639913
OS 2.4213779 2.5675276
OS 2.4249142 2.5728201
OS 2.426156 2.579063
OS 2.4249142 2.5853059
OS 2.4213779 2.5905984
OS 2.4160854 2.5941347
OS 2.4098425 2.5953765
OE
OB 2.5868425 2.5853765 H
OS 2.5805996 2.5841347
OS 2.5753071 2.5805984
OS 2.5717708 2.5753059
OS 2.570529 2.569063
OS 2.5717708 2.5628201
OS 2.5753071 2.5575276
OS 2.5805996 2.5539913
OS 2.5868425 2.5527495
OS 2.5930854 2.5539913
OS 2.5983779 2.5575276
OS 2.6019142 2.5628201
OS 2.603156 2.569063
OS 2.6019142 2.5753059
OS 2.5983779 2.5805984
OS 2.5930854 2.5841347
OS 2.5868425 2.5853765
OE
OB 2.7838425 2.5843765 H
OS 2.7775996 2.5831347
OS 2.7723071 2.5795984
OS 2.7687708 2.5743059
OS 2.767529 2.568063
OS 2.7687708 2.5618201
OS 2.7723071 2.5565276
OS 2.7775996 2.5529913
OS 2.7838425 2.5517495
OS 2.7900854 2.5529913
OS 2.7953779 2.5565276
OS 2.7989142 2.5618201
OS 2.800156 2.568063
OS 2.7989142 2.5743059
OS 2.7953779 2.5795984
OS 2.7900854 2.5831347
OS 2.7838425 2.5843765
OE
OB 2.6858425 2.5843765 H
OS 2.6795996 2.5831347
OS 2.6743071 2.5795984
OS 2.6707708 2.5743059
OS 2.669529 2.568063
OS 2.6707708 2.5618201
OS 2.6743071 2.5565276
OS 2.6795996 2.5529913
OS 2.6858425 2.5517495
OS 2.6920854 2.5529913
OS 2.6973779 2.5565276
OS 2.7009142 2.5618201
OS 2.702156 2.568063
OS 2.7009142 2.5743059
OS 2.6973779 2.5795984
OS 2.6920854 2.5831347
OS 2.6858425 2.5843765
OE
OB 2.8818425 2.5823765 H
OS 2.8755996 2.5811347
OS 2.8703071 2.5775984
OS 2.8667708 2.5723059
OS 2.865529 2.566063
OS 2.8667708 2.5598201
OS 2.8703071 2.5545276
OS 2.8755996 2.5509913
OS 2.8818425 2.5497495
OS 2.8880854 2.5509913
OS 2.8933779 2.5545276
OS 2.8969142 2.5598201
OS 2.898156 2.566063
OS 2.8969142 2.5723059
OS 2.8933779 2.5775984
OS 2.8880854 2.5811347
OS 2.8818425 2.5823765
OE
OB 2.6248425 2.4773765 H
OS 2.6185996 2.4761347
OS 2.6133071 2.4725984
OS 2.6097708 2.4673059
OS 2.608529 2.461063
OS 2.6097708 2.4548201
OS 2.6099331 2.4545773
OS 2.6063282 2.4509724
OS 2.6060854 2.4511347
OS 2.5998425 2.4523765
OS 2.5935996 2.4511347
OS 2.5883071 2.4475984
OS 2.5847708 2.4423059
OS 2.583529 2.436063
OS 2.5844621 2.4313719
OS 2.583986 2.4305231
OS 2.5813824 2.4279195
OS 2.5805336 2.4274434
OS 2.5758425 2.4283765
OS 2.5695996 2.4271347
OS 2.5643071 2.4235984
OS 2.5607708 2.4183059
OS 2.559529 2.412063
OS 2.5607708 2.4058201
OS 2.5643071 2.4005276
OS 2.5695996 2.3969913
OS 2.5758425 2.3957495
OS 2.5820854 2.3969913
OS 2.5873779 2.4005276
OS 2.5909142 2.4058201
OS 2.592156 2.412063
OS 2.5912229 2.4167541
OS 2.591699 2.4176029
OS 2.5943026 2.4202065
OS 2.5951514 2.4206826
OS 2.5998425 2.4197495
OS 2.6060854 2.4209913
OS 2.6113779 2.4245276
OS 2.6149142 2.4298201
OS 2.616156 2.436063
OS 2.6149142 2.4423059
OS 2.6147519 2.4425487
OS 2.6183568 2.4461536
OS 2.6185996 2.4459913
OS 2.6248425 2.4447495
OS 2.6310854 2.4459913
OS 2.6363779 2.4495276
OS 2.6399142 2.4548201
OS 2.641156 2.461063
OS 2.6399142 2.4673059
OS 2.6363779 2.4725984
OS 2.6310854 2.4761347
OS 2.6248425 2.4773765
OE
OB 2.2720325 2.4801865 H
OS 2.2657896 2.4789447
OS 2.2604971 2.4754084
OS 2.2569608 2.4701159
OS 2.255719 2.463873
OS 2.2569608 2.4576301
OS 2.2604971 2.4523376
OS 2.2657896 2.4488013
OS 2.2720325 2.4475595
OS 2.2782754 2.4488013
OS 2.2835679 2.4523376
OS 2.2871042 2.4576301
OS 2.288346 2.463873
OS 2.2871042 2.4701159
OS 2.2835679 2.4754084
OS 2.2782754 2.4789447
OS 2.2720325 2.4801865
OE
OB 2.5258425 2.4793765 H
OS 2.5195996 2.4781347
OS 2.5143071 2.4745984
OS 2.5107708 2.4693059
OS 2.509529 2.463063
OS 2.5107708 2.4568201
OS 2.5143071 2.4515276
OS 2.5195996 2.4479913
OS 2.5258425 2.4467495
OS 2.5320854 2.4479913
OS 2.5373779 2.4515276
OS 2.5409142 2.4568201
OS 2.542156 2.463063
OS 2.5409142 2.4693059
OS 2.5373779 2.4745984
OS 2.5320854 2.4781347
OS 2.5258425 2.4793765
OE
OB 2.9488425 2.4723765 H
OS 2.9425996 2.4711347
OS 2.9373071 2.4675984
OS 2.9337708 2.4623059
OS 2.932529 2.456063
OS 2.9337708 2.4498201
OS 2.9373071 2.4445276
OS 2.9425996 2.4409913
OS 2.9488425 2.4397495
OS 2.9550854 2.4409913
OS 2.9603779 2.4445276
OS 2.9639142 2.4498201
OS 2.965156 2.456063
OS 2.9639142 2.4623059
OS 2.9603779 2.4675984
OS 2.9550854 2.4711347
OS 2.9488425 2.4723765
OE
OB 2.4758425 2.4723765 H
OS 2.4695996 2.4711347
OS 2.4643071 2.4675984
OS 2.4607708 2.4623059
OS 2.459529 2.456063
OS 2.4607708 2.4498201
OS 2.4643071 2.4445276
OS 2.4695996 2.4409913
OS 2.4758425 2.4397495
OS 2.4820854 2.4409913
OS 2.4873779 2.4445276
OS 2.4909142 2.4498201
OS 2.492156 2.456063
OS 2.4909142 2.4623059
OS 2.4873779 2.4675984
OS 2.4820854 2.4711347
OS 2.4758425 2.4723765
OE
OB 2.9905325 2.4577319 H
OS 2.9831854 2.4562705
OS 2.9769568 2.4521087
OS 2.972795 2.4458801
OS 2.9713336 2.438533
OS 2.972795 2.4311859
OS 2.9769568 2.4249573
OS 2.9831854 2.4207955
OS 2.9905325 2.4193341
OS 2.9978796 2.4207955
OS 3.0041082 2.4249573
OS 3.00827 2.4311859
OS 3.0097314 2.438533
OS 3.00827 2.4458801
OS 3.0041082 2.4521087
OS 2.9978796 2.4562705
OS 2.9905325 2.4577319
OE
OB 2.2031325 2.4577319 H
OS 2.1957854 2.4562705
OS 2.1895568 2.4521087
OS 2.185395 2.4458801
OS 2.1839336 2.438533
OS 2.185395 2.4311859
OS 2.1895568 2.4249573
OS 2.1957854 2.4207955
OS 2.2031325 2.4193341
OS 2.2104796 2.4207955
OS 2.2167082 2.4249573
OS 2.22087 2.4311859
OS 2.2223314 2.438533
OS 2.22087 2.4458801
OS 2.2167082 2.4521087
OS 2.2104796 2.4562705
OS 2.2031325 2.4577319
OE
OB 3.6179425 2.5536725 H
OS 3.6047974 2.5523778
OS 3.5921575 2.5485435
OS 3.5805085 2.542317
OS 3.570298 2.5339375
OS 3.5619185 2.523727
OS 3.555692 2.512078
OS 3.5518577 2.4994381
OS 3.550563 2.486293
OS 3.5518577 2.4731479
OS 3.555692 2.460508
OS 3.5619185 2.448859
OS 3.570298 2.4386485
OS 3.5805085 2.430269
OS 3.5921575 2.4240425
OS 3.6047974 2.4202082
OS 3.6179425 2.4189135
OS 3.6310876 2.4202082
OS 3.6437275 2.4240425
OS 3.6553765 2.430269
OS 3.665587 2.4386485
OS 3.6739665 2.448859
OS 3.680193 2.460508
OS 3.6840273 2.4731479
OS 3.685322 2.486293
OS 3.6840273 2.4994381
OS 3.680193 2.512078
OS 3.6739665 2.523727
OS 3.665587 2.5339375
OS 3.6553765 2.542317
OS 3.6437275 2.5485435
OS 3.6310876 2.5523778
OS 3.6179425 2.5536725
OE
OB 2.7838425 2.4453765 H
OS 2.7775996 2.4441347
OS 2.7723071 2.4405984
OS 2.7687708 2.4353059
OS 2.767529 2.429063
OS 2.7687708 2.4228201
OS 2.7723071 2.4175276
OS 2.7775996 2.4139913
OS 2.7838425 2.4127495
OS 2.7900854 2.4139913
OS 2.7953779 2.4175276
OS 2.7989142 2.4228201
OS 2.800156 2.429063
OS 2.7989142 2.4353059
OS 2.7953779 2.4405984
OS 2.7900854 2.4441347
OS 2.7838425 2.4453765
OE
OB 2.8948425 2.4473765 H
OS 2.8885996 2.4461347
OS 2.8833071 2.4425984
OS 2.8797708 2.4373059
OS 2.878529 2.431063
OS 2.8797708 2.4248201
OS 2.8833071 2.4195276
OS 2.8885996 2.4159913
OS 2.8948425 2.4147495
OS 2.9010854 2.4159913
OS 2.9028598 2.4171769
OS 2.9093072 2.4165275
OS 2.9145996 2.4129913
OS 2.9208425 2.4117495
OS 2.9270854 2.4129913
OS 2.9323779 2.4165276
OS 2.9359142 2.4218201
OS 2.937156 2.428063
OS 2.9359142 2.4343059
OS 2.9323779 2.4395984
OS 2.9270854 2.4431347
OS 2.9208425 2.4443765
OS 2.9145996 2.4431347
OS 2.9093072 2.4395984
OS 2.9083824 2.4395984
OS 2.9063779 2.4425984
OS 2.9010854 2.4461347
OS 2.8948425 2.4473765
OE
OB 2.4888425 2.4293765 H
OS 2.4825996 2.4281347
OS 2.4773071 2.4245984
OS 2.4737708 2.4193059
OS 2.472529 2.413063
OS 2.4737708 2.4068201
OS 2.4773071 2.4015276
OS 2.4825996 2.3979913
OS 2.4888425 2.3967495
OS 2.4950854 2.3979913
OS 2.5003779 2.4015276
OS 2.5039142 2.4068201
OS 2.505156 2.413063
OS 2.5039142 2.4193059
OS 2.5003779 2.4245984
OS 2.4950854 2.4281347
OS 2.4888425 2.4293765
OE
OB 2.4048425 2.4283765 H
OS 2.3985996 2.4271347
OS 2.3933071 2.4235984
OS 2.3897708 2.4183059
OS 2.388529 2.412063
OS 2.3897708 2.4058201
OS 2.3933071 2.4005276
OS 2.3985996 2.3969913
OS 2.4048425 2.3957495
OS 2.4110854 2.3969913
OS 2.4163779 2.4005276
OS 2.4199142 2.4058201
OS 2.421156 2.412063
OS 2.4199142 2.4183059
OS 2.4163779 2.4235984
OS 2.4110854 2.4271347
OS 2.4048425 2.4283765
OE
OB 3.4988425 2.3573765 H
OS 3.4925996 2.3561347
OS 3.4873071 2.3525984
OS 3.4837708 2.3473059
OS 3.482529 2.341063
OS 3.4837708 2.3348201
OS 3.4873071 2.3295276
OS 3.4925996 2.3259913
OS 3.4988425 2.3247495
OS 3.5050854 2.3259913
OS 3.5103779 2.3295276
OS 3.5139142 2.3348201
OS 3.515156 2.341063
OS 3.5139142 2.3473059
OS 3.5103779 2.3525984
OS 3.5050854 2.3561347
OS 3.4988425 2.3573765
OE
OB 2.4758425 2.3073765 H
OS 2.4695996 2.3061347
OS 2.4643071 2.3025984
OS 2.4607708 2.297306
OS 2.4556938 2.2974115
OS 2.4508425 2.2983765
OS 2.4445996 2.2971347
OS 2.4393071 2.2935984
OS 2.4357708 2.2883059
OS 2.434529 2.282063
OS 2.4357708 2.2758201
OS 2.4393071 2.2705276
OS 2.4445996 2.2669913
OS 2.4508425 2.2657495
OS 2.4570854 2.2669913
OS 2.4623779 2.2705276
OS 2.4659142 2.27582
OS 2.4709912 2.2757145
OS 2.4758425 2.2747495
OS 2.4820854 2.2759913
OS 2.4873779 2.2795276
OS 2.4909142 2.2848201
OS 2.492156 2.291063
OS 2.4909142 2.2973059
OS 2.4873779 2.3025984
OS 2.4820854 2.3061347
OS 2.4758425 2.3073765
OE
OB 2.8038425 2.3233765 H
OS 2.7975996 2.3221347
OS 2.7923071 2.3185984
OS 2.7887708 2.3133059
OS 2.787529 2.307063
OS 2.7887708 2.3008201
OS 2.7923071 2.2955276
OS 2.7975996 2.2919913
OS 2.8038425 2.2907495
OS 2.8100854 2.2919913
OS 2.8153779 2.2955276
OS 2.8189142 2.3008201
OS 2.820156 2.307063
OS 2.8189142 2.3133059
OS 2.8153779 2.3185984
OS 2.8100854 2.3221347
OS 2.8038425 2.3233765
OE
OB 2.6858425 2.3273765 H
OS 2.6795996 2.3261347
OS 2.6743071 2.3225984
OS 2.6707708 2.3173059
OS 2.6696588 2.3117154
OS 2.6687231 2.3100312
OS 2.6668743 2.3081824
OS 2.6651901 2.3072467
OS 2.6595996 2.3061347
OS 2.6543071 2.3025984
OS 2.6507708 2.2973059
OS 2.649529 2.2910631
OS 2.6483447 2.2898788
OS 2.6458425 2.2903765
OS 2.6395996 2.2891347
OS 2.6343071 2.2855984
OS 2.6307708 2.2803059
OS 2.629529 2.274063
OS 2.6307708 2.2678201
OS 2.6343071 2.2625276
OS 2.6395996 2.2589913
OS 2.6458425 2.2577495
OS 2.6520854 2.2589913
OS 2.6573779 2.2625276
OS 2.6609142 2.2678201
OS 2.662156 2.2740629
OS 2.6633403 2.2752472
OS 2.6658425 2.2747495
OS 2.6720854 2.2759913
OS 2.6773779 2.2795276
OS 2.6809142 2.2848201
OS 2.6817886 2.2892161
OS 2.686529 2.2890629
OS 2.6877708 2.2828201
OS 2.6913071 2.2775276
OS 2.6965996 2.2739913
OS 2.7028425 2.2727495
OS 2.7090854 2.2739913
OS 2.7143779 2.2775276
OS 2.7165125 2.2807222
OS 2.7205996 2.2779913
OS 2.7268425 2.2767495
OS 2.7330854 2.2779913
OS 2.7383779 2.2815276
OS 2.7419142 2.2868201
OS 2.743156 2.293063
OS 2.7419142 2.2993059
OS 2.7383779 2.3045984
OS 2.7330854 2.3081347
OS 2.7268425 2.3093765
OS 2.7205996 2.3081347
OS 2.7153071 2.3045984
OS 2.7131725 2.3014038
OS 2.7090854 2.3041347
OS 2.705998 2.3047488
OS 2.7019255 2.309904
OS 2.702156 2.311063
OS 2.7009142 2.3173059
OS 2.6973779 2.3225984
OS 2.6920854 2.3261347
OS 2.6858425 2.3273765
OE
OB 2.8718425 2.3133765 H
OS 2.8655996 2.3121347
OS 2.8603071 2.3085984
OS 2.8567708 2.3033059
OS 2.855529 2.297063
OS 2.8567708 2.2908201
OS 2.8603071 2.2855276
OS 2.8655996 2.2819913
OS 2.8718425 2.2807495
OS 2.8780854 2.2819913
OS 2.8833779 2.2855276
OS 2.8869142 2.2908201
OS 2.888156 2.297063
OS 2.8869142 2.3033059
OS 2.8833779 2.3085984
OS 2.8780854 2.3121347
OS 2.8718425 2.3133765
OE
OB 2.9858425 2.3033765 H
OS 2.9795996 2.3021347
OS 2.9743071 2.2985984
OS 2.9707708 2.2933059
OS 2.969529 2.287063
OS 2.9707708 2.2808201
OS 2.9743071 2.2755276
OS 2.9795996 2.2719913
OS 2.9858425 2.2707495
OS 2.9920854 2.2719913
OS 2.9973779 2.2755276
OS 3.0009142 2.2808201
OS 3.002156 2.287063
OS 3.0009142 2.2933059
OS 2.9973779 2.2985984
OS 2.9920854 2.3021347
OS 2.9858425 2.3033765
OE
OB 2.9428425 2.3023765 H
OS 2.9365996 2.3011347
OS 2.9313071 2.2975984
OS 2.9277708 2.2923059
OS 2.926529 2.286063
OS 2.9277708 2.2798201
OS 2.9313071 2.2745276
OS 2.9365996 2.2709913
OS 2.9428425 2.2697495
OS 2.9490854 2.2709913
OS 2.9543779 2.2745276
OS 2.9579142 2.2798201
OS 2.959156 2.286063
OS 2.9579142 2.2923059
OS 2.9543779 2.2975984
OS 2.9490854 2.3011347
OS 2.9428425 2.3023765
OE
OB 2.4098425 2.3303765 H
OS 2.4035996 2.3291347
OS 2.3983071 2.3255984
OS 2.3947708 2.3203059
OS 2.393529 2.314063
OS 2.3947708 2.3078201
OS 2.3983071 2.3025276
OS 2.3997406 2.3015697
OS 2.3997406 2.2955563
OS 2.3983071 2.2945984
OS 2.3947708 2.2893059
OS 2.393529 2.283063
OS 2.3947708 2.2768201
OS 2.3983071 2.2715276
OS 2.4035996 2.2679913
OS 2.4098425 2.2667495
OS 2.4160854 2.2679913
OS 2.4213779 2.2715276
OS 2.4249142 2.2768201
OS 2.426156 2.283063
OS 2.4249142 2.2893059
OS 2.4213779 2.2945984
OS 2.4199444 2.2955563
OS 2.4199444 2.3015697
OS 2.4213779 2.3025276
OS 2.4249142 2.3078201
OS 2.426156 2.314063
OS 2.4249142 2.3203059
OS 2.4213779 2.3255984
OS 2.4160854 2.3291347
OS 2.4098425 2.3303765
OE
OB 2.5818425 2.3243765 H
OS 2.5755996 2.3231347
OS 2.5703071 2.3195984
OS 2.5667708 2.3143059
OS 2.565529 2.308063
OS 2.5667708 2.3018201
OS 2.568727 2.2988924
OS 2.5683071 2.2925983
OS 2.5647708 2.2873059
OS 2.563529 2.281063
OS 2.5647708 2.2748201
OS 2.5683071 2.2695276
OS 2.5735996 2.2659913
OS 2.5798425 2.2647495
OS 2.5860854 2.2659913
OS 2.5913779 2.2695276
OS 2.5949142 2.2748201
OS 2.596156 2.281063
OS 2.5949142 2.2873059
OS 2.592958 2.2902336
OS 2.5933779 2.2965277
OS 2.5969142 2.3018201
OS 2.598156 2.308063
OS 2.5969142 2.3143059
OS 2.5933779 2.3195984
OS 2.5880854 2.3231347
OS 2.5818425 2.3243765
OE
OB 2.2538425 2.2953765 H
OS 2.2475996 2.2941347
OS 2.2423071 2.2905984
OS 2.2387708 2.2853059
OS 2.237529 2.279063
OS 2.2387708 2.2728201
OS 2.2423071 2.2675276
OS 2.2475996 2.2639913
OS 2.2538425 2.2627495
OS 2.2600854 2.2639913
OS 2.2653779 2.2675276
OS 2.2689142 2.2728201
OS 2.270156 2.279063
OS 2.2689142 2.2853059
OS 2.2653779 2.2905984
OS 2.2600854 2.2941347
OS 2.2538425 2.2953765
OE
OB 3.3428425 2.2793765 H
OS 3.3365996 2.2781347
OS 3.3313071 2.2745984
OS 3.3277708 2.2693059
OS 3.326529 2.263063
OS 3.3277708 2.2568201
OS 3.3313071 2.2515276
OS 3.3365996 2.2479913
OS 3.3428425 2.2467495
OS 3.3490854 2.2479913
OS 3.3543779 2.2515276
OS 3.3579142 2.2568201
OS 3.359156 2.263063
OS 3.3579142 2.2693059
OS 3.3543779 2.2745984
OS 3.3490854 2.2781347
OS 3.3428425 2.2793765
OE
OB 2.8418425 2.2793765 H
OS 2.8355996 2.2781347
OS 2.8303071 2.2745984
OS 2.8267708 2.2693059
OS 2.825529 2.263063
OS 2.8267708 2.2568201
OS 2.8303071 2.2515276
OS 2.8355996 2.2479913
OS 2.8418425 2.2467495
OS 2.8480854 2.2479913
OS 2.8533779 2.2515276
OS 2.8569142 2.2568201
OS 2.858156 2.263063
OS 2.8569142 2.2693059
OS 2.8533779 2.2745984
OS 2.8480854 2.2781347
OS 2.8418425 2.2793765
OE
OB 2.4998425 2.2523765 H
OS 2.4935996 2.2511347
OS 2.4883071 2.2475984
OS 2.4847708 2.2423059
OS 2.483529 2.236063
OS 2.4847708 2.2298201
OS 2.4883071 2.2245276
OS 2.4935996 2.2209913
OS 2.4998425 2.2197495
OS 2.5060854 2.2209913
OS 2.5113779 2.2245276
OS 2.5149142 2.2298201
OS 2.516156 2.236063
OS 2.5149142 2.2423059
OS 2.5113779 2.2475984
OS 2.5060854 2.2511347
OS 2.4998425 2.2523765
OE
OB 2.3308425 2.2313765 H
OS 2.3245996 2.2301347
OS 2.3193071 2.2265984
OS 2.3157708 2.2213059
OS 2.314529 2.215063
OS 2.3157708 2.2088201
OS 2.3193071 2.2035276
OS 2.3245996 2.1999913
OS 2.3308425 2.1987495
OS 2.3370854 2.1999913
OS 2.3423779 2.2035276
OS 2.3459142 2.2088201
OS 2.347156 2.215063
OS 2.3459142 2.2213059
OS 2.3423779 2.2265984
OS 2.3370854 2.2301347
OS 2.3308425 2.2313765
OE
OB 3.5717425 2.1163919 H
OS 3.5643954 2.1149305
OS 3.5581668 2.1107687
OS 3.554005 2.1045401
OS 3.5525436 2.097193
OS 3.554005 2.0898459
OS 3.5581668 2.0836173
OS 3.5643954 2.0794555
OS 3.5717425 2.0779941
OS 3.5790896 2.0794555
OS 3.5853182 2.0836173
OS 3.58948 2.0898459
OS 3.5909414 2.097193
OS 3.58948 2.1045401
OS 3.5853182 2.1107687
OS 3.5790896 2.1149305
OS 3.5717425 2.1163919
OE
OB 3.7198425 2.0123765 H
OS 3.7135996 2.0111347
OS 3.7083071 2.0075984
OS 3.7047708 2.0023059
OS 3.703529 1.996063
OS 3.7047708 1.9898201
OS 3.7083071 1.9845276
OS 3.7135996 1.9809913
OS 3.7198425 1.9797495
OS 3.7260854 1.9809913
OS 3.7313779 1.9845276
OS 3.7349142 1.9898201
OS 3.736156 1.996063
OS 3.7349142 2.0023059
OS 3.7313779 2.0075984
OS 3.7260854 2.0111347
OS 3.7198425 2.0123765
OE
OB 3.5548425 2.0073765 H
OS 3.5485996 2.0061347
OS 3.5433071 2.0025984
OS 3.5397708 1.9973059
OS 3.538529 1.991063
OS 3.5397708 1.9848201
OS 3.5433071 1.9795276
OS 3.5485996 1.9759913
OS 3.5548425 1.9747495
OS 3.5610854 1.9759913
OS 3.5663779 1.9795276
OS 3.5699142 1.9848201
OS 3.571156 1.991063
OS 3.5699142 1.9973059
OS 3.5663779 2.0025984
OS 3.5610854 2.0061347
OS 3.5548425 2.0073765
OE
OB 3.2988425 1.9873765 H
OS 3.2925996 1.9861347
OS 3.2873071 1.9825984
OS 3.2837708 1.9773059
OS 3.282529 1.971063
OS 3.2837708 1.9648201
OS 3.2873071 1.9595276
OS 3.2925996 1.9559913
OS 3.2988425 1.9547495
OS 3.3050854 1.9559913
OS 3.3103779 1.9595276
OS 3.3139142 1.9648201
OS 3.315156 1.971063
OS 3.3139142 1.9773059
OS 3.3103779 1.9825984
OS 3.3050854 1.9861347
OS 3.2988425 1.9873765
OE
OB 3.5548425 1.9573765 H
OS 3.5485996 1.9561347
OS 3.5433071 1.9525984
OS 3.5397708 1.9473059
OS 3.538529 1.941063
OS 3.5397708 1.9348201
OS 3.5433071 1.9295276
OS 3.5485996 1.9259913
OS 3.5548425 1.9247495
OS 3.5610854 1.9259913
OS 3.5663779 1.9295276
OS 3.5699142 1.9348201
OS 3.571156 1.941063
OS 3.5699142 1.9473059
OS 3.5663779 1.9525984
OS 3.5610854 1.9561347
OS 3.5548425 1.9573765
OE
OB 3.7198425 1.9373765 H
OS 3.7135996 1.9361347
OS 3.7083071 1.9325984
OS 3.7047708 1.9273059
OS 3.703529 1.921063
OS 3.7047708 1.9148201
OS 3.7083071 1.9095276
OS 3.7135996 1.9059913
OS 3.7198425 1.9047495
OS 3.7260854 1.9059913
OS 3.7313779 1.9095276
OS 3.7349142 1.9148201
OS 3.736156 1.921063
OS 3.7349142 1.9273059
OS 3.7313779 1.9325984
OS 3.7260854 1.9361347
OS 3.7198425 1.9373765
OE
OB 3.5548425 1.9073765 H
OS 3.5485996 1.9061347
OS 3.5433071 1.9025984
OS 3.5397708 1.8973059
OS 3.538529 1.891063
OS 3.5397708 1.8848201
OS 3.5433071 1.8795276
OS 3.5485996 1.8759913
OS 3.5548425 1.8747495
OS 3.5610854 1.8759913
OS 3.5663779 1.8795276
OS 3.5699142 1.8848201
OS 3.571156 1.891063
OS 3.5699142 1.8973059
OS 3.5663779 1.9025984
OS 3.5610854 1.9061347
OS 3.5548425 1.9073765
OE
OB 3.3928425 1.8873765 H
OS 3.3865996 1.8861347
OS 3.3813071 1.8825984
OS 3.3777708 1.8773059
OS 3.376529 1.871063
OS 3.3777708 1.8648201
OS 3.3813071 1.8595276
OS 3.3865996 1.8559913
OS 3.3928425 1.8547495
OS 3.3990854 1.8559913
OS 3.4043779 1.8595276
OS 3.4079142 1.8648201
OS 3.409156 1.871063
OS 3.4079142 1.8773059
OS 3.4043779 1.8825984
OS 3.3990854 1.8861347
OS 3.3928425 1.8873765
OE
OB 3.4392507 1.8872515 H
OS 3.4330078 1.8860097
OS 3.4277153 1.8824734
OS 3.424179 1.8771809
OS 3.4229372 1.870938
OS 3.424179 1.8646951
OS 3.4277153 1.8594026
OS 3.4330078 1.8558663
OS 3.4392507 1.8546245
OS 3.4454936 1.8558663
OS 3.4507861 1.8594026
OS 3.4543224 1.8646951
OS 3.4555642 1.870938
OS 3.4543224 1.8771809
OS 3.4507861 1.8824734
OS 3.4454936 1.8860097
OS 3.4392507 1.8872515
OE
OB 3.5548425 1.8573765 H
OS 3.5485996 1.8561347
OS 3.5433071 1.8525984
OS 3.5397708 1.8473059
OS 3.538529 1.841063
OS 3.5397708 1.8348201
OS 3.5433071 1.8295276
OS 3.5485996 1.8259913
OS 3.5548425 1.8247495
OS 3.5610854 1.8259913
OS 3.5663779 1.8295276
OS 3.5699142 1.8348201
OS 3.571156 1.841063
OS 3.5699142 1.8473059
OS 3.5663779 1.8525984
OS 3.5610854 1.8561347
OS 3.5548425 1.8573765
OE
OB 3.8048425 1.8563765 H
OS 3.7985996 1.8551347
OS 3.7933071 1.8515984
OS 3.7897708 1.8463059
OS 3.788529 1.840063
OS 3.7897708 1.8338201
OS 3.7933071 1.8285276
OS 3.7985996 1.8249913
OS 3.8048425 1.8237495
OS 3.8110854 1.8249913
OS 3.8163779 1.8285276
OS 3.8199142 1.8338201
OS 3.821156 1.840063
OS 3.8199142 1.8463059
OS 3.8163779 1.8515984
OS 3.8110854 1.8551347
OS 3.8048425 1.8563765
OE
OB 6.6858425 1.8443765 H
OS 6.6795996 1.8431347
OS 6.6743071 1.8395984
OS 6.6707708 1.8343059
OS 6.669529 1.828063
OS 6.6707708 1.8218201
OS 6.6743071 1.8165276
OS 6.6795996 1.8129913
OS 6.6858425 1.8117495
OS 6.6920854 1.8129913
OS 6.6973779 1.8165276
OS 6.7009142 1.8218201
OS 6.702156 1.828063
OS 6.7009142 1.8343059
OS 6.6973779 1.8395984
OS 6.6920854 1.8431347
OS 6.6858425 1.8443765
OE
OB 3.3291721 1.8423765 H
OS 3.3229292 1.8411347
OS 3.3176367 1.8375984
OS 3.3141004 1.8323059
OS 3.3128586 1.826063
OS 3.3141004 1.8198201
OS 3.3176367 1.8145276
OS 3.3229292 1.8109913
OS 3.3291721 1.8097495
OS 3.335415 1.8109913
OS 3.3407075 1.8145276
OS 3.3442438 1.8198201
OS 3.3454856 1.826063
OS 3.3442438 1.8323059
OS 3.3407075 1.8375984
OS 3.335415 1.8411347
OS 3.3291721 1.8423765
OE
OB 3.9448425 1.8323765 H
OS 3.9385996 1.8311347
OS 3.9333071 1.8275984
OS 3.9297708 1.8223059
OS 3.928529 1.816063
OS 3.9297708 1.8098201
OS 3.9333071 1.8045276
OS 3.9385996 1.8009913
OS 3.9448425 1.7997495
OS 3.9510854 1.8009913
OS 3.9563779 1.8045276
OS 3.9599142 1.8098201
OS 3.961156 1.816063
OS 3.9599142 1.8223059
OS 3.9563779 1.8275984
OS 3.9510854 1.8311347
OS 3.9448425 1.8323765
OE
OB 3.0568817 1.8281165 H
OS 3.0506388 1.8268747
OS 3.0453463 1.8233384
OS 3.04181 1.8180459
OS 3.0405682 1.811803
OS 3.04181 1.8055601
OS 3.0453463 1.8002676
OS 3.0506388 1.7967313
OS 3.0568817 1.7954895
OS 3.0631246 1.7967313
OS 3.0684171 1.8002676
OS 3.0719534 1.8055601
OS 3.0731952 1.811803
OS 3.0719534 1.8180459
OS 3.0684171 1.8233384
OS 3.0631246 1.8268747
OS 3.0568817 1.8281165
OE
OB 3.4144661 1.8213765 H
OS 3.4082232 1.8201347
OS 3.4029307 1.8165984
OS 3.3993944 1.8113059
OS 3.3981526 1.805063
OS 3.3993944 1.7988201
OS 3.4029307 1.7935276
OS 3.4082232 1.7899913
OS 3.4144661 1.7887495
OS 3.420709 1.7899913
OS 3.4260015 1.7935276
OS 3.4295378 1.7988201
OS 3.4307796 1.805063
OS 3.4295378 1.8113059
OS 3.4260015 1.8165984
OS 3.420709 1.8201347
OS 3.4144661 1.8213765
OE
OB 4.0648425 1.8123765 H
OS 4.0585996 1.8111347
OS 4.0533071 1.8075984
OS 4.0497708 1.8023059
OS 4.048529 1.796063
OS 4.0497708 1.7898201
OS 4.0533071 1.7845276
OS 4.0585996 1.7809913
OS 4.0648425 1.7797495
OS 4.0710854 1.7809913
OS 4.0763779 1.7845276
OS 4.0799142 1.7898201
OS 4.081156 1.796063
OS 4.0799142 1.8023059
OS 4.0763779 1.8075984
OS 4.0710854 1.8111347
OS 4.0648425 1.8123765
OE
OB 6.6018425 1.7933765 H
OS 6.5955996 1.7921347
OS 6.5903071 1.7885984
OS 6.5867708 1.7833059
OS 6.585529 1.777063
OS 6.5867708 1.7708201
OS 6.5903071 1.7655276
OS 6.5955996 1.7619913
OS 6.6018425 1.7607495
OS 6.6080854 1.7619913
OS 6.6133779 1.7655276
OS 6.6169142 1.7708201
OS 6.618156 1.777063
OS 6.6169142 1.7833059
OS 6.6133779 1.7885984
OS 6.6080854 1.7921347
OS 6.6018425 1.7933765
OE
OB 3.7198425 1.7823765 H
OS 3.7135996 1.7811347
OS 3.7083071 1.7775984
OS 3.7047708 1.7723059
OS 3.703529 1.766063
OS 3.7047708 1.7598201
OS 3.7083071 1.7545276
OS 3.7135996 1.7509913
OS 3.7198425 1.7497495
OS 3.7260854 1.7509913
OS 3.7313779 1.7545276
OS 3.7349142 1.7598201
OS 3.736156 1.766063
OS 3.7349142 1.7723059
OS 3.7313779 1.7775984
OS 3.7260854 1.7811347
OS 3.7198425 1.7823765
OE
OB 4.1348425 1.7673765 H
OS 4.1285996 1.7661347
OS 4.1233071 1.7625984
OS 4.1197708 1.7573059
OS 4.118529 1.751063
OS 4.1197708 1.7448201
OS 4.1233071 1.7395276
OS 4.1285996 1.7359913
OS 4.1348425 1.7347495
OS 4.1410854 1.7359913
OS 4.1463779 1.7395276
OS 4.1499142 1.7448201
OS 4.151156 1.751063
OS 4.1499142 1.7573059
OS 4.1463779 1.7625984
OS 4.1410854 1.7661347
OS 4.1348425 1.7673765
OE
OB 6.6028425 1.7383765 H
OS 6.5965996 1.7371347
OS 6.5913071 1.7335984
OS 6.5877708 1.7283059
OS 6.586529 1.722063
OS 6.5877708 1.7158201
OS 6.5913071 1.7105276
OS 6.5965996 1.7069913
OS 6.6028425 1.7057495
OS 6.6090854 1.7069913
OS 6.6143779 1.7105276
OS 6.6179142 1.7158201
OS 6.619156 1.722063
OS 6.6179142 1.7283059
OS 6.6143779 1.7335984
OS 6.6090854 1.7371347
OS 6.6028425 1.7383765
OE
OB 3.1972633 1.7303765 H
OS 3.1910204 1.7291347
OS 3.1857279 1.7255984
OS 3.1821916 1.7203059
OS 3.1809498 1.714063
OS 3.1821916 1.7078201
OS 3.1857279 1.7025276
OS 3.1910204 1.6989913
OS 3.1972633 1.6977495
OS 3.2035062 1.6989913
OS 3.2087987 1.7025276
OS 3.212335 1.7078201
OS 3.2135768 1.714063
OS 3.212335 1.7203059
OS 3.2087987 1.7255984
OS 3.2035062 1.7291347
OS 3.1972633 1.7303765
OE
OB 3.4108425 1.7299644 H
OS 3.4045996 1.7287226
OS 3.3993071 1.7251863
OS 3.3957708 1.7198938
OS 3.394529 1.7136509
OS 3.3957708 1.707408
OS 3.3993071 1.7021155
OS 3.4045996 1.6985792
OS 3.4108425 1.6973374
OS 3.4170854 1.6985792
OS 3.4223779 1.7021155
OS 3.4259142 1.707408
OS 3.427156 1.7136509
OS 3.4259142 1.7198938
OS 3.4223779 1.7251863
OS 3.4170854 1.7287226
OS 3.4108425 1.7299644
OE
OB 3.7188425 1.7293765 H
OS 3.7125996 1.7281347
OS 3.7073071 1.7245984
OS 3.7037708 1.7193059
OS 3.702529 1.713063
OS 3.7037708 1.7068201
OS 3.7073071 1.7015276
OS 3.7125996 1.6979913
OS 3.7188425 1.6967495
OS 3.7250854 1.6979913
OS 3.7303779 1.7015276
OS 3.7339142 1.7068201
OS 3.735156 1.713063
OS 3.7339142 1.7193059
OS 3.7303779 1.7245984
OS 3.7250854 1.7281347
OS 3.7188425 1.7293765
OE
OB 3.9968425 1.7273765 H
OS 3.9905996 1.7261347
OS 3.9853071 1.7225984
OS 3.9817708 1.7173059
OS 3.980529 1.711063
OS 3.9817708 1.7048201
OS 3.9853071 1.6995276
OS 3.9905996 1.6959913
OS 3.9968425 1.6947495
OS 4.0030854 1.6959913
OS 4.0083779 1.6995276
OS 4.0119142 1.7048201
OS 4.013156 1.711063
OS 4.0119142 1.7173059
OS 4.0083779 1.7225984
OS 4.0030854 1.7261347
OS 3.9968425 1.7273765
OE
OB 3.5898425 1.7273765 H
OS 3.5835996 1.7261347
OS 3.5783071 1.7225984
OS 3.5747708 1.7173059
OS 3.573529 1.711063
OS 3.5747708 1.7048201
OS 3.5783071 1.6995276
OS 3.5835996 1.6959913
OS 3.5898425 1.6947495
OS 3.5960854 1.6959913
OS 3.6013779 1.6995276
OS 3.6049142 1.7048201
OS 3.606156 1.711063
OS 3.6049142 1.7173059
OS 3.6013779 1.7225984
OS 3.5960854 1.7261347
OS 3.5898425 1.7273765
OE
OB 3.8038425 1.7073765 H
OS 3.7975996 1.7061347
OS 3.7923071 1.7025984
OS 3.7887708 1.6973059
OS 3.787529 1.691063
OS 3.7887708 1.6848201
OS 3.7923071 1.6795276
OS 3.7975996 1.6759913
OS 3.8038425 1.6747495
OS 3.8100854 1.6759913
OS 3.8153779 1.6795276
OS 3.8189142 1.6848201
OS 3.820156 1.691063
OS 3.8189142 1.6973059
OS 3.8153779 1.7025984
OS 3.8100854 1.7061347
OS 3.8038425 1.7073765
OE
OB 3.7248425 1.6913765 H
OS 3.7185996 1.6901347
OS 3.7133071 1.6865984
OS 3.7097708 1.6813059
OS 3.708529 1.675063
OS 3.7097708 1.6688201
OS 3.7133071 1.6635276
OS 3.7185996 1.6599913
OS 3.7248425 1.6587495
OS 3.7310854 1.6599913
OS 3.7363779 1.6635276
OS 3.7399142 1.6688201
OS 3.741156 1.675063
OS 3.7399142 1.6813059
OS 3.7363779 1.6865984
OS 3.7310854 1.6901347
OS 3.7248425 1.6913765
OE
OB 6.6028425 1.6883765 H
OS 6.5965996 1.6871347
OS 6.5913071 1.6835984
OS 6.5877708 1.6783059
OS 6.586529 1.672063
OS 6.5877708 1.6658201
OS 6.5913071 1.6605276
OS 6.5965996 1.6569913
OS 6.6028425 1.6557495
OS 6.6090854 1.6569913
OS 6.6143779 1.6605276
OS 6.6179142 1.6658201
OS 6.619156 1.672063
OS 6.6179142 1.6783059
OS 6.6143779 1.6835984
OS 6.6090854 1.6871347
OS 6.6028425 1.6883765
OE
OB 3.9688425 1.6873765 H
OS 3.9625996 1.6861347
OS 3.9573071 1.6825984
OS 3.9537708 1.6773059
OS 3.952529 1.671063
OS 3.9537708 1.6648201
OS 3.9573071 1.6595276
OS 3.9625996 1.6559913
OS 3.9688425 1.6547495
OS 3.9750854 1.6559913
OS 3.9803779 1.6595276
OS 3.9839142 1.6648201
OS 3.985156 1.671063
OS 3.9839142 1.6773059
OS 3.9803779 1.6825984
OS 3.9750854 1.6861347
OS 3.9688425 1.6873765
OE
OB 3.7738632 1.6824156 H
OS 3.7676203 1.6811738
OS 3.7623278 1.6776375
OS 3.7587915 1.672345
OS 3.7575497 1.6661021
OS 3.7587915 1.6598592
OS 3.7623278 1.6545667
OS 3.7676203 1.6510304
OS 3.7738632 1.6497886
OS 3.7801061 1.6510304
OS 3.7853986 1.6545667
OS 3.7889349 1.6598592
OS 3.7901767 1.6661021
OS 3.7889349 1.672345
OS 3.7853986 1.6776375
OS 3.7801061 1.6811738
OS 3.7738632 1.6824156
OE
OB 3.5908425 1.6783765 H
OS 3.5845996 1.6771347
OS 3.5793071 1.6735984
OS 3.5757708 1.6683059
OS 3.574529 1.662063
OS 3.5757708 1.6558201
OS 3.5793071 1.6505276
OS 3.5845996 1.6469913
OS 3.5908425 1.6457495
OS 3.5970854 1.6469913
OS 3.6023779 1.6505276
OS 3.6059142 1.6558201
OS 3.607156 1.662063
OS 3.6059142 1.6683059
OS 3.6023779 1.6735984
OS 3.5970854 1.6771347
OS 3.5908425 1.6783765
OE
OB 3.2248425 1.6776607 H
OS 3.2185996 1.6764189
OS 3.2133071 1.6728826
OS 3.2097708 1.6675901
OS 3.208529 1.6613472
OS 3.2097708 1.6551043
OS 3.2133071 1.6498118
OS 3.2185996 1.6462755
OS 3.2248425 1.6450337
OS 3.2310854 1.6462755
OS 3.235497 1.6492232
OS 3.2395781 1.6496996
OS 3.2419254 1.6491144
OS 3.2465996 1.6459913
OS 3.2528425 1.6447495
OS 3.2590854 1.6459913
OS 3.2643779 1.6495276
OS 3.2679142 1.6548201
OS 3.269156 1.661063
OS 3.2679142 1.6673059
OS 3.2643779 1.6725984
OS 3.2590854 1.6761347
OS 3.2528425 1.6773765
OS 3.2465996 1.6761347
OS 3.242188 1.673187
OS 3.2381069 1.6727106
OS 3.2357596 1.6732958
OS 3.2310854 1.6764189
OS 3.2248425 1.6776607
OE
OB 5.5781524 1.7357238 H
OS 5.5662745 1.73416
OS 5.5552061 1.7295754
OS 5.5457014 1.7222822
OS 5.5384082 1.7127775
OS 5.5338236 1.7017091
OS 5.5322598 1.6898312
OS 5.5338236 1.6779533
OS 5.5384082 1.6668849
OS 5.5457014 1.6573802
OS 5.5552061 1.650087
OS 5.5662745 1.6455024
OS 5.5781524 1.6439386
OS 5.5900303 1.6455024
OS 5.6010987 1.650087
OS 5.6106034 1.6573802
OS 5.6178966 1.6668849
OS 5.6224812 1.6779533
OS 5.624045 1.6898312
OS 5.6224812 1.7017091
OS 5.6178966 1.7127775
OS 5.6106034 1.7222822
OS 5.6010987 1.7295754
OS 5.5900303 1.73416
OS 5.5781524 1.7357238
OE
OB 6.6028425 1.6283765 H
OS 6.5965996 1.6271347
OS 6.5913071 1.6235984
OS 6.5877708 1.6183059
OS 6.586529 1.612063
OS 6.5877708 1.6058201
OS 6.5913071 1.6005276
OS 6.5965996 1.5969913
OS 6.6028425 1.5957495
OS 6.6090854 1.5969913
OS 6.6143779 1.6005276
OS 6.6179142 1.6058201
OS 6.619156 1.612063
OS 6.6179142 1.6183059
OS 6.6143779 1.6235984
OS 6.6090854 1.6271347
OS 6.6028425 1.6283765
OE
OB 4.1318425 1.7023765 H
OS 4.1255996 1.7011347
OS 4.1203071 1.6975984
OS 4.1167708 1.6923059
OS 4.115529 1.686063
OS 4.1167708 1.6798201
OS 4.1203071 1.6745276
OS 4.1255996 1.6709913
OS 4.1271051 1.6706918
OS 4.1275051 1.6694719
OS 4.127633 1.6654888
OS 4.1233071 1.6625984
OS 4.1197708 1.6573059
OS 4.118529 1.651063
OS 4.1197708 1.6448201
OS 4.1233071 1.6395276
OS 4.1285996 1.6359913
OS 4.1336434 1.634988
OS 4.1357664 1.6316625
OS 4.1362826 1.629938
OS 4.1362346 1.6298661
OS 4.1349928 1.6236232
OS 4.1362346 1.6173803
OS 4.1397709 1.6120878
OS 4.1450634 1.6085515
OS 4.1513063 1.6073097
OS 4.1575492 1.6085515
OS 4.1612353 1.6110144
OS 4.1648401 1.6074096
OS 4.1647708 1.6073059
OS 4.163529 1.601063
OS 4.1647708 1.5948201
OS 4.1683071 1.5895276
OS 4.1735996 1.5859913
OS 4.1798425 1.5847495
OS 4.1860854 1.5859913
OS 4.1913779 1.5895276
OS 4.1949142 1.5948201
OS 4.196156 1.601063
OS 4.1949142 1.6073059
OS 4.1913779 1.6125984
OS 4.1860854 1.6161347
OS 4.1798425 1.6173765
OS 4.1735996 1.6161347
OS 4.1699135 1.6136718
OS 4.1663087 1.6172766
OS 4.166378 1.6173803
OS 4.1676198 1.6236232
OS 4.166378 1.6298661
OS 4.1628417 1.6351586
OS 4.1575492 1.6386949
OS 4.1525054 1.6396982
OS 4.1503824 1.6430237
OS 4.1498662 1.6447482
OS 4.1499142 1.6448201
OS 4.151156 1.651063
OS 4.1499142 1.6573059
OS 4.1463779 1.6625984
OS 4.1410854 1.6661347
OS 4.1395799 1.6664342
OS 4.1391799 1.6676541
OS 4.139052 1.6716372
OS 4.1433779 1.6745276
OS 4.1469142 1.6798201
OS 4.148156 1.686063
OS 4.1469142 1.6923059
OS 4.1433779 1.6975984
OS 4.1380854 1.7011347
OS 4.1318425 1.7023765
OE
OB 3.4138425 1.5893765 H
OS 3.4075996 1.5881347
OS 3.4023071 1.5845984
OS 3.3987708 1.5793059
OS 3.397529 1.573063
OS 3.3987708 1.5668201
OS 3.4023071 1.5615276
OS 3.4075996 1.5579913
OS 3.4138425 1.5567495
OS 3.4200854 1.5579913
OS 3.4253779 1.5615276
OS 3.4289142 1.5668201
OS 3.430156 1.573063
OS 3.4289142 1.5793059
OS 3.4253779 1.5845984
OS 3.4200854 1.5881347
OS 3.4138425 1.5893765
OE
OB 3.8948425 1.5823765 H
OS 3.8885996 1.5811347
OS 3.8833071 1.5775984
OS 3.8797708 1.5723059
OS 3.878529 1.566063
OS 3.8797708 1.5598201
OS 3.8833071 1.5545276
OS 3.8885996 1.5509913
OS 3.8948425 1.5497495
OS 3.9010854 1.5509913
OS 3.9063779 1.5545276
OS 3.9099142 1.5598201
OS 3.911156 1.566063
OS 3.9099142 1.5723059
OS 3.9063779 1.5775984
OS 3.9010854 1.5811347
OS 3.8948425 1.5823765
OE
OB 3.9698425 1.5683765 H
OS 3.9635996 1.5671347
OS 3.9583071 1.5635984
OS 3.9547708 1.5583059
OS 3.953529 1.552063
OS 3.9547708 1.5458201
OS 3.9583071 1.5405276
OS 3.9635996 1.5369913
OS 3.9698425 1.5357495
OS 3.9760854 1.5369913
OS 3.9780923 1.5383323
OS 3.9831154 1.5394836
OS 3.9856688 1.5379496
OS 3.9885996 1.5359913
OS 3.9948425 1.5347495
OS 4.0010854 1.5359913
OS 4.0063779 1.5395276
OS 4.0099142 1.5448201
OS 4.011156 1.551063
OS 4.0099142 1.5573059
OS 4.0063779 1.5625984
OS 4.0010854 1.5661347
OS 3.9948425 1.5673765
OS 3.9885996 1.5661347
OS 3.9833072 1.5625984
OS 3.982046 1.5625984
OS 3.9813779 1.5635984
OS 3.9760854 1.5671347
OS 3.9698425 1.5683765
OE
OB 4.0348425 1.5623765 H
OS 4.0285996 1.5611347
OS 4.0233071 1.5575984
OS 4.0197708 1.5523059
OS 4.018529 1.546063
OS 4.0197708 1.5398201
OS 4.0233071 1.5345276
OS 4.0285996 1.5309913
OS 4.0348425 1.5297495
OS 4.0410854 1.5309913
OS 4.0463779 1.5345276
OS 4.0499142 1.5398201
OS 4.051156 1.546063
OS 4.0499142 1.5523059
OS 4.0463779 1.5575984
OS 4.0410854 1.5611347
OS 4.0348425 1.5623765
OE
OB 3.9248425 1.5523765 H
OS 3.9185996 1.5511347
OS 3.9133071 1.5475984
OS 3.9097708 1.5423059
OS 3.908529 1.536063
OS 3.9097708 1.5298201
OS 3.9133071 1.5245276
OS 3.9185996 1.5209913
OS 3.9248425 1.5197495
OS 3.9310854 1.5209913
OS 3.9363779 1.5245276
OS 3.9399142 1.5298201
OS 3.941156 1.536063
OS 3.9399142 1.5423059
OS 3.9363779 1.5475984
OS 3.9310854 1.5511347
OS 3.9248425 1.5523765
OE
OB 2.8948425 1.5773765 H
OS 2.8885996 1.5761347
OS 2.8833071 1.5725984
OS 2.8797708 1.5673059
OS 2.878529 1.561063
OS 2.8797708 1.5548201
OS 2.8833071 1.5495276
OS 2.8885996 1.5459913
OS 2.8948425 1.5447495
OS 2.9010854 1.5459913
OS 2.9013282 1.5461536
OS 2.9049331 1.5425487
OS 2.9047708 1.5423059
OS 2.903529 1.536063
OS 2.9047708 1.5298201
OS 2.9083071 1.5245276
OS 2.9135996 1.5209913
OS 2.9198425 1.5197495
OS 2.9260854 1.5209913
OS 2.9313779 1.5245276
OS 2.9349142 1.5298201
OS 2.936156 1.536063
OS 2.9349142 1.5423059
OS 2.9313779 1.5475984
OS 2.9260854 1.5511347
OS 2.9198425 1.5523765
OS 2.9135996 1.5511347
OS 2.9133568 1.5509724
OS 2.9097519 1.5545773
OS 2.9099142 1.5548201
OS 2.911156 1.561063
OS 2.9099142 1.5673059
OS 2.9063779 1.5725984
OS 2.9010854 1.5761347
OS 2.8948425 1.5773765
OE
OB 6.5488425 1.5473765 H
OS 6.5425996 1.5461347
OS 6.5373071 1.5425984
OS 6.5337708 1.5373059
OS 6.532529 1.531063
OS 6.5337708 1.5248201
OS 6.5373071 1.5195276
OS 6.5425996 1.5159913
OS 6.5488425 1.5147495
OS 6.5550854 1.5159913
OS 6.5603779 1.5195276
OS 6.5639142 1.5248201
OS 6.565156 1.531063
OS 6.5639142 1.5373059
OS 6.5603779 1.5425984
OS 6.5550854 1.5461347
OS 6.5488425 1.5473765
OE
OB 3.5948425 1.5303765 H
OS 3.5885996 1.5291347
OS 3.5833071 1.5255984
OS 3.5797708 1.5203059
OS 3.578529 1.514063
OS 3.5797708 1.5078201
OS 3.5833071 1.5025276
OS 3.5885996 1.4989913
OS 3.5948425 1.4977495
OS 3.6010854 1.4989913
OS 3.6063779 1.5025276
OS 3.6099142 1.5078201
OS 3.611156 1.514063
OS 3.6099142 1.5203059
OS 3.6063779 1.5255984
OS 3.6010854 1.5291347
OS 3.5948425 1.5303765
OE
OB 4.0648425 1.5273765 H
OS 4.0585996 1.5261347
OS 4.0533071 1.5225984
OS 4.0497708 1.5173059
OS 4.048529 1.511063
OS 4.0497708 1.5048201
OS 4.0533071 1.4995276
OS 4.0585996 1.4959913
OS 4.0648425 1.4947495
OS 4.0710854 1.4959913
OS 4.0763779 1.4995276
OS 4.0799142 1.5048201
OS 4.081156 1.511063
OS 4.0799142 1.5173059
OS 4.0763779 1.5225984
OS 4.0710854 1.5261347
OS 4.0648425 1.5273765
OE
OB 3.8648425 1.5273765 H
OS 3.8585996 1.5261347
OS 3.8533071 1.5225984
OS 3.8497708 1.5173059
OS 3.848529 1.511063
OS 3.8497708 1.5048201
OS 3.8533071 1.4995276
OS 3.8585996 1.4959913
OS 3.8648425 1.4947495
OS 3.8710854 1.4959913
OS 3.8763779 1.4995276
OS 3.8799142 1.5048201
OS 3.881156 1.511063
OS 3.8799142 1.5173059
OS 3.8763779 1.5225984
OS 3.8710854 1.5261347
OS 3.8648425 1.5273765
OE
OB 3.8348425 1.4973765 H
OS 3.8285996 1.4961347
OS 3.8233071 1.4925984
OS 3.8197708 1.4873059
OS 3.818529 1.481063
OS 3.8197708 1.4748201
OS 3.8233071 1.4695276
OS 3.8285996 1.4659913
OS 3.8348425 1.4647495
OS 3.8410854 1.4659913
OS 3.8463779 1.4695276
OS 3.8499142 1.4748201
OS 3.851156 1.481063
OS 3.8499142 1.4873059
OS 3.8463779 1.4925984
OS 3.8410854 1.4961347
OS 3.8348425 1.4973765
OE
OB 3.4068425 1.4773765 H
OS 3.4005996 1.4761347
OS 3.3953071 1.4725984
OS 3.3917708 1.4673059
OS 3.390529 1.461063
OS 3.3917708 1.4548201
OS 3.3953071 1.4495276
OS 3.4005996 1.4459913
OS 3.4068425 1.4447495
OS 3.4130854 1.4459913
OS 3.4183779 1.4495276
OS 3.4219142 1.4548201
OS 3.423156 1.461063
OS 3.4219142 1.4673059
OS 3.4183779 1.4725984
OS 3.4130854 1.4761347
OS 3.4068425 1.4773765
OE
OB 3.7328425 1.4343765 H
OS 3.7265996 1.4331347
OS 3.7213071 1.4295984
OS 3.7177708 1.4243059
OS 3.716529 1.418063
OS 3.7177708 1.4118201
OS 3.7213071 1.4065276
OS 3.7265996 1.4029913
OS 3.7328425 1.4017495
OS 3.7390854 1.4029913
OS 3.7443779 1.4065276
OS 3.7479142 1.4118201
OS 3.749156 1.418063
OS 3.7479142 1.4243059
OS 3.7443779 1.4295984
OS 3.7390854 1.4331347
OS 3.7328425 1.4343765
OE
OB 3.4072822 1.4276365 H
OS 3.4010393 1.4263947
OS 3.3957468 1.4228584
OS 3.3922105 1.4175659
OS 3.3909687 1.411323
OS 3.3922105 1.4050801
OS 3.3952066 1.4005957
OS 3.3913778 1.3975986
OS 3.3860854 1.4011347
OS 3.3798425 1.4023765
OS 3.3735996 1.4011347
OS 3.3683071 1.3975984
OS 3.3647708 1.3923059
OS 3.363529 1.386063
OS 3.3647708 1.3798201
OS 3.3683071 1.3745276
OS 3.3735996 1.3709913
OS 3.3798425 1.3697495
OS 3.3850268 1.3707807
OS 3.3880585 1.3685992
OS 3.3892832 1.3671145
OS 3.388529 1.363323
OS 3.3897708 1.3570801
OS 3.3920261 1.3537048
OS 3.3926608 1.3527545
OS 3.3890562 1.3491499
OS 3.3882815 1.3496673
OS 3.3860854 1.3511347
OS 3.3798425 1.3523765
OS 3.3735996 1.3511347
OS 3.3683071 1.3475984
OS 3.3647708 1.3423059
OS 3.363529 1.336063
OS 3.3647708 1.3298201
OS 3.3683071 1.3245276
OS 3.3735996 1.3209913
OS 3.3798425 1.3197495
OS 3.3860854 1.3209913
OS 3.3913779 1.3245276
OS 3.3949142 1.3298201
OS 3.396156 1.336063
OS 3.3949142 1.3423059
OS 3.3926589 1.3456812
OS 3.3920242 1.3466315
OS 3.3956288 1.3502361
OS 3.3964035 1.3497187
OS 3.3985996 1.3482513
OS 3.4048425 1.3470095
OS 3.4110854 1.3482513
OS 3.4163779 1.3517876
OS 3.4199142 1.3570801
OS 3.421156 1.363323
OS 3.4199142 1.3695659
OS 3.4163779 1.3748584
OS 3.4110854 1.3783947
OS 3.4048425 1.3796365
OS 3.3996582 1.3786053
OS 3.3966265 1.3807868
OS 3.3954018 1.3822715
OS 3.396156 1.386063
OS 3.3949142 1.3923059
OS 3.3919181 1.3967903
OS 3.3957469 1.3997874
OS 3.4010393 1.3962513
OS 3.4072822 1.3950095
OS 3.4135251 1.3962513
OS 3.4188176 1.3997876
OS 3.4223539 1.4050801
OS 3.4235957 1.411323
OS 3.4223539 1.4175659
OS 3.4188176 1.4228584
OS 3.4135251 1.4263947
OS 3.4072822 1.4276365
OE
OB 3.5498425 1.4573765 H
OS 3.5435996 1.4561347
OS 3.5383071 1.4525984
OS 3.5347708 1.4473059
OS 3.533529 1.441063
OS 3.5347708 1.4348201
OS 3.5383071 1.4295277
OS 3.5383071 1.4245983
OS 3.5347708 1.4193059
OS 3.533529 1.413063
OS 3.5347708 1.4068201
OS 3.5383071 1.4015276
OS 3.5435996 1.3979913
OS 3.5498425 1.3967495
OS 3.5560854 1.3979913
OS 3.5613779 1.4015276
OS 3.5649142 1.4068201
OS 3.566156 1.413063
OS 3.5649142 1.4193059
OS 3.5613779 1.4245983
OS 3.5613779 1.4295277
OS 3.5649142 1.4348201
OS 3.566156 1.441063
OS 3.5649142 1.4473059
OS 3.5613779 1.4525984
OS 3.5560854 1.4561347
OS 3.5498425 1.4573765
OE
OB 3.5717425 1.3289919 H
OS 3.5643954 1.3275305
OS 3.5581668 1.3233687
OS 3.554005 1.3171401
OS 3.5525436 1.309793
OS 3.554005 1.3024459
OS 3.5581668 1.2962173
OS 3.5643954 1.2920555
OS 3.5717425 1.2905941
OS 3.5790896 1.2920555
OS 3.5853182 1.2962173
OS 3.58948 1.3024459
OS 3.5909414 1.309793
OS 3.58948 1.3171401
OS 3.5853182 1.3233687
OS 3.5790896 1.3275305
OS 3.5717425 1.3289919
OE
OB 4.3662677 1.0459921 H
OS 4.2892441 1.0459921
OS 4.2892441 0.9689685
OS 4.3662677 0.9689685
OS 4.3662677 1.0459921
OE
OB 5.3277559 1.0463244 H
OS 5.3177023 1.0450008
OS 5.3083338 1.0411203
OS 5.300289 1.0349472
OS 5.2941159 1.0269023
OS 5.2902354 1.0175339
OS 5.2889118 1.0074803
OS 5.2902354 0.9974267
OS 5.2941159 0.9880583
OS 5.300289 0.9800134
OS 5.3083338 0.9738403
OS 5.3177023 0.9699598
OS 5.3277559 0.9686362
OS 5.3378095 0.9699598
OS 5.347178 0.9738403
OS 5.3552228 0.9800134
OS 5.3613959 0.9880583
OS 5.3652764 0.9974267
OS 5.3666 1.0074803
OS 5.3652764 1.0175339
OS 5.3613959 1.0269023
OS 5.3552228 1.0349472
OS 5.347178 1.0411203
OS 5.3378095 1.0450008
OS 5.3277559 1.0463244
OE
OB 5.1277559 1.0463244 H
OS 5.1177023 1.0450008
OS 5.1083338 1.0411203
OS 5.100289 1.0349472
OS 5.0941159 1.0269023
OS 5.0902354 1.0175339
OS 5.0889118 1.0074803
OS 5.0902354 0.9974267
OS 5.0941159 0.9880583
OS 5.100289 0.9800134
OS 5.1083338 0.9738403
OS 5.1177023 0.9699598
OS 5.1277559 0.9686362
OS 5.1378095 0.9699598
OS 5.147178 0.9738403
OS 5.1552228 0.9800134
OS 5.1613959 0.9880583
OS 5.1652764 0.9974267
OS 5.1666 1.0074803
OS 5.1652764 1.0175339
OS 5.1613959 1.0269023
OS 5.1552228 1.0349472
OS 5.147178 1.0411203
OS 5.1378095 1.0450008
OS 5.1277559 1.0463244
OE
OB 4.9277559 1.0463244 H
OS 4.9177023 1.0450008
OS 4.9083338 1.0411203
OS 4.900289 1.0349472
OS 4.8941159 1.0269023
OS 4.8902354 1.0175339
OS 4.8889118 1.0074803
OS 4.8902354 0.9974267
OS 4.8941159 0.9880583
OS 4.900289 0.9800134
OS 4.9083338 0.9738403
OS 4.9177023 0.9699598
OS 4.9277559 0.9686362
OS 4.9378095 0.9699598
OS 4.947178 0.9738403
OS 4.9552228 0.9800134
OS 4.9613959 0.9880583
OS 4.9652764 0.9974267
OS 4.9666 1.0074803
OS 4.9652764 1.0175339
OS 4.9613959 1.0269023
OS 4.9552228 1.0349472
OS 4.947178 1.0411203
OS 4.9378095 1.0450008
OS 4.9277559 1.0463244
OE
OB 3.6179425 0.9836725 H
OS 3.6047974 0.9823778
OS 3.5921575 0.9785435
OS 3.5805085 0.972317
OS 3.570298 0.9639375
OS 3.5619185 0.953727
OS 3.555692 0.942078
OS 3.5518577 0.9294381
OS 3.550563 0.916293
OS 3.5518577 0.9031479
OS 3.555692 0.890508
OS 3.5619185 0.878859
OS 3.570298 0.8686485
OS 3.5805085 0.860269
OS 3.5921575 0.8540425
OS 3.6047974 0.8502082
OS 3.6179425 0.8489135
OS 3.6310876 0.8502082
OS 3.6437275 0.8540425
OS 3.6553765 0.860269
OS 3.665587 0.8686485
OS 3.6739665 0.878859
OS 3.680193 0.890508
OS 3.6840273 0.9031479
OS 3.685322 0.916293
OS 3.6840273 0.9294381
OS 3.680193 0.942078
OS 3.6739665 0.953727
OS 3.665587 0.9639375
OS 3.6553765 0.972317
OS 3.6437275 0.9785435
OS 3.6310876 0.9823778
OS 3.6179425 0.9836725
OE
OB 5.5781524 0.9365112 H
OS 5.5662745 0.9349474
OS 5.5552061 0.9303628
OS 5.5457014 0.9230696
OS 5.5384082 0.9135649
OS 5.5338236 0.9024965
OS 5.5322598 0.8906186
OS 5.5338236 0.8787407
OS 5.5384082 0.8676723
OS 5.5457014 0.8581676
OS 5.5552061 0.8508744
OS 5.5662745 0.8462898
OS 5.5781524 0.844726
OS 5.5900303 0.8462898
OS 5.6010987 0.8508744
OS 5.6106034 0.8581676
OS 5.6178966 0.8676723
OS 5.6224812 0.8787407
OS 5.624045 0.8906186
OS 5.6224812 0.9024965
OS 5.6178966 0.9135649
OS 5.6106034 0.9230696
OS 5.6010987 0.9303628
OS 5.5900303 0.9349474
OS 5.5781524 0.9365112
OE
SE
S P 0
OB 6.2758024 3.7096816 I
OS 6.2792454 3.7046648
OS 6.278529 3.701063
OS 6.2797708 3.6948201
OS 6.2833071 3.6895276
OS 6.2885996 3.6859913
OS 6.2948425 3.6847495
OS 6.3010854 3.6859913
OS 6.3063779 3.6895276
OS 6.3099142 3.6948201
OS 6.311156 3.701063
OS 6.3104696 3.704514
OS 6.3140059 3.709497
OS 7.0248425 3.706063
OS 7.0875984 3.6433071
OS 7.0875984 1.4888189
OS 6.7798425 1.181063
OS 6.6498425 1.181063
OS 6.5898425 1.241063
OS 6.5898425 1.326063
OS 6.6215033 1.3577238
OS 6.6225996 1.3569913
OS 6.6288425 1.3557495
OS 6.6350854 1.3569913
OS 6.6403779 1.3605276
OS 6.6439142 1.3658201
OS 6.645156 1.372063
OS 6.6439142 1.3783059
OS 6.6431817 1.3794022
OS 6.9098425 1.646063
OS 6.9098425 1.991063
OS 6.8198425 2.081063
OS 6.4098425 2.081063
OS 6.3998541 2.0910514
OS 6.4013055 2.0958362
OS 6.4020854 2.0959913
OS 6.4073779 2.0995276
OS 6.4109142 2.1048201
OS 6.412156 2.111063
OS 6.4109142 2.1173059
OS 6.4073779 2.1225984
OS 6.4020854 2.1261347
OS 6.3958425 2.1273765
OS 6.3895996 2.1261347
OS 6.3843071 2.1225984
OS 6.3807708 2.1173059
OS 6.3806157 2.116526
OS 6.3758309 2.1150746
OS 6.3348425 2.156063
OS 6.3348425 2.996063
OS 5.8798425 3.451063
OS 5.8798425 3.601063
OS 5.9898425 3.711063
OS 6.2758024 3.7096816
OE
OB 6.9001969 3.6472339 H
OS 6.8852614 3.6452676
OS 6.8713437 3.6395027
OS 6.8593924 3.6303321
OS 6.8502218 3.6183808
OS 6.8444569 3.6044631
OS 6.8424906 3.5895276
OS 6.8444569 3.5745921
OS 6.8502218 3.5606744
OS 6.8593924 3.5487231
OS 6.8713437 3.5395525
OS 6.8852614 3.5337876
OS 6.9001969 3.5318213
OS 6.9151324 3.5337876
OS 6.9290501 3.5395525
OS 6.9410014 3.5487231
OS 6.950172 3.5606744
OS 6.9559369 3.5745921
OS 6.9579032 3.5895276
OS 6.9559369 3.6044631
OS 6.950172 3.6183808
OS 6.9410014 3.6303321
OS 6.9290501 3.6395027
OS 6.9151324 3.6452676
OS 6.9001969 3.6472339
OE
OB 6.7348425 3.6472339 H
OS 6.719907 3.6452676
OS 6.7059893 3.6395027
OS 6.694038 3.6303321
OS 6.6848674 3.6183808
OS 6.6791025 3.6044631
OS 6.6771362 3.5895276
OS 6.6791025 3.5745921
OS 6.6848674 3.5606744
OS 6.694038 3.5487231
OS 6.7059893 3.5395525
OS 6.719907 3.5337876
OS 6.7348425 3.5318213
OS 6.749778 3.5337876
OS 6.7636957 3.5395525
OS 6.775647 3.5487231
OS 6.7848176 3.5606744
OS 6.7905825 3.5745921
OS 6.7925488 3.5895276
OS 6.7905825 3.6044631
OS 6.7848176 3.6183808
OS 6.775647 3.6303321
OS 6.7636957 3.6395027
OS 6.749778 3.6452676
OS 6.7348425 3.6472339
OE
OB 6.5694882 3.6472339 H
OS 6.5545527 3.6452676
OS 6.540635 3.6395027
OS 6.5286837 3.6303321
OS 6.5195131 3.6183807
OS 6.5137482 3.6044631
OS 6.5117819 3.5895276
OS 6.5137482 3.5745921
OS 6.5195131 3.5606745
OS 6.5286837 3.5487231
OS 6.540635 3.5395525
OS 6.5545527 3.5337876
OS 6.5694882 3.5318213
OS 6.5844237 3.5337876
OS 6.5983414 3.5395525
OS 6.6102927 3.5487231
OS 6.6194633 3.5606745
OS 6.6252282 3.5745921
OS 6.6271945 3.5895276
OS 6.6252282 3.6044631
OS 6.6194633 3.6183807
OS 6.6102927 3.6303321
OS 6.5983414 3.6395027
OS 6.5844237 3.6452676
OS 6.5694882 3.6472339
OE
OB 6.5098425 3.4723765 H
OS 6.5035996 3.4711347
OS 6.4983071 3.4675984
OS 6.4947708 3.4623059
OS 6.493529 3.456063
OS 6.4947708 3.4498201
OS 6.4983071 3.4445276
OS 6.5035996 3.4409913
OS 6.5098425 3.4397495
OS 6.5160854 3.4409913
OS 6.5213779 3.4445276
OS 6.5249142 3.4498201
OS 6.526156 3.456063
OS 6.5249142 3.4623059
OS 6.5213779 3.4675984
OS 6.5160854 3.4711347
OS 6.5098425 3.4723765
OE
OB 6.4798425 3.4423765 H
OS 6.4735996 3.4411347
OS 6.4683071 3.4375984
OS 6.4647708 3.4323059
OS 6.463529 3.426063
OS 6.4647708 3.4198201
OS 6.4683071 3.4145276
OS 6.4735996 3.4109913
OS 6.4798425 3.4097495
OS 6.4860854 3.4109913
OS 6.4913779 3.4145276
OS 6.4949142 3.4198201
OS 6.496156 3.426063
OS 6.4949142 3.4323059
OS 6.4913779 3.4375984
OS 6.4860854 3.4411347
OS 6.4798425 3.4423765
OE
OB 6.4475772 3.4123765 H
OS 6.4413343 3.4111347
OS 6.4360418 3.4075984
OS 6.4325055 3.4023059
OS 6.4312637 3.396063
OS 6.4325055 3.3898201
OS 6.4360418 3.3845276
OS 6.4413343 3.3809913
OS 6.4475772 3.3797495
OS 6.4538201 3.3809913
OS 6.4591126 3.3845276
OS 6.4626489 3.3898201
OS 6.4638907 3.396063
OS 6.4626489 3.4023059
OS 6.4591126 3.4075984
OS 6.4538201 3.4111347
OS 6.4475772 3.4123765
OE
OB 6.4098425 3.3873765 H
OS 6.4035996 3.3861347
OS 6.3983071 3.3825984
OS 6.3947708 3.3773059
OS 6.393529 3.371063
OS 6.3947708 3.3648201
OS 6.3983071 3.3595276
OS 6.4035996 3.3559913
OS 6.4098425 3.3547495
OS 6.4160854 3.3559913
OS 6.4213779 3.3595276
OS 6.4249142 3.3648201
OS 6.426156 3.371063
OS 6.4249142 3.3773059
OS 6.4213779 3.3825984
OS 6.4160854 3.3861347
OS 6.4098425 3.3873765
OE
OB 6.6488425 3.3573765 H
OS 6.6425996 3.3561347
OS 6.6373071 3.3525984
OS 6.6337708 3.3473059
OS 6.632529 3.341063
OS 6.6337708 3.3348201
OS 6.6373071 3.3295276
OS 6.6425996 3.3259913
OS 6.6488425 3.3247495
OS 6.6550854 3.3259913
OS 6.6603779 3.3295276
OS 6.6639142 3.3348201
OS 6.665156 3.341063
OS 6.6639142 3.3473059
OS 6.6603779 3.3525984
OS 6.6550854 3.3561347
OS 6.6488425 3.3573765
OE
OB 6.3547483 3.3474519 H
OS 6.3485054 3.3462101
OS 6.3432129 3.3426738
OS 6.3396766 3.3373813
OS 6.3384348 3.3311384
OS 6.3396766 3.3248955
OS 6.3432129 3.319603
OS 6.3485054 3.3160667
OS 6.3547483 3.3148249
OS 6.3609912 3.3160667
OS 6.3662837 3.319603
OS 6.36982 3.3248955
OS 6.3710618 3.3311384
OS 6.36982 3.3373813
OS 6.3662837 3.3426738
OS 6.3609912 3.3462101
OS 6.3547483 3.3474519
OE
OB 6.4448425 3.3073765 H
OS 6.4385996 3.3061347
OS 6.4333071 3.3025984
OS 6.4297708 3.2973059
OS 6.428529 3.291063
OS 6.4297708 3.2848201
OS 6.4333071 3.2795276
OS 6.4385996 3.2759913
OS 6.4448425 3.2747495
OS 6.4510854 3.2759913
OS 6.4563779 3.2795276
OS 6.4599142 3.2848201
OS 6.461156 3.291063
OS 6.4599142 3.2973059
OS 6.4563779 3.3025984
OS 6.4510854 3.3061347
OS 6.4448425 3.3073765
OE
OB 6.3348425 3.2823765 H
OS 6.3285996 3.2811347
OS 6.3233071 3.2775984
OS 6.3197708 3.2723059
OS 6.318529 3.266063
OS 6.3197708 3.2598201
OS 6.3233071 3.2545276
OS 6.3285996 3.2509913
OS 6.3348425 3.2497495
OS 6.3410854 3.2509913
OS 6.3463779 3.2545276
OS 6.3499142 3.2598201
OS 6.351156 3.266063
OS 6.3499142 3.2723059
OS 6.3463779 3.2775984
OS 6.3410854 3.2811347
OS 6.3348425 3.2823765
OE
OB 6.4768425 3.2473765 H
OS 6.4705996 3.2461347
OS 6.4653071 3.2425984
OS 6.4617708 3.2373059
OS 6.460529 3.231063
OS 6.4617708 3.2248201
OS 6.4653071 3.2195276
OS 6.4705996 3.2159913
OS 6.4768425 3.2147495
OS 6.4830854 3.2159913
OS 6.4883779 3.2195276
OS 6.4919142 3.2248201
OS 6.493156 3.231063
OS 6.4919142 3.2373059
OS 6.4883779 3.2425984
OS 6.4830854 3.2461347
OS 6.4768425 3.2473765
OE
OB 6.2824161 3.2423765 H
OS 6.2761732 3.2411347
OS 6.2708807 3.2375984
OS 6.2673444 3.2323059
OS 6.2661026 3.226063
OS 6.2673444 3.2198201
OS 6.2708807 3.2145276
OS 6.2761732 3.2109913
OS 6.2824161 3.2097495
OS 6.288659 3.2109913
OS 6.2939515 3.2145276
OS 6.2974878 3.2198201
OS 6.2987296 3.226063
OS 6.2974878 3.2323059
OS 6.2939515 3.2375984
OS 6.288659 3.2411347
OS 6.2824161 3.2423765
OE
OB 6.3094161 3.2153765 H
OS 6.3031732 3.2141347
OS 6.2978807 3.2105984
OS 6.2943444 3.2053059
OS 6.2931026 3.199063
OS 6.2943444 3.1928201
OS 6.2978807 3.1875276
OS 6.3031732 3.1839913
OS 6.3094161 3.1827495
OS 6.315659 3.1839913
OS 6.3209515 3.1875276
OS 6.3244878 3.1928201
OS 6.3257296 3.199063
OS 6.3244878 3.2053059
OS 6.3209515 3.2105984
OS 6.315659 3.2141347
OS 6.3094161 3.2153765
OE
OB 6.4398425 3.2073765 H
OS 6.4335996 3.2061347
OS 6.4283071 3.2025984
OS 6.4247708 3.1973059
OS 6.423529 3.191063
OS 6.4247708 3.1848201
OS 6.4283071 3.1795276
OS 6.4335996 3.1759913
OS 6.4398425 3.1747495
OS 6.4460854 3.1759913
OS 6.4513779 3.1795276
OS 6.4549142 3.1848201
OS 6.456156 3.191063
OS 6.4549142 3.1973059
OS 6.4513779 3.2025984
OS 6.4460854 3.2061347
OS 6.4398425 3.2073765
OE
OB 6.3398425 3.1673765 H
OS 6.3335996 3.1661347
OS 6.3283071 3.1625984
OS 6.3247708 3.1573059
OS 6.323529 3.151063
OS 6.3247708 3.1448201
OS 6.3283071 3.1395276
OS 6.3335996 3.1359913
OS 6.3398425 3.1347495
OS 6.3460854 3.1359913
OS 6.3513779 3.1395276
OS 6.3549142 3.1448201
OS 6.356156 3.151063
OS 6.3549142 3.1573059
OS 6.3513779 3.1625984
OS 6.3460854 3.1661347
OS 6.3398425 3.1673765
OE
OB 6.6476378 3.1462348 H
OS 6.6413949 3.144993
OS 6.6361024 3.1414567
OS 6.6325661 3.1361642
OS 6.6313243 3.1299213
OS 6.6325661 3.1236784
OS 6.6361024 3.1183859
OS 6.6413949 3.1148496
OS 6.6476378 3.1136078
OS 6.6538807 3.1148496
OS 6.6591732 3.1183859
OS 6.6627095 3.1236784
OS 6.6639513 3.1299213
OS 6.6627095 3.1361642
OS 6.6591732 3.1414567
OS 6.6538807 3.144993
OS 6.6476378 3.1462348
OE
OB 6.3048425 3.1373765 H
OS 6.2985996 3.1361347
OS 6.2933071 3.1325984
OS 6.2897708 3.1273059
OS 6.288529 3.121063
OS 6.2897708 3.1148201
OS 6.2933071 3.1095276
OS 6.2985996 3.1059913
OS 6.3048425 3.1047495
OS 6.3110854 3.1059913
OS 6.3163779 3.1095276
OS 6.3199142 3.1148201
OS 6.321156 3.121063
OS 6.3199142 3.1273059
OS 6.3163779 3.1325984
OS 6.3110854 3.1361347
OS 6.3048425 3.1373765
OE
OB 6.6268425 3.0483765 H
OS 6.6205996 3.0471347
OS 6.6153071 3.0435984
OS 6.6117708 3.0383059
OS 6.610529 3.032063
OS 6.6117708 3.0258201
OS 6.6153071 3.0205276
OS 6.6205996 3.0169913
OS 6.6268425 3.0157495
OS 6.6330854 3.0169913
OS 6.6383779 3.0205276
OS 6.6419142 3.0258201
OS 6.643156 3.032063
OS 6.6419142 3.0383059
OS 6.6383779 3.0435984
OS 6.6330854 3.0471347
OS 6.6268425 3.0483765
OE
OB 6.4568425 3.0253765 H
OS 6.4505996 3.0241347
OS 6.4453071 3.0205984
OS 6.4417708 3.0153059
OS 6.440529 3.009063
OS 6.4417708 3.0028201
OS 6.4453071 2.9975276
OS 6.4505996 2.9939913
OS 6.4568425 2.9927495
OS 6.4630854 2.9939913
OS 6.4683779 2.9975276
OS 6.4719142 3.0028201
OS 6.473156 3.009063
OS 6.4719142 3.0153059
OS 6.4683779 3.0205984
OS 6.4630854 3.0241347
OS 6.4568425 3.0253765
OE
OB 6.3720472 2.9257623 H
OS 6.3658043 2.9245205
OS 6.3605118 2.9209842
OS 6.3569755 2.9156917
OS 6.3557337 2.9094488
OS 6.3569755 2.9032059
OS 6.3605118 2.8979134
OS 6.3658043 2.8943771
OS 6.3720472 2.8931353
OS 6.3782901 2.8943771
OS 6.3835826 2.8979134
OS 6.3871189 2.9032059
OS 6.3883607 2.9094488
OS 6.3871189 2.9156917
OS 6.3835826 2.9209842
OS 6.3782901 2.9245205
OS 6.3720472 2.9257623
OE
OB 6.3988425 2.6733765 H
OS 6.3925996 2.6721347
OS 6.3873071 2.6685984
OS 6.3837708 2.6633059
OS 6.382529 2.657063
OS 6.3837708 2.6508201
OS 6.3873071 2.6455276
OS 6.3925996 2.6419913
OS 6.3988425 2.6407495
OS 6.4050854 2.6419913
OS 6.4103779 2.6455276
OS 6.4139142 2.6508201
OS 6.415156 2.657063
OS 6.4139142 2.6633059
OS 6.4103779 2.6685984
OS 6.4050854 2.6721347
OS 6.3988425 2.6733765
OE
OB 6.3978425 2.6263765 H
OS 6.3915996 2.6251347
OS 6.3863071 2.6215984
OS 6.3827708 2.6163059
OS 6.381529 2.610063
OS 6.3827708 2.6038201
OS 6.3863071 2.5985276
OS 6.3915996 2.5949913
OS 6.3978425 2.5937495
OS 6.4040854 2.5949913
OS 6.4093779 2.5985276
OS 6.4129142 2.6038201
OS 6.414156 2.610063
OS 6.4129142 2.6163059
OS 6.4093779 2.6215984
OS 6.4040854 2.6251347
OS 6.3978425 2.6263765
OE
OB 6.3968425 2.5723765 H
OS 6.3905996 2.5711347
OS 6.3853071 2.5675984
OS 6.3817708 2.5623059
OS 6.380529 2.556063
OS 6.3817708 2.5498201
OS 6.3853071 2.5445276
OS 6.3905996 2.5409913
OS 6.3968425 2.5397495
OS 6.4030854 2.5409913
OS 6.4083779 2.5445276
OS 6.4119142 2.5498201
OS 6.413156 2.556063
OS 6.4119142 2.5623059
OS 6.4083779 2.5675984
OS 6.4030854 2.5711347
OS 6.3968425 2.5723765
OE
OB 6.3978425 2.5173765 H
OS 6.3915996 2.5161347
OS 6.3863071 2.5125984
OS 6.3827708 2.5073059
OS 6.381529 2.501063
OS 6.3827708 2.4948201
OS 6.3863071 2.4895276
OS 6.3915996 2.4859913
OS 6.3978425 2.4847495
OS 6.4040854 2.4859913
OS 6.4093779 2.4895276
OS 6.4129142 2.4948201
OS 6.414156 2.501063
OS 6.4129142 2.5073059
OS 6.4093779 2.5125984
OS 6.4040854 2.5161347
OS 6.3978425 2.5173765
OE
OB 6.3988425 2.4693765 H
OS 6.3925996 2.4681347
OS 6.3873071 2.4645984
OS 6.3837708 2.4593059
OS 6.382529 2.453063
OS 6.3837708 2.4468201
OS 6.3873071 2.4415276
OS 6.3925996 2.4379913
OS 6.3988425 2.4367495
OS 6.4050854 2.4379913
OS 6.4103779 2.4415276
OS 6.4139142 2.4468201
OS 6.415156 2.453063
OS 6.4139142 2.4593059
OS 6.4103779 2.4645984
OS 6.4050854 2.4681347
OS 6.3988425 2.4693765
OE
OB 6.6078425 2.1923765 H
OS 6.6015996 2.1911347
OS 6.5963071 2.1875984
OS 6.5927708 2.1823059
OS 6.591529 2.176063
OS 6.5927708 2.1698201
OS 6.5963071 2.1645276
OS 6.6015996 2.1609913
OS 6.6078425 2.1597495
OS 6.6140854 2.1609913
OS 6.6193779 2.1645276
OS 6.6229142 2.1698201
OS 6.624156 2.176063
OS 6.6229142 2.1823059
OS 6.6193779 2.1875984
OS 6.6140854 2.1911347
OS 6.6078425 2.1923765
OE
OB 6.9498425 2.1113765 H
OS 6.9435996 2.1101347
OS 6.9383071 2.1065984
OS 6.9347708 2.1013059
OS 6.933529 2.095063
OS 6.9347708 2.0888201
OS 6.9383071 2.0835276
OS 6.9435996 2.0799913
OS 6.9498425 2.0787495
OS 6.9560854 2.0799913
OS 6.9613779 2.0835276
OS 6.9649142 2.0888201
OS 6.966156 2.095063
OS 6.9649142 2.1013059
OS 6.9613779 2.1065984
OS 6.9560854 2.1101347
OS 6.9498425 2.1113765
OE
OB 6.9744094 1.9562741 H
OS 6.9681665 1.9550323
OS 6.962874 1.951496
OS 6.9593377 1.9462035
OS 6.9580959 1.9399606
OS 6.9593377 1.9337177
OS 6.962874 1.9284252
OS 6.9681665 1.9248889
OS 6.9744094 1.9236471
OS 6.9806523 1.9248889
OS 6.9859448 1.9284252
OS 6.9894811 1.9337177
OS 6.9907229 1.9399606
OS 6.9894811 1.9462035
OS 6.9859448 1.951496
OS 6.9806523 1.9550323
OS 6.9744094 1.9562741
OE
SE
S P 0
OB 6.5048425 4.151063 I
OS 6.5048425 4.1113541
OS 6.5034033 4.1066097
OS 6.5021086 4.0934646
OS 6.5034033 4.0803195
OS 6.5048425 4.0755751
OS 6.5048425 3.720276
OS 6.5012984 3.7167489
OS 6.3140453 3.7176536
OS 6.3133492 3.7175186
OS 6.3126403 3.7175386
OS 6.3118019 3.7172186
OS 6.3109209 3.7170478
OS 6.3103292 3.7166565
OS 6.3096669 3.7164038
OS 6.3090152 3.7157878
OS 6.3082661 3.7152925
OS 6.3078691 3.7147045
OS 6.307354 3.7142176
OS 6.3062605 3.7126768
OS 6.3010854 3.7161347
OS 6.2948425 3.7173765
OS 6.2885996 3.7161347
OS 6.2866976 3.7148638
OS 6.2815978 3.7154215
OS 6.2808743 3.7159099
OS 6.2802495 3.7165194
OS 6.2795679 3.7167919
OS 6.2789601 3.7172022
OS 6.2781054 3.7173765
OS 6.2772942 3.7177008
OS 6.2765603 3.7176917
OS 6.2758418 3.7178382
OS 5.9898819 3.7192196
OS 5.9898625 3.7192158
OS 5.9898425 3.7192198
OS 5.988292 3.7189113
OS 5.9867575 3.7186138
OS 5.9867407 3.7186027
OS 5.9867211 3.7185988
OS 5.9854185 3.7177285
OS 5.9841027 3.7168585
OS 5.9840914 3.7168418
OS 5.9840748 3.7168307
OS 5.8740748 3.6068307
OS 5.8723067 3.6041845
OS 5.8716857 3.601063
OS 5.8716858 3.6010625
OS 5.8716858 3.4510635
OS 5.8716857 3.451063
OS 5.8723067 3.4479416
OS 5.8740748 3.4452953
OS 5.8740751 3.4452951
OS 6.3266858 2.9926843
OS 6.3266858 2.3979063
OS 6.3048425 2.376063
OS 6.2895075 2.376063
OS 6.2874038 2.381063
OS 6.2899142 2.3848201
OS 6.291156 2.391063
OS 6.2899142 2.3973059
OS 6.2863779 2.4025984
OS 6.2810854 2.4061347
OS 6.2748425 2.4073765
OS 6.2685996 2.4061347
OS 6.2633071 2.4025984
OS 6.2597708 2.3973059
OS 6.258529 2.391063
OS 6.2597708 2.3848201
OS 6.2622812 2.381063
OS 6.2601775 2.376063
OS 4.6398425 2.376063
OS 4.3498425 2.666063
OS 4.3498425 2.7125017
OS 4.3513779 2.7135276
OS 4.3549142 2.7188201
OS 4.356156 2.725063
OS 4.3549142 2.7313059
OS 4.3513779 2.7365984
OS 4.3498425 2.7376243
OS 4.3498425 3.1334869
OS 4.350156 3.135063
OS 4.3498425 3.1366391
OS 4.3498425 3.781063
OS 4.1848425 3.946063
OS 4.0648425 3.946063
OS 3.9370776 3.8182981
OS 3.8403307 3.8182981
OS 3.8360854 3.8211347
OS 3.8298425 3.8223765
OS 3.8235996 3.8211347
OS 3.8183071 3.8175984
OS 3.8147708 3.8123059
OS 3.813529 3.806063
OS 3.8147708 3.7998201
OS 3.8183071 3.7945276
OS 3.8235996 3.7909913
OS 3.8298425 3.7897495
OS 3.8360854 3.7909913
OS 3.8403307 3.7938279
OS 3.9060745 3.7938279
OS 3.907988 3.7892085
OS 3.8048425 3.686063
OS 2.7098425 3.686063
OS 2.6959296 3.6721501
OS 2.6913778 3.6725985
OS 2.6860854 3.6761347
OS 2.6798425 3.6773765
OS 2.6735996 3.6761347
OS 2.6683071 3.6725984
OS 2.6647708 3.6673059
OS 2.663529 3.661063
OS 2.6647708 3.6548201
OS 2.668307 3.6495277
OS 2.6687554 3.6449759
OS 2.3498425 3.326063
OS 2.3498425 3.3091102
OS 2.2854055 3.3091102
OS 2.2854055 3.2490158
OS 2.3498425 3.2490158
OS 2.3498425 3.2303701
OS 2.2854055 3.2303701
OS 2.2854055 3.1702757
OS 2.3498425 3.1702757
OS 2.3498425 3.1516299
OS 2.2854055 3.1516299
OS 2.2854055 3.0915355
OS 2.3498425 3.0915355
OS 2.3498425 2.718063
OS 2.0148425 2.718063
OS 2.0148425 3.8035017
OS 2.0163779 3.8045276
OS 2.0199142 3.8098201
OS 2.021156 3.816063
OS 2.0210101 3.8167964
OS 2.0215918 3.8177387
OS 2.0253427 3.8206446
OS 2.0298425 3.8197495
OS 2.0360854 3.8209913
OS 2.0413779 3.8245276
OS 2.0449142 3.8298201
OS 2.046156 3.836063
OS 2.0449142 3.8423059
OS 2.0413779 3.8475984
OS 2.0360854 3.8511347
OS 2.0298425 3.8523765
OS 2.0235996 3.8511347
OS 2.0198425 3.8486243
OS 2.0148425 3.850728
OS 2.0148425 4.0287647
OS 2.0198425 4.0311322
OS 2.0254039 4.0268648
OS 2.0340397 4.0232878
OS 2.0433071 4.0220677
OS 2.0525745 4.0232878
OS 2.0612103 4.0268648
OS 2.068626 4.0325551
OS 2.0743163 4.0399708
OS 2.0778933 4.0486066
OS 2.0791134 4.057874
OS 2.0778933 4.0671414
OS 2.0743163 4.0757772
OS 2.068626 4.0831929
OS 2.0612103 4.0888832
OS 2.0525745 4.0924602
OS 2.0433071 4.0936803
OS 2.0340397 4.0924602
OS 2.0254039 4.0888832
OS 2.0198425 4.0846158
OS 2.0148425 4.0869833
OS 2.0148425 4.1287647
OS 2.0198425 4.1311322
OS 2.0254039 4.1268648
OS 2.0340397 4.1232878
OS 2.0433071 4.1220677
OS 2.0525745 4.1232878
OS 2.0612103 4.1268648
OS 2.068626 4.1325551
OS 2.0743163 4.1399708
OS 2.0778933 4.1486066
OS 2.0791134 4.157874
OS 2.0778933 4.1671414
OS 2.0743163 4.1757772
OS 2.068626 4.1831929
OS 2.0612103 4.1888832
OS 2.0525745 4.1924602
OS 2.0433071 4.1936803
OS 2.0340397 4.1924602
OS 2.0254039 4.1888832
OS 2.0198425 4.1846158
OS 2.0148425 4.1869833
OS 2.0148425 4.222374
OS 2.0788071 4.222374
OS 2.0788071 4.293374
OS 2.0148425 4.293374
OS 2.0148425 4.326063
OS 6.3298425 4.326063
OS 6.5048425 4.151063
OE
OB 3.3958425 4.2383765 H
OS 3.3895996 4.2371347
OS 3.3843071 4.2335984
OS 3.3807708 4.2283059
OS 3.379529 4.222063
OS 3.3807708 4.2158201
OS 3.3843071 4.2105276
OS 3.3895996 4.2069913
OS 3.3958425 4.2057495
OS 3.4020854 4.2069913
OS 3.4073779 4.2105276
OS 3.4109142 4.2158201
OS 3.412156 4.222063
OS 3.4109142 4.2283059
OS 3.4073779 4.2335984
OS 3.4020854 4.2371347
OS 3.3958425 4.2383765
OE
OB 2.8888425 4.2373765 H
OS 2.8825996 4.2361347
OS 2.8773071 4.2325984
OS 2.8737708 4.2273059
OS 2.872529 4.221063
OS 2.8737708 4.2148201
OS 2.8773071 4.2095276
OS 2.8825996 4.2059913
OS 2.8888425 4.2047495
OS 2.8950854 4.2059913
OS 2.9003779 4.2095276
OS 2.9039142 4.2148201
OS 2.905156 4.221063
OS 2.9039142 4.2273059
OS 2.9003779 4.2325984
OS 2.8950854 4.2361347
OS 2.8888425 4.2373765
OE
OB 2.2908425 4.2333765 H
OS 2.2845996 4.2321347
OS 2.2793071 4.2285984
OS 2.2757708 4.2233059
OS 2.274529 4.217063
OS 2.2757708 4.2108201
OS 2.2793071 4.2055276
OS 2.2845996 4.2019913
OS 2.2908425 4.2007495
OS 2.2970854 4.2019913
OS 2.3023779 4.2055276
OS 2.3059142 4.2108201
OS 2.307156 4.217063
OS 2.3059142 4.2233059
OS 2.3023779 4.2285984
OS 2.2970854 4.2321347
OS 2.2908425 4.2333765
OE
OB 4.3878425 4.2223765 H
OS 4.3815996 4.2211347
OS 4.3763071 4.2175984
OS 4.3727708 4.2123059
OS 4.371529 4.206063
OS 4.3727708 4.1998201
OS 4.3763071 4.1945276
OS 4.3815996 4.1909913
OS 4.3878425 4.1897495
OS 4.3940854 4.1909913
OS 4.3993779 4.1945276
OS 4.4029142 4.1998201
OS 4.404156 4.206063
OS 4.4029142 4.2123059
OS 4.3993779 4.2175984
OS 4.3940854 4.2211347
OS 4.3878425 4.2223765
OE
OB 4.9108425 4.2193765 H
OS 4.9045996 4.2181347
OS 4.8993071 4.2145984
OS 4.8957708 4.2093059
OS 4.894529 4.203063
OS 4.8957708 4.1968201
OS 4.8993071 4.1915276
OS 4.9045996 4.1879913
OS 4.9108425 4.1867495
OS 4.9170854 4.1879913
OS 4.9223779 4.1915276
OS 4.9259142 4.1968201
OS 4.927156 4.203063
OS 4.9259142 4.2093059
OS 4.9223779 4.2145984
OS 4.9170854 4.2181347
OS 4.9108425 4.2193765
OE
OB 3.9580709 4.1520014 H
OS 3.9513575 4.1511176
OS 3.9451017 4.1485263
OS 3.9397297 4.1444042
OS 3.9356076 4.1390322
OS 3.9330163 4.1327764
OS 3.9321325 4.126063
OS 3.9330163 4.1193496
OS 3.9356076 4.1130938
OS 3.9397297 4.1077218
OS 3.9451017 4.1035997
OS 3.9513575 4.1010084
OS 3.9580709 4.1001246
OS 3.9647843 4.1010084
OS 3.9710401 4.1035997
OS 3.9764121 4.1077218
OS 3.9805342 4.1130938
OS 3.9831255 4.1193496
OS 3.9840093 4.126063
OS 3.9831255 4.1327764
OS 3.9805342 4.1390322
OS 3.9764121 4.1444042
OS 3.9710401 4.1485263
OS 3.9647843 4.1511176
OS 3.9580709 4.1520014
OE
OB 3.7848425 4.1520014 H
OS 3.7781291 4.1511176
OS 3.7718733 4.1485263
OS 3.7665013 4.1444042
OS 3.7623792 4.1390322
OS 3.7597879 4.1327764
OS 3.7589041 4.126063
OS 3.7597879 4.1193496
OS 3.7623792 4.1130938
OS 3.7665013 4.1077218
OS 3.7718733 4.1035997
OS 3.7781291 4.1010084
OS 3.7848425 4.1001246
OS 3.7915559 4.1010084
OS 3.7978117 4.1035997
OS 3.8031837 4.1077218
OS 3.8073058 4.1130938
OS 3.8098971 4.1193496
OS 3.8107809 4.126063
OS 3.8098971 4.1327764
OS 3.8073058 4.1390322
OS 3.8031837 4.1444042
OS 3.7978117 4.1485263
OS 3.7915559 4.1511176
OS 3.7848425 4.1520014
OE
OB 4.7547119 4.1322459 H
OS 4.748469 4.1310041
OS 4.7431765 4.1274678
OS 4.7396402 4.1221753
OS 4.7383984 4.1159324
OS 4.7396402 4.1096895
OS 4.7431765 4.104397
OS 4.748469 4.1008607
OS 4.7547119 4.0996189
OS 4.7609548 4.1008607
OS 4.7662473 4.104397
OS 4.7697836 4.1096895
OS 4.7710254 4.1159324
OS 4.7697836 4.1221753
OS 4.7662473 4.1274678
OS 4.7609548 4.1310041
OS 4.7547119 4.1322459
OE
OB 2.1460663 4.1201044 H
OS 2.1398234 4.1188626
OS 2.1345309 4.1153263
OS 2.1309946 4.1100338
OS 2.1297528 4.1037909
OS 2.1309946 4.097548
OS 2.1345309 4.0922555
OS 2.1398234 4.0887192
OS 2.1460663 4.0874774
OS 2.1523092 4.0887192
OS 2.1576017 4.0922555
OS 2.161138 4.097548
OS 2.1623798 4.1037909
OS 2.161138 4.1100338
OS 2.1576017 4.1153263
OS 2.1523092 4.1188626
OS 2.1460663 4.1201044
OE
OB 5.2670079 4.1052111 H
OS 5.260765 4.1039693
OS 5.2554725 4.100433
OS 5.2519362 4.0951405
OS 5.2506944 4.0888976
OS 5.2519362 4.0826547
OS 5.2554725 4.0773622
OS 5.260765 4.0738259
OS 5.2670079 4.0725841
OS 5.2732508 4.0738259
OS 5.2785433 4.0773622
OS 5.2820796 4.0826547
OS 5.2833214 4.0888976
OS 5.2820796 4.0951405
OS 5.2785433 4.100433
OS 5.2732508 4.1039693
OS 5.2670079 4.1052111
OE
OB 2.253937 4.1029277 H
OS 2.2476941 4.1016859
OS 2.2424016 4.0981496
OS 2.2388653 4.0928571
OS 2.2376235 4.0866142
OS 2.2388653 4.0803713
OS 2.2424016 4.0750788
OS 2.2476941 4.0715425
OS 2.253937 4.0703007
OS 2.2601799 4.0715425
OS 2.2654724 4.0750788
OS 2.2690087 4.0803713
OS 2.2702505 4.0866142
OS 2.2690087 4.0928571
OS 2.2654724 4.0981496
OS 2.2601799 4.1016859
OS 2.253937 4.1029277
OE
OB 3.5048425 4.1023765 H
OS 3.4985996 4.1011347
OS 3.4933071 4.0975984
OS 3.4897708 4.0923059
OS 3.488529 4.086063
OS 3.4897708 4.0798201
OS 3.4933071 4.0745276
OS 3.4985996 4.0709913
OS 3.5048425 4.0697495
OS 3.5110854 4.0709913
OS 3.5163779 4.0745276
OS 3.5199142 4.0798201
OS 3.521156 4.086063
OS 3.5199142 4.0923059
OS 3.5163779 4.0975984
OS 3.5110854 4.1011347
OS 3.5048425 4.1023765
OE
OB 3.2948425 4.1274482 H
OS 3.2841414 4.1260394
OS 3.2741696 4.1219089
OS 3.2656066 4.1153383
OS 3.259036 4.1067753
OS 3.2549055 4.0968035
OS 3.2534967 4.0861024
OS 3.2549055 4.0754013
OS 3.259036 4.0654295
OS 3.2656066 4.0568665
OS 3.2741696 4.0502959
OS 3.2841414 4.0461654
OS 3.2948425 4.0447566
OS 3.3055436 4.0461654
OS 3.3155154 4.0502959
OS 3.3240784 4.0568665
OS 3.330649 4.0654295
OS 3.3347795 4.0754013
OS 3.3361883 4.0861024
OS 3.3347795 4.0968035
OS 3.330649 4.1067753
OS 3.3240784 4.1153383
OS 3.3155154 4.1219089
OS 3.3055436 4.1260394
OS 3.2948425 4.1274482
OE
OB 2.9948425 4.1274482 H
OS 2.9841414 4.1260394
OS 2.9741696 4.1219089
OS 2.9656066 4.1153383
OS 2.959036 4.1067753
OS 2.9549055 4.0968035
OS 2.9534967 4.0861024
OS 2.9549055 4.0754013
OS 2.959036 4.0654295
OS 2.9656066 4.0568665
OS 2.9741696 4.0502959
OS 2.9841414 4.0461654
OS 2.9948425 4.0447566
OS 3.0055436 4.0461654
OS 3.0155154 4.0502959
OS 3.0240784 4.0568665
OS 3.030649 4.0654295
OS 3.0347795 4.0754013
OS 3.0361883 4.0861024
OS 3.0347795 4.0968035
OS 3.030649 4.1067753
OS 3.0240784 4.1153383
OS 3.0155154 4.1219089
OS 3.0055436 4.1260394
OS 2.9948425 4.1274482
OE
OB 3.7778425 4.0393765 H
OS 3.7715996 4.0381347
OS 3.7663071 4.0345984
OS 3.7627708 4.0293059
OS 3.761529 4.023063
OS 3.7627708 4.0168201
OS 3.7663071 4.0115276
OS 3.7715996 4.0079913
OS 3.7778425 4.0067495
OS 3.7840854 4.0079913
OS 3.7893779 4.0115276
OS 3.7929142 4.0168201
OS 3.794156 4.023063
OS 3.7929142 4.0293059
OS 3.7893779 4.0345984
OS 3.7840854 4.0381347
OS 3.7778425 4.0393765
OE
OB 6.1641339 4.1088055 H
OS 6.0755511 4.1088055
OS 6.0619003 4.1070083
OS 6.0491799 4.1017393
OS 6.0382565 4.0933576
OS 6.0298748 4.0824342
OS 6.0246058 4.0697138
OS 6.0228086 4.056063
OS 6.0246058 4.0424122
OS 6.0298748 4.0296918
OS 6.0382565 4.0187684
OS 6.0491799 4.0103867
OS 6.0619003 4.0051177
OS 6.0755511 4.0033205
OS 6.1641339 4.0033205
OS 6.1777847 4.0051177
OS 6.1905051 4.0103867
OS 6.2014285 4.0187684
OS 6.2098102 4.0296918
OS 6.2150792 4.0424122
OS 6.2168764 4.056063
OS 6.2150792 4.0697138
OS 6.2098102 4.0824342
OS 6.2014285 4.0933576
OS 6.1905051 4.1017393
OS 6.1777847 4.1070083
OS 6.1641339 4.1088055
OE
OB 2.3533464 4.03403 H
OS 2.3471035 4.0327882
OS 2.341811 4.0292519
OS 2.3382747 4.0239594
OS 2.3370329 4.0177165
OS 2.3382747 4.0114736
OS 2.341811 4.0061811
OS 2.3471035 4.0026448
OS 2.3533464 4.001403
OS 2.3595893 4.0026448
OS 2.3648818 4.0061811
OS 2.3684181 4.0114736
OS 2.3696599 4.0177165
OS 2.3684181 4.0239594
OS 2.3648818 4.0292519
OS 2.3595893 4.0327882
OS 2.3533464 4.03403
OE
OB 5.7234252 4.0832969 H
OS 5.7084897 4.0813306
OS 5.6945721 4.0755657
OS 5.6826207 4.0663951
OS 5.6734501 4.0544438
OS 5.6676852 4.0405261
OS 5.6657189 4.0255906
OS 5.6676852 4.0106551
OS 5.6734501 3.9967374
OS 5.6826207 3.9847861
OS 5.6945721 3.9756155
OS 5.7084897 3.9698506
OS 5.7234252 3.9678843
OS 5.7383607 3.9698506
OS 5.7522783 3.9756155
OS 5.7642297 3.9847861
OS 5.7734003 3.9967374
OS 5.7791652 4.0106551
OS 5.7811315 4.0255906
OS 5.7791652 4.0405261
OS 5.7734003 4.0544438
OS 5.7642297 4.0663951
OS 5.7522783 4.0755657
OS 5.7383607 4.0813306
OS 5.7234252 4.0832969
OE
OB 2.0848425 3.9123765 H
OS 2.0785996 3.9111347
OS 2.0733071 3.9075984
OS 2.0697708 3.9023059
OS 2.068529 3.896063
OS 2.0697708 3.8898201
OS 2.0699331 3.8895773
OS 2.0663282 3.8859724
OS 2.0660854 3.8861347
OS 2.0598425 3.8873765
OS 2.0535996 3.8861347
OS 2.0483071 3.8825984
OS 2.0447708 3.8773059
OS 2.043529 3.871063
OS 2.0447708 3.8648201
OS 2.0483071 3.8595276
OS 2.0535996 3.8559913
OS 2.0598425 3.8547495
OS 2.0660854 3.8559913
OS 2.0713779 3.8595276
OS 2.0749142 3.8648201
OS 2.076156 3.871063
OS 2.0749142 3.8773059
OS 2.0747519 3.8775487
OS 2.0783568 3.8811536
OS 2.0785996 3.8809913
OS 2.0848425 3.8797495
OS 2.0910854 3.8809913
OS 2.0963779 3.8845276
OS 2.0999142 3.8898201
OS 2.101156 3.896063
OS 2.0999142 3.9023059
OS 2.0963779 3.9075984
OS 2.0910854 3.9111347
OS 2.0848425 3.9123765
OE
OB 5.9348031 4.0349866 H
OS 5.9211523 4.0331894
OS 5.9084318 4.0279204
OS 5.8975085 4.0195387
OS 5.8891268 4.0086153
OS 5.8838578 3.9958949
OS 5.8820606 3.9822441
OS 5.8820606 3.8936613
OS 5.8838578 3.8800105
OS 5.8891268 3.8672901
OS 5.8975085 3.8563667
OS 5.9084318 3.847985
OS 5.9211523 3.842716
OS 5.9348031 3.8409188
OS 5.9484539 3.842716
OS 5.9611744 3.847985
OS 5.9720977 3.8563667
OS 5.9804794 3.8672901
OS 5.9857484 3.8800105
OS 5.9875456 3.8936613
OS 5.9875456 3.9822441
OS 5.9857484 3.9958949
OS 5.9804794 4.0086153
OS 5.9720977 4.0195387
OS 5.9611744 4.0279204
OS 5.9484539 4.0331894
OS 5.9348031 4.0349866
OE
OB 3.6998425 3.8523765 H
OS 3.6935996 3.8511347
OS 3.6883071 3.8475984
OS 3.6847708 3.8423059
OS 3.683529 3.836063
OS 3.6847708 3.8298201
OS 3.6883071 3.8245276
OS 3.6935996 3.8209913
OS 3.6998425 3.8197495
OS 3.7060854 3.8209913
OS 3.7113779 3.8245276
OS 3.7149142 3.8298201
OS 3.716156 3.836063
OS 3.7149142 3.8423059
OS 3.7113779 3.8475984
OS 3.7060854 3.8511347
OS 3.6998425 3.8523765
OE
OB 3.0148425 3.8473765 H
OS 3.0085996 3.8461347
OS 3.0033071 3.8425984
OS 2.9997708 3.8373059
OS 2.998529 3.831063
OS 2.9997708 3.8248201
OS 3.0033071 3.8195276
OS 3.0085996 3.8159913
OS 3.0148425 3.8147495
OS 3.0210854 3.8159913
OS 3.0263779 3.8195276
OS 3.0299142 3.8248201
OS 3.031156 3.831063
OS 3.0299142 3.8373059
OS 3.0263779 3.8425984
OS 3.0210854 3.8461347
OS 3.0148425 3.8473765
OE
OB 5.7234252 3.9021945 H
OS 5.7084897 3.9002282
OS 5.6945721 3.8944633
OS 5.6826207 3.8852927
OS 5.6734501 3.8733414
OS 5.6676852 3.8594237
OS 5.6657189 3.8444882
OS 5.6676852 3.8295527
OS 5.6734501 3.815635
OS 5.6826207 3.8036837
OS 5.6945721 3.7945131
OS 5.7084897 3.7887482
OS 5.7234252 3.7867819
OS 5.7383607 3.7887482
OS 5.7522783 3.7945131
OS 5.7642297 3.8036837
OS 5.7734003 3.815635
OS 5.7791652 3.8295527
OS 5.7811315 3.8444882
OS 5.7791652 3.8594237
OS 5.7734003 3.8733414
OS 5.7642297 3.8852927
OS 5.7522783 3.8944633
OS 5.7383607 3.9002282
OS 5.7234252 3.9021945
OE
OB 3.2698425 3.8043765 H
OS 3.2635996 3.8031347
OS 3.2583071 3.7995984
OS 3.2547708 3.7943059
OS 3.253529 3.788063
OS 3.2547708 3.7818201
OS 3.2583071 3.7765276
OS 3.2635996 3.7729913
OS 3.2698425 3.7717495
OS 3.2760854 3.7729913
OS 3.2813779 3.7765276
OS 3.2849142 3.7818201
OS 3.286156 3.788063
OS 3.2849142 3.7943059
OS 3.2813779 3.7995984
OS 3.2760854 3.8031347
OS 3.2698425 3.8043765
OE
OB 2.8608425 3.8033765 H
OS 2.8545996 3.8021347
OS 2.8493071 3.7985984
OS 2.8457708 3.7933059
OS 2.844529 3.787063
OS 2.8457708 3.7808201
OS 2.8493071 3.7755276
OS 2.8545996 3.7719913
OS 2.8608425 3.7707495
OS 2.8670854 3.7719913
OS 2.8723779 3.7755276
OS 2.8759142 3.7808201
OS 2.877156 3.787063
OS 2.8759142 3.7933059
OS 2.8723779 3.7985984
OS 2.8670854 3.8021347
OS 2.8608425 3.8033765
OE
OB 6.1690551 3.8775488 H
OS 6.0706299 3.8775488
OS 6.0556944 3.8755825
OS 6.0417767 3.8698176
OS 6.0298254 3.860647
OS 6.0206548 3.8486956
OS 6.0148899 3.834778
OS 6.0129236 3.8198425
OS 6.0148899 3.804907
OS 6.0206548 3.7909894
OS 6.0298254 3.779038
OS 6.0417767 3.7698674
OS 6.0556944 3.7641025
OS 6.0706299 3.7621362
OS 6.1690551 3.7621362
OS 6.1839906 3.7641025
OS 6.1979083 3.7698674
OS 6.2098596 3.779038
OS 6.2190302 3.7909894
OS 6.2247951 3.804907
OS 6.2267614 3.8198425
OS 6.2247951 3.834778
OS 6.2190302 3.8486956
OS 6.2098596 3.860647
OS 6.1979083 3.8698176
OS 6.1839906 3.8755825
OS 6.1690551 3.8775488
OE
OB 3.8308425 3.7783765 H
OS 3.8245996 3.7771347
OS 3.8193071 3.7735984
OS 3.8157708 3.7683059
OS 3.814529 3.762063
OS 3.8157708 3.7558201
OS 3.8193071 3.7505276
OS 3.8245996 3.7469913
OS 3.8308425 3.7457495
OS 3.8370854 3.7469913
OS 3.8423779 3.7505276
OS 3.8459142 3.7558201
OS 3.847156 3.762063
OS 3.8459142 3.7683059
OS 3.8423779 3.7735984
OS 3.8370854 3.7771347
OS 3.8308425 3.7783765
OE
OB 2.531398 3.962003 H
OS 2.5144508 3.9606692
OS 2.497921 3.9567008
OS 2.4822154 3.9501953
OS 2.4677209 3.941313
OS 2.4547943 3.9302727
OS 2.443754 3.9173461
OS 2.4348717 3.9028516
OS 2.4283662 3.887146
OS 2.4243978 3.8706162
OS 2.423064 3.853669
OS 2.4243978 3.8367218
OS 2.4283662 3.820192
OS 2.4348717 3.8044864
OS 2.443754 3.7899919
OS 2.4547943 3.7770653
OS 2.4677209 3.766025
OS 2.4822154 3.7571427
OS 2.497921 3.7506372
OS 2.5144508 3.7466688
OS 2.531398 3.745335
OS 2.5483452 3.7466688
OS 2.564875 3.7506372
OS 2.5805806 3.7571427
OS 2.5950751 3.766025
OS 2.6080017 3.7770653
OS 2.619042 3.7899919
OS 2.6279243 3.8044864
OS 2.6344298 3.820192
OS 2.6383982 3.8367218
OS 2.639732 3.853669
OS 2.6383982 3.8706162
OS 2.6344298 3.887146
OS 2.6279243 3.9028516
OS 2.619042 3.9173461
OS 2.6080017 3.9302727
OS 2.5950751 3.941313
OS 2.5805806 3.9501953
OS 2.564875 3.9567008
OS 2.5483452 3.9606692
OS 2.531398 3.962003
OE
OB 3.6998425 3.7673765 H
OS 3.6935996 3.7661347
OS 3.6883071 3.7625984
OS 3.6847708 3.7573059
OS 3.683529 3.751063
OS 3.6847708 3.7448201
OS 3.6883071 3.7395276
OS 3.6935996 3.7359913
OS 3.6998425 3.7347495
OS 3.7060854 3.7359913
OS 3.7113779 3.7395276
OS 3.7149142 3.7448201
OS 3.716156 3.751063
OS 3.7149142 3.7573059
OS 3.7113779 3.7625984
OS 3.7060854 3.7661347
OS 3.6998425 3.7673765
OE
OB 2.9933858 3.7673765 H
OS 2.9871429 3.7661347
OS 2.9818504 3.7625984
OS 2.9783141 3.7573059
OS 2.9770723 3.751063
OS 2.9783141 3.7448201
OS 2.9818504 3.7395276
OS 2.9871429 3.7359913
OS 2.9933858 3.7347495
OS 2.9996287 3.7359913
OS 3.0049212 3.7395276
OS 3.0084575 3.7448201
OS 3.0096993 3.751063
OS 3.0084575 3.7573059
OS 3.0049212 3.7625984
OS 2.9996287 3.7661347
OS 2.9933858 3.7673765
OE
OB 2.2588425 3.7573765 H
OS 2.2525996 3.7561347
OS 2.2473071 3.7525984
OS 2.2437708 3.7473059
OS 2.242529 3.741063
OS 2.2437708 3.7348201
OS 2.2473071 3.7295276
OS 2.2525996 3.7259913
OS 2.2588425 3.7247495
OS 2.2650854 3.7259913
OS 2.2703779 3.7295276
OS 2.2739142 3.7348201
OS 2.275156 3.741063
OS 2.2739142 3.7473059
OS 2.2703779 3.7525984
OS 2.2650854 3.7561347
OS 2.2588425 3.7573765
OE
OB 2.1398425 3.7543765 H
OS 2.1335996 3.7531347
OS 2.1283071 3.7495984
OS 2.1247708 3.7443059
OS 2.123529 3.738063
OS 2.1247708 3.7318201
OS 2.1283071 3.7265276
OS 2.1335996 3.7229913
OS 2.1398425 3.7217495
OS 2.1460854 3.7229913
OS 2.1513779 3.7265276
OS 2.1549142 3.7318201
OS 2.156156 3.738063
OS 2.1549142 3.7443059
OS 2.1513779 3.7495984
OS 2.1460854 3.7531347
OS 2.1398425 3.7543765
OE
OB 2.7248425 3.7453765 H
OS 2.7185996 3.7441347
OS 2.7133071 3.7405984
OS 2.7097708 3.7353059
OS 2.708529 3.729063
OS 2.7097708 3.7228201
OS 2.7133071 3.7175276
OS 2.7185996 3.7139913
OS 2.7248425 3.7127495
OS 2.7310854 3.7139913
OS 2.7363779 3.7175276
OS 2.7399142 3.7228201
OS 2.741156 3.729063
OS 2.7399142 3.7353059
OS 2.7363779 3.7405984
OS 2.7310854 3.7441347
OS 2.7248425 3.7453765
OE
OB 2.4223425 3.6247884 H
OS 2.4133837 3.6230064
OS 2.4057888 3.6179317
OS 2.4007141 3.6103368
OS 2.3989321 3.601378
OS 2.4007141 3.5924192
OS 2.4057888 3.5848243
OS 2.4133837 3.5797496
OS 2.4223425 3.5779676
OS 2.4313013 3.5797496
OS 2.4388962 3.5848243
OS 2.4439709 3.5924192
OS 2.4457529 3.601378
OS 2.4439709 3.6103368
OS 2.4388962 3.6179317
OS 2.4313013 3.6230064
OS 2.4223425 3.6247884
OE
OB 5.7338425 3.5723765 H
OS 5.7275996 3.5711347
OS 5.7223071 3.5675984
OS 5.7187708 3.5623059
OS 5.717529 3.556063
OS 5.7187708 3.5498201
OS 5.7223071 3.5445276
OS 5.7275996 3.5409913
OS 5.7338425 3.5397495
OS 5.7400854 3.5409913
OS 5.7453779 3.5445276
OS 5.7489142 3.5498201
OS 5.750156 3.556063
OS 5.7489142 3.5623059
OS 5.7453779 3.5675984
OS 5.7400854 3.5711347
OS 5.7338425 3.5723765
OE
OB 5.6768425 3.5623765 H
OS 5.6705996 3.5611347
OS 5.6653071 3.5575984
OS 5.6617708 3.5523059
OS 5.660529 3.546063
OS 5.6617708 3.5398201
OS 5.6653071 3.5345276
OS 5.6705996 3.5309913
OS 5.6768425 3.5297495
OS 5.6830854 3.5309913
OS 5.6883779 3.5345276
OS 5.6919142 3.5398201
OS 5.693156 3.546063
OS 5.6919142 3.5523059
OS 5.6883779 3.5575984
OS 5.6830854 3.5611347
OS 5.6768425 3.5623765
OE
OB 2.4348425 3.5623765 H
OS 2.4285996 3.5611347
OS 2.4233071 3.5575984
OS 2.4197708 3.5523059
OS 2.418529 3.546063
OS 2.4197708 3.5398201
OS 2.4233071 3.5345276
OS 2.4285996 3.5309913
OS 2.4348425 3.5297495
OS 2.4410854 3.5309913
OS 2.4463779 3.5345276
OS 2.4499142 3.5398201
OS 2.451156 3.546063
OS 2.4499142 3.5523059
OS 2.4463779 3.5575984
OS 2.4410854 3.5611347
OS 2.4348425 3.5623765
OE
OB 2.2548425 3.5523765 H
OS 2.2485996 3.5511347
OS 2.2433071 3.5475984
OS 2.2397708 3.5423059
OS 2.238529 3.536063
OS 2.2397708 3.5298201
OS 2.2424883 3.5257531
OS 2.2396399 3.5214222
OS 2.2348425 3.5223765
OS 2.2285996 3.5211347
OS 2.2233071 3.5175984
OS 2.2197708 3.5123059
OS 2.218529 3.506063
OS 2.2197708 3.4998201
OS 2.2233071 3.4945276
OS 2.2285996 3.4909913
OS 2.2348425 3.4897495
OS 2.2410854 3.4909913
OS 2.2463779 3.4945276
OS 2.2499142 3.4998201
OS 2.251156 3.506063
OS 2.2499142 3.5123059
OS 2.2471967 3.5163729
OS 2.2500451 3.5207038
OS 2.2548425 3.5197495
OS 2.2610854 3.5209913
OS 2.2663779 3.5245276
OS 2.2699142 3.5298201
OS 2.271156 3.536063
OS 2.2699142 3.5423059
OS 2.2663779 3.5475984
OS 2.2610854 3.5511347
OS 2.2548425 3.5523765
OE
OB 2.3898425 3.4973765 H
OS 2.3835996 3.4961347
OS 2.3783071 3.4925984
OS 2.3747708 3.4873059
OS 2.373529 3.481063
OS 2.3747708 3.4748201
OS 2.3783071 3.4695276
OS 2.3835996 3.4659913
OS 2.3898425 3.4647495
OS 2.3960854 3.4659913
OS 2.4013779 3.4695276
OS 2.4049142 3.4748201
OS 2.406156 3.481063
OS 2.4049142 3.4873059
OS 2.4013779 3.4925984
OS 2.3960854 3.4961347
OS 2.3898425 3.4973765
OE
OB 2.4223425 3.4673081 H
OS 2.4133837 3.4655261
OS 2.4057888 3.4604514
OS 2.4007141 3.4528565
OS 2.3989321 3.4438977
OS 2.4007141 3.4349389
OS 2.4057888 3.427344
OS 2.4133837 3.4222693
OS 2.4223425 3.4204873
OS 2.4313013 3.4222693
OS 2.4388962 3.427344
OS 2.4439709 3.4349389
OS 2.4457529 3.4438977
OS 2.4439709 3.4528565
OS 2.4388962 3.4604514
OS 2.4313013 3.4655261
OS 2.4223425 3.4673081
OE
OB 2.3215354 3.3773765 H
OS 2.3152925 3.3761347
OS 2.31 3.3725984
OS 2.3064637 3.3673059
OS 2.3052219 3.361063
OS 2.3064637 3.3548201
OS 2.31 3.3495276
OS 2.3152925 3.3459913
OS 2.3215354 3.3447495
OS 2.3277783 3.3459913
OS 2.3330708 3.3495276
OS 2.3366071 3.3548201
OS 2.3378489 3.361063
OS 2.3366071 3.3673059
OS 2.3330708 3.3725984
OS 2.3277783 3.3761347
OS 2.3215354 3.3773765
OE
OB 2.2598425 3.2773765 H
OS 2.2535996 3.2761347
OS 2.2483071 3.2725984
OS 2.2447708 3.2673059
OS 2.243529 3.261063
OS 2.2447708 3.2548201
OS 2.2483071 3.2495276
OS 2.2535996 3.2459913
OS 2.2598425 3.2447495
OS 2.2660854 3.2459913
OS 2.2713779 3.2495276
OS 2.2749142 3.2548201
OS 2.276156 3.261063
OS 2.2749142 3.2673059
OS 2.2713779 3.2725984
OS 2.2660854 3.2761347
OS 2.2598425 3.2773765
OE
OB 2.2058425 3.2163765 H
OS 2.1995996 3.2151347
OS 2.1943071 3.2115984
OS 2.1907708 3.2063059
OS 2.189529 3.200063
OS 2.1907708 3.1938201
OS 2.1943071 3.1885276
OS 2.1995996 3.1849913
OS 2.2058425 3.1837495
OS 2.2120854 3.1849913
OS 2.2173779 3.1885276
OS 2.2209142 3.1938201
OS 2.222156 3.200063
OS 2.2209142 3.2063059
OS 2.2173779 3.2115984
OS 2.2120854 3.2151347
OS 2.2058425 3.2163765
OE
OB 4.4778425 3.1513765 H
OS 4.4715996 3.1501347
OS 4.4663071 3.1465984
OS 4.4627708 3.1413059
OS 4.461529 3.135063
OS 4.4627708 3.1288201
OS 4.4663071 3.1235276
OS 4.4715996 3.1199913
OS 4.4778425 3.1187495
OS 4.4840854 3.1199913
OS 4.4893779 3.1235276
OS 4.4929142 3.1288201
OS 4.494156 3.135063
OS 4.4929142 3.1413059
OS 4.4893779 3.1465984
OS 4.4840854 3.1501347
OS 4.4778425 3.1513765
OE
OB 4.4318425 3.1513765 H
OS 4.4255996 3.1501347
OS 4.4203071 3.1465984
OS 4.4167708 3.1413059
OS 4.415529 3.135063
OS 4.4167708 3.1288201
OS 4.4203071 3.1235276
OS 4.4255996 3.1199913
OS 4.4318425 3.1187495
OS 4.4380854 3.1199913
OS 4.4433779 3.1235276
OS 4.4469142 3.1288201
OS 4.448156 3.135063
OS 4.4469142 3.1413059
OS 4.4433779 3.1465984
OS 4.4380854 3.1501347
OS 4.4318425 3.1513765
OE
OB 6.253937 2.9257623 H
OS 6.2476941 2.9245205
OS 6.2424016 2.9209842
OS 6.2388653 2.9156917
OS 6.2376235 2.9094488
OS 6.2388653 2.9032059
OS 6.2424016 2.8979134
OS 6.2476941 2.8943771
OS 6.253937 2.8931353
OS 6.2601799 2.8943771
OS 6.2654724 2.8979134
OS 6.2690087 2.9032059
OS 6.2702505 2.9094488
OS 6.2690087 2.9156917
OS 6.2654724 2.9209842
OS 6.2601799 2.9245205
OS 6.253937 2.9257623
OE
OB 4.7942913 2.8243844 H
OS 4.7880484 2.8231426
OS 4.7827559 2.8196063
OS 4.7792196 2.8143138
OS 4.7779778 2.8080709
OS 4.7792196 2.801828
OS 4.7827559 2.7965355
OS 4.7880484 2.7929992
OS 4.7942913 2.7917574
OS 4.8005342 2.7929992
OS 4.8058267 2.7965355
OS 4.809363 2.801828
OS 4.8106048 2.8080709
OS 4.809363 2.8143138
OS 4.8058267 2.8196063
OS 4.8005342 2.8231426
OS 4.7942913 2.8243844
OE
OB 5.5781524 2.5349364 H
OS 5.5662745 2.5333726
OS 5.5552061 2.528788
OS 5.5457014 2.5214948
OS 5.5384082 2.5119901
OS 5.5338236 2.5009217
OS 5.5322598 2.4890438
OS 5.5338236 2.4771659
OS 5.5384082 2.4660975
OS 5.5457014 2.4565928
OS 5.5552061 2.4492996
OS 5.5662745 2.444715
OS 5.5781524 2.4431512
OS 5.5900303 2.444715
OS 5.6010987 2.4492996
OS 5.6106034 2.4565928
OS 5.6178966 2.4660975
OS 5.6224812 2.4771659
OS 5.624045 2.4890438
OS 5.6224812 2.5009217
OS 5.6178966 2.5119901
OS 5.6106034 2.5214948
OS 5.6010987 2.528788
OS 5.5900303 2.5333726
OS 5.5781524 2.5349364
OE
OB 6.0048425 2.4503765 H
OS 5.9985996 2.4491347
OS 5.9933071 2.4455984
OS 5.9897708 2.4403059
OS 5.988529 2.434063
OS 5.9897708 2.4278201
OS 5.9933071 2.4225276
OS 5.9985996 2.4189913
OS 6.0048425 2.4177495
OS 6.0110854 2.4189913
OS 6.0163779 2.4225276
OS 6.0199142 2.4278201
OS 6.021156 2.434063
OS 6.0199142 2.4403059
OS 6.0163779 2.4455984
OS 6.0110854 2.4491347
OS 6.0048425 2.4503765
OE
SE
P 0.149508 2.830047 31 P 0 0 ;0=24,1=1
P 0.149508 3.853669 31 P 0 0 ;0=24,1=1
P 0.6538425 1.551063 30 P 0 0 ;0=23,1=1
P 0.6539669 2.5938902 30 P 0 0 ;0=23,1=1
P 0.6548425 0.790063 30 P 0 0 ;0=23,1=1
P 0.6548425 1.314063 30 P 0 0 ;0=23,1=1
P 0.6548425 1.839063 30 P 0 0 ;0=23,1=1
P 0.6548425 2.073063 30 P 0 0 ;0=23,1=1
P 0.6548425 2.365063 30 P 0 0 ;0=23,1=1
P 0.6558425 1.028063 30 P 0 0 ;0=23,1=1
P 0.9370078 2.3179133 30 P 0 0 ;0=23,1=1
P 0.988189 1.7175197 30 P 0 0 ;0=23,1=1
P 0.9901575 0.6870079 30 P 0 0 ;0=23,1=1
P 0.996063 1.1870079 30 P 0 0 ;0=23,1=1
P 0.9968357 2.256036 30 P 0 0 ;0=23,1=1
P 1.0048425 0.906063 30 P 0 0 ;0=23,1=1
P 1.0088425 1.430063 30 P 0 0 ;0=23,1=1
P 1.0098425 1.956063 30 P 0 0 ;0=23,1=1
P 1.0208425 2.481063 30 P 0 0 ;0=23,1=1
P 1.2428425 1.472063 30 P 0 0 ;0=23,1=1
P 1.2488425 2.000063 30 P 0 0 ;0=23,1=1
P 1.2568425 0.942063 30 P 0 0 ;0=23,1=1
P 1.2618425 2.482063 30 P 0 0 ;0=23,1=1
P 1.2948425 4.256063 30 P 0 0 ;0=23,1=1
P 1.3454724 4.1751969 30 P 0 0 ;0=23,1=1
P 1.3937008 1.8169291 30 P 0 0 ;0=23,1=1
P 1.4084645 3.980315 30 P 0 0 ;0=23,1=1
P 1.4408425 3.557063 30 P 0 0 ;0=23,1=1
P 1.4598425 3.147063 30 P 0 0 ;0=23,1=1
P 1.5498425 3.621063 30 P 0 0 ;0=23,1=1
P 1.5578425 4.229063 30 P 0 0 ;0=23,1=1
P 1.5679134 1.2854331 30 P 0 0 ;0=23,1=1
P 1.5682025 2.067703 30 P 0 0 ;0=23,1=1
P 1.5698819 4.1712599 30 P 0 0 ;0=23,1=1
P 1.5748425 3.596063 30 P 0 0 ;0=23,1=1
P 1.6198425 2.121063 30 P 0 0 ;0=23,1=1
P 1.6708425 1.595063 30 P 0 0 ;0=23,1=1
P 1.6708425 1.694063 30 P 0 0 ;0=23,1=1
P 1.6718425 1.399063 30 P 0 0 ;0=23,1=1
P 1.6718425 1.497063 30 P 0 0 ;0=23,1=1
P 1.6718425 1.792063 30 P 0 0 ;0=23,1=1
P 1.6748425 1.989063 30 P 0 0 ;0=23,1=1
P 1.6758425 1.891063 30 P 0 0 ;0=23,1=1
P 1.6918425 4.079063 30 P 0 0 ;0=23,1=1
P 1.7148425 1.595063 30 P 0 0 ;0=23,1=1
P 1.7168425 1.399063 30 P 0 0 ;0=23,1=1
P 1.7188425 1.497063 30 P 0 0 ;0=23,1=1
P 1.7188425 1.792063 30 P 0 0 ;0=23,1=1
P 1.7198425 1.536063 30 P 0 0 ;0=23,1=1
P 1.7218425 1.694063 30 P 0 0 ;0=23,1=1
P 1.7218425 1.890063 30 P 0 0 ;0=23,1=1
P 1.7218425 1.989063 30 P 0 0 ;0=23,1=1
P 1.7268425 4.329374 30 P 0 0 ;0=23,1=1
P 1.7498425 4.110063 30 P 0 0 ;0=23,1=1
P 1.7548425 2.126063 30 P 0 0 ;0=23,1=1
P 1.7548425 3.661063 30 P 0 0 ;0=23,1=1
P 1.7798425 4.156063 30 P 0 0 ;0=23,1=1
P 1.7888425 4.329374 30 P 0 0 ;0=23,1=1
P 1.7978425 0.355063 30 P 0 0 ;0=23,1=1
P 1.7982283 1.3041339 30 P 0 0 ;0=23,1=1
P 1.8227825 1.674003 30 P 0 0 ;0=23,1=1
P 1.8326771 0.2559055 30 P 0 0 ;0=23,1=1
P 1.8326771 0.2874016 30 P 0 0 ;0=23,1=1
P 1.8498425 3.701063 30 P 0 0 ;0=23,1=1
P 1.8523622 0.2559055 30 P 0 0 ;0=23,1=1
P 1.8523622 0.2874016 30 P 0 0 ;0=23,1=1
P 1.8720472 0.2559055 30 P 0 0 ;0=23,1=1
P 1.8720472 0.2874016 30 P 0 0 ;0=23,1=1
P 1.8799377 1.811803 30 P 0 0 ;0=23,1=1
P 1.8848425 2.071063 30 P 0 0 ;0=23,1=1
P 1.8848425 3.601063 30 P 0 0 ;0=23,1=1
P 1.8938425 1.693063 30 P 0 0 ;0=23,1=1
P 1.8973025 1.516523 30 P 0 0 ;0=23,1=1
P 1.9038425 4.018063 30 P 0 0 ;0=23,1=1
P 1.9161425 0.244763 30 P 0 0 ;0=23,1=1
P 2.0048425 1.336063 30 P 0 0 ;0=23,1=1
P 2.0048425 3.816063 30 P 0 0 ;0=23,1=1
P 2.0288425 1.361663 30 P 0 0 ;0=23,1=1
P 2.0298425 3.836063 30 P 0 0 ;0=23,1=1
P 2.0348425 0.246063 30 P 0 0 ;0=23,1=1
P 2.0598425 1.386063 30 P 0 0 ;0=23,1=1
P 2.0598425 3.871063 30 P 0 0 ;0=23,1=1
P 2.0767716 0.2559055 30 P 0 0 ;0=23,1=1
P 2.0767716 0.2874016 30 P 0 0 ;0=23,1=1
P 2.0838425 1.411663 30 P 0 0 ;0=23,1=1
P 2.0848425 3.896063 30 P 0 0 ;0=23,1=1
P 2.1122047 0.2559055 30 P 0 0 ;0=23,1=1
P 2.1122047 0.2874016 30 P 0 0 ;0=23,1=1
P 2.1398425 3.611063 30 P 0 0 ;0=23,1=1
P 2.1398425 3.738063 30 P 0 0 ;0=23,1=1
P 2.1460663 4.1037909 30 P 0 0 ;0=23,1=1
P 2.1468425 2.753063 30 P 0 0 ;0=23,1=1
P 2.1515748 0.2559055 30 P 0 0 ;0=23,1=1
P 2.1515748 0.2874016 30 P 0 0 ;0=23,1=1
P 2.2058425 3.200063 30 P 0 0 ;0=23,1=1
P 2.2068425 1.298063 30 P 0 0 ;0=23,1=1
P 2.2317425 2.584163 30 P 0 0 ;0=23,1=1
P 2.2348425 3.506063 30 P 0 0 ;0=23,1=1
P 2.2523425 2.613563 30 P 0 0 ;0=23,1=1
P 2.2538425 2.279063 30 P 0 0 ;0=23,1=1
P 2.253937 4.0866142 30 P 0 0 ;0=23,1=1
P 2.2548425 3.536063 30 P 0 0 ;0=23,1=1
P 2.2588425 3.741063 30 P 0 0 ;0=23,1=1
P 2.2598425 3.261063 30 P 0 0 ;0=23,1=1
P 2.2720325 2.463873 30 P 0 0 ;0=23,1=1
P 2.2748425 1.506063 30 P 0 0 ;0=23,1=1
P 2.2908425 4.217063 30 P 0 0 ;0=23,1=1
P 2.2998425 1.916063 30 P 0 0 ;0=23,1=1
P 2.3098425 0.246063 30 P 0 0 ;0=23,1=1
P 2.3114125 1.0900094 30 P 0 0 ;0=23,1=1
P 2.3118425 0.934063 30 P 0 0 ;0=23,1=1
P 2.3215354 2.586063 30 P 0 0 ;0=23,1=1
P 2.3215354 3.361063 30 P 0 0 ;0=23,1=1
P 2.3308425 2.215063 30 P 0 0 ;0=23,1=1
P 2.3503937 0.4055118 30 P 0 0 ;0=23,1=1
P 2.3533464 4.0177165 30 P 0 0 ;0=23,1=1
P 2.3848425 1.941063 30 P 0 0 ;0=23,1=1
P 2.3897638 0.4055118 30 P 0 0 ;0=23,1=1
P 2.3898425 3.481063 30 P 0 0 ;0=23,1=1
P 2.394685 2.7204724 30 P 0 0 ;0=23,1=1
P 2.4048425 2.412063 30 P 0 0 ;0=23,1=1
P 2.4098325 0.932053 30 P 0 0 ;0=23,1=1
P 2.4098325 1.088053 30 P 0 0 ;0=23,1=1
P 2.4098425 1.967063 30 P 0 0 ;0=23,1=1
P 2.4098425 2.283063 30 P 0 0 ;0=23,1=1
P 2.4098425 2.314063 30 P 0 0 ;0=23,1=1
P 2.4098425 2.579063 30 P 0 0 ;0=23,1=1
P 2.4133858 0.2795276 30 P 0 0 ;0=23,1=1
P 2.4138425 3.295063 30 P 0 0 ;0=23,1=1
P 2.4140551 3.1998504 30 P 0 0 ;0=23,1=1
P 2.4187174 3.1185066 30 P 0 0 ;0=23,1=1
P 2.4192759 2.7886295 30 P 0 0 ;0=23,1=1
P 2.4291925 2.621063 30 P 0 0 ;0=23,1=1
P 2.4348425 3.546063 30 P 0 0 ;0=23,1=1
P 2.4448819 0.2795276 30 P 0 0 ;0=23,1=1
P 2.4468425 1.437063 30 P 0 0 ;0=23,1=1
P 2.4470546 0.2425914 30 P 0 0 ;0=23,1=1
P 2.4508425 2.282063 30 P 0 0 ;0=23,1=1
P 2.462374 3.1722441 30 P 0 0 ;0=23,1=1
P 2.4698827 0.4109883 30 P 0 0 ;0=23,1=1
P 2.4738425 2.980063 30 P 0 0 ;0=23,1=1
P 2.4758425 2.291063 30 P 0 0 ;0=23,1=1
P 2.4758425 2.456063 30 P 0 0 ;0=23,1=1
P 2.4788425 0.937063 30 P 0 0 ;0=23,1=1
P 2.4888425 2.413063 30 P 0 0 ;0=23,1=1
P 2.4948425 2.661063 30 P 0 0 ;0=23,1=1
P 2.4948425 2.696063 30 P 0 0 ;0=23,1=1
P 2.4998425 2.236063 30 P 0 0 ;0=23,1=1
P 2.5028425 1.316063 30 P 0 0 ;0=23,1=1
P 2.5082625 0.931483 30 P 0 0 ;0=23,1=1
P 2.5088425 1.090063 30 P 0 0 ;0=23,1=1
P 2.511811 0.4055118 30 P 0 0 ;0=23,1=1
P 2.5258425 2.463063 30 P 0 0 ;0=23,1=1
P 2.531398 2.830047 31 P 0 0 ;0=24,1=1
P 2.531398 3.853669 31 P 0 0 ;0=24,1=1
P 2.5460625 0.244843 30 P 0 0 ;0=23,1=1
P 2.5498425 1.755063 30 P 0 0 ;0=23,1=1
P 2.5708425 4.283063 30 P 0 0 ;0=23,1=1
P 2.5758425 2.412063 30 P 0 0 ;0=23,1=1
P 2.5787402 0.2795276 30 P 0 0 ;0=23,1=1
P 2.5798425 1.790063 30 P 0 0 ;0=23,1=1
P 2.5798425 2.281063 30 P 0 0 ;0=23,1=1
P 2.5798425 3.486063 30 P 0 0 ;0=23,1=1
P 2.5818425 2.308063 30 P 0 0 ;0=23,1=1
P 2.5868425 2.569063 30 P 0 0 ;0=23,1=1
P 2.5908425 3.288063 30 P 0 0 ;0=23,1=1
P 2.5918425 3.1862205 30 P 0 0 ;0=23,1=1
P 2.5984252 0.7952756 30 P 0 0 ;0=23,1=1
P 2.5998425 2.436063 30 P 0 0 ;0=23,1=1
P 2.6048425 1.734063 30 P 0 0 ;0=23,1=1
P 2.6066825 0.931903 30 P 0 0 ;0=23,1=1
P 2.6068425 1.091063 30 P 0 0 ;0=23,1=1
P 2.6102362 0.2795276 30 P 0 0 ;0=23,1=1
P 2.6220472 0.976378 30 P 0 0 ;0=23,1=1
P 2.6248425 2.461063 30 P 0 0 ;0=23,1=1
P 2.6259843 0.7952756 30 P 0 0 ;0=23,1=1
P 2.6268425 1.770063 30 P 0 0 ;0=23,1=1
P 2.6318425 2.876063 30 P 0 0 ;0=23,1=1
P 2.6348425 3.406063 30 P 0 0 ;0=23,1=1
P 2.636874 0.2479055 30 P 0 0 ;0=23,1=1
P 2.6438425 1.616063 30 P 0 0 ;0=23,1=1
P 2.6458425 2.274063 30 P 0 0 ;0=23,1=1
P 2.6496063 0.976378 30 P 0 0 ;0=23,1=1
P 2.6653543 0.4055118 30 P 0 0 ;0=23,1=1
P 2.6653543 0.7952756 30 P 0 0 ;0=23,1=1
P 2.6658425 1.092063 30 P 0 0 ;0=23,1=1
P 2.6658425 2.291063 30 P 0 0 ;0=23,1=1
P 2.6668425 1.640063 30 P 0 0 ;0=23,1=1
P 2.6748425 3.501063 30 P 0 0 ;0=23,1=1
P 2.6798425 3.661063 30 P 0 0 ;0=23,1=1
P 2.6811024 0.976378 30 P 0 0 ;0=23,1=1
P 2.6858425 2.311063 30 P 0 0 ;0=23,1=1
P 2.6858425 2.568063 30 P 0 0 ;0=23,1=1
P 2.6929134 0.7952756 30 P 0 0 ;0=23,1=1
P 2.6929134 2.7214567 30 P 0 0 ;0=23,1=1
P 2.6948425 1.481063 30 P 0 0 ;0=23,1=1
P 2.7028425 2.289063 30 P 0 0 ;0=23,1=1
P 2.7047244 0.4055118 30 P 0 0 ;0=23,1=1
P 2.7086614 0.976378 30 P 0 0 ;0=23,1=1
P 2.7198425 1.591063 30 P 0 0 ;0=23,1=1
P 2.7224094 3.7860709 30 P 0 0 ;0=23,1=1
P 2.7244825 1.093063 30 P 0 0 ;0=23,1=1
P 2.7248425 3.521063 30 P 0 0 ;0=23,1=1
P 2.7248425 3.729063 30 P 0 0 ;0=23,1=1
P 2.7268425 2.293063 30 P 0 0 ;0=23,1=1
P 2.7322835 0.7952756 30 P 0 0 ;0=23,1=1
P 2.7401575 0.976378 30 P 0 0 ;0=23,1=1
P 2.74882 0.282312 30 P 0 0 ;0=23,1=1
P 2.7598425 0.7952756 30 P 0 0 ;0=23,1=1
P 2.7677165 0.976378 30 P 0 0 ;0=23,1=1
P 2.7748425 3.566063 30 P 0 0 ;0=23,1=1
P 2.7795276 0.2795276 30 P 0 0 ;0=23,1=1
P 2.7838425 2.429063 30 P 0 0 ;0=23,1=1
P 2.7838425 2.568063 30 P 0 0 ;0=23,1=1
P 2.7841625 1.094063 30 P 0 0 ;0=23,1=1
P 2.7992126 0.7952756 30 P 0 0 ;0=23,1=1
P 2.7992126 0.976378 30 P 0 0 ;0=23,1=1
P 2.7998425 3.616063 30 P 0 0 ;0=23,1=1
P 2.7999951 0.2519685 30 P 0 0 ;0=23,1=1
P 2.8038425 2.307063 30 P 0 0 ;0=23,1=1
P 2.8218425 2.601063 30 P 0 0 ;0=23,1=1
P 2.8219832 0.4078519 30 P 0 0 ;0=23,1=1
P 2.8267717 0.7952756 30 P 0 0 ;0=23,1=1
P 2.8267717 0.976378 30 P 0 0 ;0=23,1=1
P 2.8418425 2.263063 30 P 0 0 ;0=23,1=1
P 2.8428425 1.095063 30 P 0 0 ;0=23,1=1
P 2.8543307 0.4055118 30 P 0 0 ;0=23,1=1
P 2.8608425 3.787063 30 P 0 0 ;0=23,1=1
P 2.8622047 0.7952756 30 P 0 0 ;0=23,1=1
P 2.8718425 2.297063 30 P 0 0 ;0=23,1=1
P 2.8782843 0.2495967 30 P 0 0 ;0=23,1=1
P 2.8818425 2.566063 30 P 0 0 ;0=23,1=1
P 2.8888425 4.221063 30 P 0 0 ;0=23,1=1
P 2.8937008 0.7952756 30 P 0 0 ;0=23,1=1
P 2.8948425 1.561063 30 P 0 0 ;0=23,1=1
P 2.8948425 2.431063 30 P 0 0 ;0=23,1=1
P 2.9018425 1.095063 30 P 0 0 ;0=23,1=1
P 2.9054946 0.2795104 30 P 0 0 ;0=23,1=1
P 2.9198425 1.536063 30 P 0 0 ;0=23,1=1
P 2.9208425 2.428063 30 P 0 0 ;0=23,1=1
P 2.9338425 0.953063 30 P 0 0 ;0=23,1=1
P 2.9370079 0.2795276 30 P 0 0 ;0=23,1=1
P 2.9428425 2.286063 30 P 0 0 ;0=23,1=1
P 2.9488425 2.456063 30 P 0 0 ;0=23,1=1
P 2.9574751 0.2519685 30 P 0 0 ;0=23,1=1
P 2.9588425 2.621063 30 P 0 0 ;0=23,1=1
P 2.980457 0.4091539 30 P 0 0 ;0=23,1=1
P 2.9858425 2.287063 30 P 0 0 ;0=23,1=1
P 2.9933858 3.751063 30 P 0 0 ;0=23,1=1
P 3.0148425 3.831063 30 P 0 0 ;0=23,1=1
P 3.019685 0.4055118 30 P 0 0 ;0=23,1=1
P 3.0568817 1.811803 30 P 0 0 ;0=23,1=1
P 3.0688976 3.3956693 30 P 0 0 ;0=23,1=1
P 3.0974409 0.2519685 30 P 0 0 ;0=23,1=1
P 3.1830708 3.1358268 30 P 0 0 ;0=23,1=1
P 3.1889764 3.1870079 30 P 0 0 ;0=23,1=1
P 3.1972633 1.714063 30 P 0 0 ;0=23,1=1
P 3.1978425 2.970063 30 P 0 0 ;0=23,1=1
P 3.2198425 3.806063 30 P 0 0 ;0=23,1=1
P 3.2248425 1.6613472 30 P 0 0 ;0=23,1=1
P 3.2308425 3.235063 30 P 0 0 ;0=23,1=1
P 3.2398425 3.596063 30 P 0 0 ;0=23,1=1
P 3.2528425 1.661063 30 P 0 0 ;0=23,1=1
P 3.2636972 3.3039177 30 P 0 0 ;0=23,1=1
P 3.2698425 3.788063 30 P 0 0 ;0=23,1=1
P 3.2755905 3.1417323 30 P 0 0 ;0=23,1=1
P 3.277559 2.9635827 30 P 0 0 ;0=23,1=1
P 3.2988425 1.971063 30 P 0 0 ;0=23,1=1
P 3.3028425 3.344063 30 P 0 0 ;0=23,1=1
P 3.3291721 1.826063 30 P 0 0 ;0=23,1=1
P 3.3308425 3.301063 30 P 0 0 ;0=23,1=1
P 3.3428425 2.263063 30 P 0 0 ;0=23,1=1
P 3.3448425 2.996063 30 P 0 0 ;0=23,1=1
P 3.3588425 3.448063 30 P 0 0 ;0=23,1=1
P 3.3688425 3.050063 30 P 0 0 ;0=23,1=1
P 3.3708425 2.888063 30 P 0 0 ;0=23,1=1
P 3.3748425 3.273063 30 P 0 0 ;0=23,1=1
P 3.3798425 1.336063 30 P 0 0 ;0=23,1=1
P 3.3798425 1.386063 30 P 0 0 ;0=23,1=1
P 3.3928425 1.871063 30 P 0 0 ;0=23,1=1
P 3.3948425 3.447063 30 P 0 0 ;0=23,1=1
P 3.3958425 4.222063 30 P 0 0 ;0=23,1=1
P 3.4048425 1.363323 30 P 0 0 ;0=23,1=1
P 3.4068425 1.461063 30 P 0 0 ;0=23,1=1
P 3.4072822 1.411323 30 P 0 0 ;0=23,1=1
P 3.4108425 1.7136509 30 P 0 0 ;0=23,1=1
P 3.4138425 1.573063 30 P 0 0 ;0=23,1=1
P 3.4144661 1.805063 30 P 0 0 ;0=23,1=1
P 3.4248425 3.636063 30 P 0 0 ;0=23,1=1
P 3.4368425 3.457063 30 P 0 0 ;0=23,1=1
P 3.4392507 1.870938 30 P 0 0 ;0=23,1=1
P 3.4698425 3.456063 30 P 0 0 ;0=23,1=1
P 3.4918425 3.103063 30 P 0 0 ;0=23,1=1
P 3.4918425 3.297063 30 P 0 0 ;0=23,1=1
P 3.4988425 2.341063 30 P 0 0 ;0=23,1=1
P 3.5048425 4.086063 30 P 0 0 ;0=23,1=1
P 3.5298425 3.481063 30 P 0 0 ;0=23,1=1
P 3.5318425 3.660063 30 P 0 0 ;0=23,1=1
P 3.5398425 3.806063 30 P 0 0 ;0=23,1=1
P 3.542865 3.3190405 30 P 0 0 ;0=23,1=1
P 3.5498425 1.413063 30 P 0 0 ;0=23,1=1
P 3.5498425 1.441063 30 P 0 0 ;0=23,1=1
P 3.5548425 1.841063 30 P 0 0 ;0=23,1=1
P 3.5548425 1.891063 30 P 0 0 ;0=23,1=1
P 3.5548425 1.941063 30 P 0 0 ;0=23,1=1
P 3.5548425 1.991063 30 P 0 0 ;0=23,1=1
P 3.5718425 2.033063 30 P 0 0 ;0=23,1=1
P 3.5718425 2.058063 30 P 0 0 ;0=23,1=1
P 3.5898425 1.711063 30 P 0 0 ;0=23,1=1
P 3.5908425 1.662063 30 P 0 0 ;0=23,1=1
P 3.5948425 1.514063 30 P 0 0 ;0=23,1=1
P 3.6038425 0.682063 30 P 0 0 ;0=23,1=1
P 3.6228425 3.486063 30 P 0 0 ;0=23,1=1
P 3.6238425 2.587063 30 P 0 0 ;0=23,1=1
P 3.6428425 0.636063 30 P 0 0 ;0=23,1=1
P 3.6538425 3.293063 30 P 0 0 ;0=23,1=1
P 3.6998425 3.751063 30 P 0 0 ;0=23,1=1
P 3.6998425 3.836063 30 P 0 0 ;0=23,1=1
P 3.7178425 3.072063 30 P 0 0 ;0=23,1=1
P 3.7188425 1.713063 30 P 0 0 ;0=23,1=1
P 3.7198425 1.766063 30 P 0 0 ;0=23,1=1
P 3.7198425 1.921063 30 P 0 0 ;0=23,1=1
P 3.7198425 1.996063 30 P 0 0 ;0=23,1=1
P 3.7248425 1.675063 30 P 0 0 ;0=23,1=1
P 3.7328425 1.418063 30 P 0 0 ;0=23,1=1
P 3.7448425 3.261063 30 P 0 0 ;0=23,1=1
P 3.7448425 3.342063 30 P 0 0 ;0=23,1=1
P 3.7738632 1.6661021 30 P 0 0 ;0=23,1=1
P 3.7778425 4.023063 30 P 0 0 ;0=23,1=1
P 3.7998425 3.201063 30 P 0 0 ;0=23,1=1
P 3.8038425 1.691063 30 P 0 0 ;0=23,1=1
P 3.8048425 1.840063 30 P 0 0 ;0=23,1=1
P 3.8068425 3.235063 30 P 0 0 ;0=23,1=1
P 3.8298425 3.176063 30 P 0 0 ;0=23,1=1
P 3.8298425 3.806063 30 P 0 0 ;0=23,1=1
P 3.8308425 3.762063 30 P 0 0 ;0=23,1=1
P 3.8348425 1.481063 30 P 0 0 ;0=23,1=1
P 3.8548425 3.151063 30 P 0 0 ;0=23,1=1
P 3.8648425 1.511063 30 P 0 0 ;0=23,1=1
P 3.8808425 3.109063 30 P 0 0 ;0=23,1=1
P 3.8948425 1.566063 30 P 0 0 ;0=23,1=1
P 3.9248425 1.536063 30 P 0 0 ;0=23,1=1
P 3.9398425 3.121063 30 P 0 0 ;0=23,1=1
P 3.9448425 1.816063 30 P 0 0 ;0=23,1=1
P 3.9608425 2.724063 30 P 0 0 ;0=23,1=1
P 3.9688425 1.671063 30 P 0 0 ;0=23,1=1
P 3.9698425 1.552063 30 P 0 0 ;0=23,1=1
P 3.9948425 1.551063 30 P 0 0 ;0=23,1=1
P 3.9968425 1.711063 30 P 0 0 ;0=23,1=1
P 4.0348425 1.546063 30 P 0 0 ;0=23,1=1
P 4.0398425 2.406063 30 P 0 0 ;0=23,1=1
P 4.0398425 3.784063 30 P 0 0 ;0=23,1=1
P 4.0498425 3.665063 30 P 0 0 ;0=23,1=1
P 4.0648425 1.511063 30 P 0 0 ;0=23,1=1
P 4.0648425 1.796063 30 P 0 0 ;0=23,1=1
P 4.0648425 2.722063 30 P 0 0 ;0=23,1=1
P 4.0688425 3.135063 30 P 0 0 ;0=23,1=1
P 4.0858425 3.892063 30 P 0 0 ;0=23,1=1
P 4.1148425 3.135063 30 P 0 0 ;0=23,1=1
P 4.1203866 3.5941508 30 P 0 0 ;0=23,1=1
P 4.1318425 1.686063 30 P 0 0 ;0=23,1=1
P 4.1348425 1.651063 30 P 0 0 ;0=23,1=1
P 4.1348425 1.751063 30 P 0 0 ;0=23,1=1
P 4.1513063 1.6236232 30 P 0 0 ;0=23,1=1
P 4.1528425 3.135063 30 P 0 0 ;0=23,1=1
P 4.1798425 1.601063 30 P 0 0 ;0=23,1=1
P 4.1948425 3.884063 30 P 0 0 ;0=23,1=1
P 4.2088425 3.135063 30 P 0 0 ;0=23,1=1
P 4.2348425 2.725063 30 P 0 0 ;0=23,1=1
P 4.2548425 3.776063 30 P 0 0 ;0=23,1=1
P 4.2728425 3.135063 30 P 0 0 ;0=23,1=1
P 4.3338425 3.135063 30 P 0 0 ;0=23,1=1
P 4.3398425 2.725063 30 P 0 0 ;0=23,1=1
P 4.3878425 4.206063 30 P 0 0 ;0=23,1=1
P 4.4318425 3.135063 30 P 0 0 ;0=23,1=1
P 4.4778425 3.135063 30 P 0 0 ;0=23,1=1
P 4.5036614 2.7898819 30 P 0 0 ;0=23,1=1
P 4.7547119 4.1159324 30 P 0 0 ;0=23,1=1
P 4.7942913 2.8080709 30 P 0 0 ;0=23,1=1
P 4.9108425 4.203063 30 P 0 0 ;0=23,1=1
P 5.2670079 4.0888976 30 P 0 0 ;0=23,1=1
P 5.2748425 3.511063 30 P 0 0 ;0=23,1=1
P 5.5778425 2.214063 30 P 0 0 ;0=23,1=1
P 5.6348425 2.236063 30 P 0 0 ;0=23,1=1
P 5.6768425 3.546063 30 P 0 0 ;0=23,1=1
P 5.7338425 3.556063 30 P 0 0 ;0=23,1=1
P 5.9948425 3.552063 30 P 0 0 ;0=23,1=1
P 6.0048425 2.434063 30 P 0 0 ;0=23,1=1
P 6.0488425 2.171063 30 P 0 0 ;0=23,1=1
P 6.253937 2.9094488 30 P 0 0 ;0=23,1=1
P 6.2748425 2.391063 30 P 0 0 ;0=23,1=1
P 6.2824161 3.226063 30 P 0 0 ;0=23,1=1
P 6.2848425 2.501063 30 P 0 0 ;0=23,1=1
P 6.2948425 3.701063 30 P 0 0 ;0=23,1=1
P 6.3048425 3.121063 30 P 0 0 ;0=23,1=1
P 6.3094161 3.199063 30 P 0 0 ;0=23,1=1
P 6.3348425 3.266063 30 P 0 0 ;0=23,1=1
P 6.3398425 3.151063 30 P 0 0 ;0=23,1=1
P 6.3547483 3.3311384 30 P 0 0 ;0=23,1=1
P 6.3720472 2.9094488 30 P 0 0 ;0=23,1=1
P 6.3958425 2.111063 30 P 0 0 ;0=23,1=1
P 6.3968425 2.556063 30 P 0 0 ;0=23,1=1
P 6.3978425 2.501063 30 P 0 0 ;0=23,1=1
P 6.3978425 2.610063 30 P 0 0 ;0=23,1=1
P 6.3988425 2.453063 30 P 0 0 ;0=23,1=1
P 6.3988425 2.657063 30 P 0 0 ;0=23,1=1
P 6.4098425 3.371063 30 P 0 0 ;0=23,1=1
P 6.4248425 2.181063 30 P 0 0 ;0=23,1=1
P 6.4398425 3.191063 30 P 0 0 ;0=23,1=1
P 6.4448425 3.291063 30 P 0 0 ;0=23,1=1
P 6.4475772 3.396063 30 P 0 0 ;0=23,1=1
P 6.4568425 3.009063 30 P 0 0 ;0=23,1=1
P 6.4768425 3.231063 30 P 0 0 ;0=23,1=1
P 6.4798425 3.426063 30 P 0 0 ;0=23,1=1
P 6.5098425 3.456063 30 P 0 0 ;0=23,1=1
P 6.5488425 1.531063 30 P 0 0 ;0=23,1=1
P 6.6018425 1.777063 30 P 0 0 ;0=23,1=1
P 6.6028425 1.612063 30 P 0 0 ;0=23,1=1
P 6.6028425 1.672063 30 P 0 0 ;0=23,1=1
P 6.6028425 1.722063 30 P 0 0 ;0=23,1=1
P 6.6078425 2.176063 30 P 0 0 ;0=23,1=1
P 6.6268425 3.032063 30 P 0 0 ;0=23,1=1
P 6.6288425 1.372063 30 P 0 0 ;0=23,1=1
P 6.6476378 3.1299213 30 P 0 0 ;0=23,1=1
P 6.6488425 3.341063 30 P 0 0 ;0=23,1=1
P 6.6858425 1.828063 30 P 0 0 ;0=23,1=1
P 6.6998425 1.881063 30 P 0 0 ;0=23,1=1
P 6.8448425 1.661063 30 P 0 0 ;0=23,1=1
P 6.9498425 2.095063 30 P 0 0 ;0=23,1=1
P 6.9744094 1.9399606 30 P 0 0 ;0=23,1=1

### steps/pcb/layers/bottom_overlay/features
#Layer_Color=32896
#
#Feature symbol names
#
$0 r3.937
$1 r1
$2 r10
$3 r6

#
#Feature attribute names
#
@0 .nomenclature
@1 .string
@2 .string_angle

#
#Feature attribute text strings
#
&0 U14
&1 C87
&2 C88
&3 C89
&4 C90
&5 C53
&6 C52
&7 C51
&8 C50
&9 C49
&10 C48
&11 C47
&12 C46
&13 C45
&14 C44

#
#Layer features
#
A 0.2105315 2.8300473 0.2105315 2.8300473 0.1495079 2.8300473 2 P 0 N
A 1.7712204 0.4310709 1.6275196 0.4310709 1.69937 0.4310709 0 P 0 N
A 2.5924212 2.8300473 2.5924212 2.8300473 2.5313976 2.8300473 2 P 0 N
A 2.5924212 3.8536693 2.5924212 3.8536693 2.5313976 3.8536693 2 P 0 N
L -0.0001175 0.177913 0.5908825 0.177913 1 P 0
L -0.0004331 0.1781182 0.5901181 0.1781182 0 P 0
L 0.0180118 2.7168583 0.0180118 3.9668583 2 P 0
L 0.0180118 2.7168583 2.6628937 2.7168583 2 P 0
L 0.0180118 3.9668583 2.6628937 3.9668583 2 P 0
L 0.5901181 0.1781182 0.5901181 0.5029213 0 P 0
L 0.5901181 0.5029213 1.312559 0.5029213 0 P 0
L 0.5908825 0.177913 0.5908825 0.502913 1 P 0
L 1.312559 0.313945 1.312559 0.5029213 0 P 0
L 1.312559 0.313945 1.6275197 0.313945 0 P 0
L 1.6275197 0.313945 1.6275197 0.4310709 0 P 0
L 2.1985692 2.9482203 2.2185627 2.9282268 2 P 0 ;0,1=1,2=0.000000
L 2.1985692 2.9532187 2.1985692 2.9482203 2 P 0 ;0,1=1,2=0.000000
L 2.2185627 2.9282268 2.2185627 2.9232284 2 P 0 ;0,1=1,2=0.000000
L 2.2185627 2.9532187 2.1985692 2.9532187 2 P 0 ;0,1=1,2=0.000000
L 2.2285595 2.9282268 2.2335578 2.9232284 2 P 0 ;0,1=1,2=0.000000
L 2.2285595 2.9332252 2.2285595 2.9282268 2 P 0 ;0,1=1,2=0.000000
L 2.2285595 2.9432219 2.2335578 2.9382236 2 P 0 ;0,1=1,2=0.000000
L 2.2285595 2.9482203 2.2285595 2.9432219 2 P 0 ;0,1=1,2=0.000000
L 2.2335578 2.9232284 2.2435546 2.9232284 2 P 0 ;0,1=1,2=0.000000
L 2.2335578 2.9382236 2.2285595 2.9332252 2 P 0 ;0,1=1,2=0.000000
L 2.2335578 2.9532187 2.2285595 2.9482203 2 P 0 ;0,1=1,2=0.000000
L 2.2399078 2.8288173 2.2449061 2.8238189 2 P 0 ;0,1=2,2=0.000000
L 2.2399078 2.8338157 2.2399078 2.8288173 2 P 0 ;0,1=2,2=0.000000
L 2.2399078 2.8438124 2.2449061 2.8388141 2 P 0 ;0,1=2,2=0.000000
L 2.2399078 2.8488108 2.2399078 2.8438124 2 P 0 ;0,1=2,2=0.000000
L 2.2435546 2.9232284 2.248553 2.9282268 2 P 0 ;0,1=1,2=0.000000
L 2.2435546 2.9382236 2.2335578 2.9382236 2 P 0 ;0,1=1,2=0.000000
L 2.2435546 2.9382236 2.248553 2.9432219 2 P 0 ;0,1=1,2=0.000000
L 2.2435546 2.9532187 2.2335578 2.9532187 2 P 0 ;0,1=1,2=0.000000
L 2.2449061 2.8238189 2.2549029 2.8238189 2 P 0 ;0,1=2,2=0.000000
L 2.2449061 2.8388141 2.2399078 2.8338157 2 P 0 ;0,1=2,2=0.000000
L 2.2449061 2.8538092 2.2399078 2.8488108 2 P 0 ;0,1=2,2=0.000000
L 2.248553 2.9282268 2.248553 2.9332252 2 P 0 ;0,1=1,2=0.000000
L 2.248553 2.9332252 2.2435546 2.9382236 2 P 0 ;0,1=1,2=0.000000
L 2.248553 2.9432219 2.248553 2.9482203 2 P 0 ;0,1=1,2=0.000000
L 2.248553 2.9482203 2.2435546 2.9532187 2 P 0 ;0,1=1,2=0.000000
L 2.2549029 2.8238189 2.2599013 2.8288173 2 P 0 ;0,1=2,2=0.000000
L 2.2549029 2.8388141 2.2449061 2.8388141 2 P 0 ;0,1=2,2=0.000000
L 2.2549029 2.8388141 2.2599013 2.8438124 2 P 0 ;0,1=2,2=0.000000
L 2.2549029 2.8538092 2.2449061 2.8538092 2 P 0 ;0,1=2,2=0.000000
L 2.2585498 2.9482203 2.2635481 2.9532187 2 P 0 ;0,1=1,2=0.000000
L 2.2599013 2.8288173 2.2599013 2.8338157 2 P 0 ;0,1=2,2=0.000000
L 2.2599013 2.8338157 2.2549029 2.8388141 2 P 0 ;0,1=2,2=0.000000
L 2.2599013 2.8438124 2.2599013 2.8488108 2 P 0 ;0,1=2,2=0.000000
L 2.2599013 2.8488108 2.2549029 2.8538092 2 P 0 ;0,1=2,2=0.000000
L 2.2635481 2.9232284 2.2585498 2.9282268 2 P 0 ;0,1=1,2=0.000000
L 2.2635481 2.9532187 2.2735449 2.9532187 2 P 0 ;0,1=1,2=0.000000
L 2.2698981 2.8288173 2.2748964 2.8238189 2 P 0 ;0,1=2,2=0.000000
L 2.2698981 2.8338157 2.2698981 2.8288173 2 P 0 ;0,1=2,2=0.000000
L 2.2698981 2.8438124 2.2748964 2.8388141 2 P 0 ;0,1=2,2=0.000000
L 2.2698981 2.8488108 2.2698981 2.8438124 2 P 0 ;0,1=2,2=0.000000
L 2.2735449 2.9232284 2.2635481 2.9232284 2 P 0 ;0,1=1,2=0.000000
L 2.2735449 2.9532187 2.2785433 2.9482203 2 P 0 ;0,1=1,2=0.000000
L 2.2748964 2.8238189 2.2848932 2.8238189 2 P 0 ;0,1=2,2=0.000000
L 2.2748964 2.8388141 2.2698981 2.8338157 2 P 0 ;0,1=2,2=0.000000
L 2.2748964 2.8538092 2.2698981 2.8488108 2 P 0 ;0,1=2,2=0.000000
L 2.2785433 2.9282268 2.2735449 2.9232284 2 P 0 ;0,1=1,2=0.000000
L 2.2785433 2.9482203 2.2785433 2.9282268 2 P 0 ;0,1=1,2=0.000000
L 2.2848932 2.8238189 2.2898916 2.8288173 2 P 0 ;0,1=2,2=0.000000
L 2.2848932 2.8388141 2.2748964 2.8388141 2 P 0 ;0,1=2,2=0.000000
L 2.2848932 2.8388141 2.2898916 2.8438124 2 P 0 ;0,1=2,2=0.000000
L 2.2848932 2.8538092 2.2748964 2.8538092 2 P 0 ;0,1=2,2=0.000000
L 2.2898916 2.8288173 2.2898916 2.8338157 2 P 0 ;0,1=2,2=0.000000
L 2.2898916 2.8338157 2.2848932 2.8388141 2 P 0 ;0,1=2,2=0.000000
L 2.2898916 2.8438124 2.2898916 2.8488108 2 P 0 ;0,1=2,2=0.000000
L 2.2898916 2.8488108 2.2848932 2.8538092 2 P 0 ;0,1=2,2=0.000000
L 2.2998884 2.8488108 2.3048867 2.8538092 2 P 0 ;0,1=2,2=0.000000
L 2.3048867 2.8238189 2.2998884 2.8288173 2 P 0 ;0,1=2,2=0.000000
L 2.3048867 2.8538092 2.3148835 2.8538092 2 P 0 ;0,1=2,2=0.000000
L 2.3061023 0.4646441 2.3061023 0.4746409 2 P 0 ;0,1=14,2=270.000000
L 2.3061023 0.4746409 2.3111007 0.4796392 2 P 0 ;0,1=14,2=270.000000
L 2.3061023 0.5046312 2.3360926 0.5046312 2 P 0 ;0,1=14,2=270.000000
L 2.3061023 0.5346215 2.3360926 0.5346215 2 P 0 ;0,1=14,2=270.000000
L 2.3111007 0.4596457 2.3061023 0.4646441 2 P 0 ;0,1=14,2=270.000000
L 2.3148835 2.8238189 2.3048867 2.8238189 2 P 0 ;0,1=2,2=0.000000
L 2.3148835 2.8538092 2.3198819 2.8488108 2 P 0 ;0,1=2,2=0.000000
L 2.3198819 2.8288173 2.3148835 2.8238189 2 P 0 ;0,1=2,2=0.000000
L 2.3198819 2.8488108 2.3198819 2.8288173 2 P 0 ;0,1=2,2=0.000000
L 2.3210975 0.489636 2.3210975 0.5096295 2 P 0 ;0,1=14,2=270.000000
L 2.3210975 0.5196263 2.3210975 0.5396198 2 P 0 ;0,1=14,2=270.000000
L 2.3310942 0.4596457 2.3111007 0.4596457 2 P 0 ;0,1=14,2=270.000000
L 2.3310942 0.4796392 2.3360926 0.4746409 2 P 0 ;0,1=14,2=270.000000
L 2.3328425 2.906063 2.3928425 2.906063 3 P 0
L 2.3328425 2.982063 2.3928425 2.982063 3 P 0
L 2.3360926 0.4646441 2.3310942 0.4596457 2 P 0 ;0,1=14,2=270.000000
L 2.3360926 0.4746409 2.3360926 0.4646441 2 P 0 ;0,1=14,2=270.000000
L 2.3360926 0.5046312 2.3210975 0.489636 2 P 0 ;0,1=14,2=270.000000
L 2.3360926 0.5346215 2.3210975 0.5196263 2 P 0 ;0,1=14,2=270.000000
L 2.3759842 0.4626756 2.3759842 0.4726724 2 P 0 ;0,1=13,2=270.000000
L 2.3759842 0.4726724 2.3809826 0.4776707 2 P 0 ;0,1=13,2=270.000000
L 2.3759842 0.5026627 2.4059745 0.5026627 2 P 0 ;0,1=13,2=270.000000
L 2.3759842 0.5226562 2.3809826 0.5176578 2 P 0 ;0,1=13,2=270.000000
L 2.3759842 0.532653 2.3759842 0.5226562 2 P 0 ;0,1=13,2=270.000000
L 2.3809826 0.4576772 2.3759842 0.4626756 2 P 0 ;0,1=13,2=270.000000
L 2.3809826 0.5376513 2.3759842 0.532653 2 P 0 ;0,1=13,2=270.000000
L 2.3909794 0.4876675 2.3909794 0.507661 2 P 0 ;0,1=13,2=270.000000
L 2.3909794 0.5176578 2.3959777 0.5276546 2 P 0 ;0,1=13,2=270.000000
L 2.3909794 0.5376513 2.3809826 0.5376513 2 P 0 ;0,1=13,2=270.000000
L 2.3959777 0.5276546 2.3959777 0.532653 2 P 0 ;0,1=13,2=270.000000
L 2.3959777 0.532653 2.3909794 0.5376513 2 P 0 ;0,1=13,2=270.000000
L 2.4009761 0.4576772 2.3809826 0.4576772 2 P 0 ;0,1=13,2=270.000000
L 2.4009761 0.4776707 2.4059745 0.4726724 2 P 0 ;0,1=13,2=270.000000
L 2.4059745 0.4626756 2.4009761 0.4576772 2 P 0 ;0,1=13,2=270.000000
L 2.4059745 0.4726724 2.4059745 0.4626756 2 P 0 ;0,1=13,2=270.000000
L 2.4059745 0.5026627 2.3909794 0.4876675 2 P 0 ;0,1=13,2=270.000000
L 2.4059745 0.5176578 2.3909794 0.5176578 2 P 0 ;0,1=13,2=270.000000
L 2.4059745 0.5376513 2.4059745 0.5176578 2 P 0 ;0,1=13,2=270.000000
L 2.4503498 0.4460808 2.4503498 0.4560776 2 P 0 ;0,1=12,2=270.000000
L 2.4503498 0.4560776 2.4553482 0.4610759 2 P 0 ;0,1=12,2=270.000000
L 2.4503498 0.4860679 2.4803401 0.4860679 2 P 0 ;0,1=12,2=270.000000
L 2.4503498 0.5060614 2.4503498 0.5160582 2 P 0 ;0,1=12,2=270.000000
L 2.4503498 0.5160582 2.4553482 0.5210565 2 P 0 ;0,1=12,2=270.000000
L 2.4553482 0.4410824 2.4503498 0.4460808 2 P 0 ;0,1=12,2=270.000000
L 2.4553482 0.501063 2.4503498 0.5060614 2 P 0 ;0,1=12,2=270.000000
L 2.4553482 0.5210565 2.4603466 0.5210565 2 P 0 ;0,1=12,2=270.000000
L 2.4603466 0.5210565 2.465345 0.5160582 2 P 0 ;0,1=12,2=270.000000
L 2.465345 0.4710727 2.465345 0.4910662 2 P 0 ;0,1=12,2=270.000000
L 2.465345 0.501063 2.4553482 0.501063 2 P 0 ;0,1=12,2=270.000000
L 2.465345 0.5160582 2.465345 0.501063 2 P 0 ;0,1=12,2=270.000000
L 2.4753417 0.4410824 2.4553482 0.4410824 2 P 0 ;0,1=12,2=270.000000
L 2.4753417 0.4610759 2.4803401 0.4560776 2 P 0 ;0,1=12,2=270.000000
L 2.4753417 0.5110598 2.465345 0.501063 2 P 0 ;0,1=12,2=270.000000
L 2.4803401 0.4460808 2.4753417 0.4410824 2 P 0 ;0,1=12,2=270.000000
L 2.4803401 0.4560776 2.4803401 0.4460808 2 P 0 ;0,1=12,2=270.000000
L 2.4803401 0.4860679 2.465345 0.4710727 2 P 0 ;0,1=12,2=270.000000
L 2.4803401 0.5210565 2.4753417 0.5110598 2 P 0 ;0,1=12,2=270.000000
L 2.5193498 0.4460808 2.5193498 0.4560776 2 P 0 ;0,1=11,2=270.000000
L 2.5193498 0.4560776 2.5243482 0.4610759 2 P 0 ;0,1=11,2=270.000000
L 2.5193498 0.4860679 2.5493401 0.4860679 2 P 0 ;0,1=11,2=270.000000
L 2.5243482 0.4410824 2.5193498 0.4460808 2 P 0 ;0,1=11,2=270.000000
L 2.5243482 0.501063 2.5193498 0.501063 2 P 0 ;0,1=11,2=270.000000
L 2.534345 0.4710727 2.534345 0.4910662 2 P 0 ;0,1=11,2=270.000000
L 2.5443417 0.4410824 2.5243482 0.4410824 2 P 0 ;0,1=11,2=270.000000
L 2.5443417 0.4610759 2.5493401 0.4560776 2 P 0 ;0,1=11,2=270.000000
L 2.5443417 0.5210565 2.5243482 0.501063 2 P 0 ;0,1=11,2=270.000000
L 2.5493401 0.4460808 2.5443417 0.4410824 2 P 0 ;0,1=11,2=270.000000
L 2.5493401 0.4560776 2.5493401 0.4460808 2 P 0 ;0,1=11,2=270.000000
L 2.5493401 0.4860679 2.534345 0.4710727 2 P 0 ;0,1=11,2=270.000000
L 2.5493401 0.501063 2.5493401 0.5210565 2 P 0 ;0,1=11,2=270.000000
L 2.5493401 0.5210565 2.5443417 0.5210565 2 P 0 ;0,1=11,2=270.000000
L 2.5878651 4.002063 2.5878651 4.0320533 2 P 0 ;0,1=0,2=0.000000
L 2.5878651 4.0320533 2.6028603 4.0170582 2 P 0 ;0,1=0,2=0.000000
L 2.5948425 2.977063 2.5948425 3.037063 3 P 0
L 2.6028603 4.0170582 2.5828668 4.0170582 2 P 0 ;0,1=0,2=0.000000
L 2.6043307 3.0857071 2.6043307 3.0957039 2 P 0 ;0,1=3,2=270.000000
L 2.6043307 3.0957039 2.6093291 3.1007022 2 P 0 ;0,1=3,2=270.000000
L 2.6043307 3.1156974 2.6093291 3.110699 2 P 0 ;0,1=3,2=270.000000
L 2.6043307 3.1256942 2.6043307 3.1156974 2 P 0 ;0,1=3,2=270.000000
L 2.6043307 3.1456877 2.6043307 3.1556845 2 P 0 ;0,1=3,2=270.000000
L 2.6043307 3.1556845 2.6093291 3.1606828 2 P 0 ;0,1=3,2=270.000000
L 2.6093291 3.0807087 2.6043307 3.0857071 2 P 0 ;0,1=3,2=270.000000
L 2.6093291 3.110699 2.6143275 3.110699 2 P 0 ;0,1=3,2=270.000000
L 2.6093291 3.1306925 2.6043307 3.1256942 2 P 0 ;0,1=3,2=270.000000
L 2.6093291 3.1406893 2.6043307 3.1456877 2 P 0 ;0,1=3,2=270.000000
L 2.6093291 3.1606828 2.6293226 3.1606828 2 P 0 ;0,1=3,2=270.000000
L 2.6143275 3.110699 2.6193259 3.1156974 2 P 0 ;0,1=3,2=270.000000
L 2.6143275 3.1306925 2.6093291 3.1306925 2 P 0 ;0,1=3,2=270.000000
L 2.6178554 4.002063 2.6228538 4.002063 2 P 0 ;0,1=0,2=0.000000
L 2.6193259 3.1156974 2.6193259 3.1256942 2 P 0 ;0,1=3,2=270.000000
L 2.6193259 3.1156974 2.6243242 3.110699 2 P 0 ;0,1=3,2=270.000000
L 2.6193259 3.1256942 2.6143275 3.1306925 2 P 0 ;0,1=3,2=270.000000
L 2.6193259 3.1456877 2.6193259 3.1606828 2 P 0 ;0,1=3,2=270.000000
L 2.6228538 4.002063 2.6228538 4.0320533 2 P 0 ;0,1=0,2=0.000000
L 2.6228538 4.0320533 2.6278522 4.0270549 2 P 0 ;0,1=0,2=0.000000
L 2.6243242 3.110699 2.6293226 3.110699 2 P 0 ;0,1=3,2=270.000000
L 2.6243242 3.1306925 2.6193259 3.1256942 2 P 0 ;0,1=3,2=270.000000
L 2.6243242 3.1406893 2.6193259 3.1456877 2 P 0 ;0,1=3,2=270.000000
L 2.6278522 4.002063 2.6178554 4.002063 2 P 0 ;0,1=0,2=0.000000
L 2.6293226 3.0807087 2.6093291 3.0807087 2 P 0 ;0,1=3,2=270.000000
L 2.6293226 3.1007022 2.634321 3.0957039 2 P 0 ;0,1=3,2=270.000000
L 2.6293226 3.110699 2.634321 3.1156974 2 P 0 ;0,1=3,2=270.000000
L 2.6293226 3.1306925 2.6243242 3.1306925 2 P 0 ;0,1=3,2=270.000000
L 2.6293226 3.1406893 2.6243242 3.1406893 2 P 0 ;0,1=3,2=270.000000
L 2.6293226 3.1606828 2.634321 3.1556845 2 P 0 ;0,1=3,2=270.000000
L 2.634321 3.0857071 2.6293226 3.0807087 2 P 0 ;0,1=3,2=270.000000
L 2.634321 3.0957039 2.634321 3.0857071 2 P 0 ;0,1=3,2=270.000000
L 2.634321 3.1156974 2.634321 3.1256942 2 P 0 ;0,1=3,2=270.000000
L 2.634321 3.1256942 2.6293226 3.1306925 2 P 0 ;0,1=3,2=270.000000
L 2.634321 3.1456877 2.6293226 3.1406893 2 P 0 ;0,1=3,2=270.000000
L 2.634321 3.1556845 2.634321 3.1456877 2 P 0 ;0,1=3,2=270.000000
L 2.6343498 0.4460808 2.6343498 0.4560776 2 P 0 ;0,1=10,2=270.000000
L 2.6343498 0.4560776 2.6393482 0.4610759 2 P 0 ;0,1=10,2=270.000000
L 2.6343498 0.4860679 2.6643401 0.4860679 2 P 0 ;0,1=10,2=270.000000
L 2.6343498 0.5060614 2.6393482 0.501063 2 P 0 ;0,1=10,2=270.000000
L 2.6343498 0.5160582 2.6343498 0.5060614 2 P 0 ;0,1=10,2=270.000000
L 2.637849 4.0070614 2.637849 4.0320533 2 P 0 ;0,1=0,2=0.000000
L 2.6393482 0.4410824 2.6343498 0.4460808 2 P 0 ;0,1=10,2=270.000000
L 2.6393482 0.501063 2.6443466 0.501063 2 P 0 ;0,1=10,2=270.000000
L 2.6393482 0.5210565 2.6343498 0.5160582 2 P 0 ;0,1=10,2=270.000000
L 2.6428473 4.002063 2.637849 4.0070614 2 P 0 ;0,1=0,2=0.000000
L 2.6443466 0.501063 2.649345 0.5060614 2 P 0 ;0,1=10,2=270.000000
L 2.6443466 0.5210565 2.6393482 0.5210565 2 P 0 ;0,1=10,2=270.000000
L 2.649345 0.4710727 2.649345 0.4910662 2 P 0 ;0,1=10,2=270.000000
L 2.649345 0.5060614 2.649345 0.5160582 2 P 0 ;0,1=10,2=270.000000
L 2.649345 0.5060614 2.6543433 0.501063 2 P 0 ;0,1=10,2=270.000000
L 2.649345 0.5160582 2.6443466 0.5210565 2 P 0 ;0,1=10,2=270.000000
L 2.6528441 4.002063 2.6428473 4.002063 2 P 0 ;0,1=0,2=0.000000
L 2.6543433 0.501063 2.6593417 0.501063 2 P 0 ;0,1=10,2=270.000000
L 2.6543433 0.5210565 2.649345 0.5160582 2 P 0 ;0,1=10,2=270.000000
L 2.6578425 4.0070614 2.6528441 4.002063 2 P 0 ;0,1=0,2=0.000000
L 2.6578425 4.0320533 2.6578425 4.0070614 2 P 0 ;0,1=0,2=0.000000
L 2.6593417 0.4410824 2.6393482 0.4410824 2 P 0 ;0,1=10,2=270.000000
L 2.6593417 0.4610759 2.6643401 0.4560776 2 P 0 ;0,1=10,2=270.000000
L 2.6593417 0.501063 2.6643401 0.5060614 2 P 0 ;0,1=10,2=270.000000
L 2.6593417 0.5210565 2.6543433 0.5210565 2 P 0 ;0,1=10,2=270.000000
L 2.6628937 2.7168583 2.6628937 3.9668583 2 P 0
L 2.6643401 0.4460808 2.6593417 0.4410824 2 P 0 ;0,1=10,2=270.000000
L 2.6643401 0.4560776 2.6643401 0.4460808 2 P 0 ;0,1=10,2=270.000000
L 2.6643401 0.4860679 2.649345 0.4710727 2 P 0 ;0,1=10,2=270.000000
L 2.6643401 0.5060614 2.6643401 0.5160582 2 P 0 ;0,1=10,2=270.000000
L 2.6643401 0.5160582 2.6593417 0.5210565 2 P 0 ;0,1=10,2=270.000000
L 2.6708425 2.977063 2.6708425 3.037063 3 P 0
L 2.7023498 0.4460808 2.7023498 0.4560776 2 P 0 ;0,1=9,2=270.000000
L 2.7023498 0.4560776 2.7073482 0.4610759 2 P 0 ;0,1=9,2=270.000000
L 2.7023498 0.4860679 2.7323401 0.4860679 2 P 0 ;0,1=9,2=270.000000
L 2.7023498 0.5060614 2.7023498 0.5160582 2 P 0 ;0,1=9,2=270.000000
L 2.7023498 0.5160582 2.7073482 0.5210565 2 P 0 ;0,1=9,2=270.000000
L 2.7073482 0.4410824 2.7023498 0.4460808 2 P 0 ;0,1=9,2=270.000000
L 2.7073482 0.501063 2.7023498 0.5060614 2 P 0 ;0,1=9,2=270.000000
L 2.7073482 0.5210565 2.7273417 0.5210565 2 P 0 ;0,1=9,2=270.000000
L 2.717345 0.4710727 2.717345 0.4910662 2 P 0 ;0,1=9,2=270.000000
L 2.717345 0.5060614 2.717345 0.5210565 2 P 0 ;0,1=9,2=270.000000
L 2.7223433 0.501063 2.717345 0.5060614 2 P 0 ;0,1=9,2=270.000000
L 2.7273417 0.4410824 2.7073482 0.4410824 2 P 0 ;0,1=9,2=270.000000
L 2.7273417 0.4610759 2.7323401 0.4560776 2 P 0 ;0,1=9,2=270.000000
L 2.7273417 0.501063 2.7223433 0.501063 2 P 0 ;0,1=9,2=270.000000
L 2.7273417 0.5210565 2.7323401 0.5160582 2 P 0 ;0,1=9,2=270.000000
L 2.7323401 0.4460808 2.7273417 0.4410824 2 P 0 ;0,1=9,2=270.000000
L 2.7323401 0.4560776 2.7323401 0.4460808 2 P 0 ;0,1=9,2=270.000000
L 2.7323401 0.4860679 2.717345 0.4710727 2 P 0 ;0,1=9,2=270.000000
L 2.7323401 0.5060614 2.7273417 0.501063 2 P 0 ;0,1=9,2=270.000000
L 2.7323401 0.5160582 2.7323401 0.5060614 2 P 0 ;0,1=9,2=270.000000
L 2.789849 3.0025687 2.7948473 2.9975703 2 P 0 ;0,1=4,2=0.000000
L 2.789849 3.0225622 2.789849 3.0025687 2 P 0 ;0,1=4,2=0.000000
L 2.7933498 0.4460808 2.7933498 0.4560776 2 P 0 ;0,1=8,2=270.000000
L 2.7933498 0.4560776 2.7983482 0.4610759 2 P 0 ;0,1=8,2=270.000000
L 2.7933498 0.4760711 2.7983482 0.4710727 2 P 0 ;0,1=8,2=270.000000
L 2.7933498 0.4860679 2.7933498 0.4760711 2 P 0 ;0,1=8,2=270.000000
L 2.7933498 0.5060614 2.7983482 0.501063 2 P 0 ;0,1=8,2=270.000000
L 2.7933498 0.5160582 2.7933498 0.5060614 2 P 0 ;0,1=8,2=270.000000
L 2.7948473 2.9975703 2.8048441 2.9975703 2 P 0 ;0,1=4,2=0.000000
L 2.7948473 3.0275606 2.789849 3.0225622 2 P 0 ;0,1=4,2=0.000000
L 2.7983482 0.4410824 2.7933498 0.4460808 2 P 0 ;0,1=8,2=270.000000
L 2.7983482 0.4910662 2.7933498 0.4860679 2 P 0 ;0,1=8,2=270.000000
L 2.7983482 0.501063 2.8183417 0.501063 2 P 0 ;0,1=8,2=270.000000
L 2.7983482 0.5210565 2.7933498 0.5160582 2 P 0 ;0,1=8,2=270.000000
L 2.8048441 2.9975703 2.8098425 3.0025687 2 P 0 ;0,1=4,2=0.000000
L 2.8048441 3.0275606 2.7948473 3.0275606 2 P 0 ;0,1=4,2=0.000000
L 2.808345 0.4710727 2.8133433 0.4810695 2 P 0 ;0,1=8,2=270.000000
L 2.808345 0.4910662 2.7983482 0.4910662 2 P 0 ;0,1=8,2=270.000000
L 2.8098425 3.0025687 2.8098425 3.0225622 2 P 0 ;0,1=4,2=0.000000
L 2.8098425 3.0225622 2.8048441 3.0275606 2 P 0 ;0,1=4,2=0.000000
L 2.8133433 0.4810695 2.8133433 0.4860679 2 P 0 ;0,1=8,2=270.000000
L 2.8133433 0.4860679 2.808345 0.4910662 2 P 0 ;0,1=8,2=270.000000
L 2.8183417 0.4410824 2.7983482 0.4410824 2 P 0 ;0,1=8,2=270.000000
L 2.8183417 0.4610759 2.8233401 0.4560776 2 P 0 ;0,1=8,2=270.000000
L 2.8183417 0.501063 2.8233401 0.5060614 2 P 0 ;0,1=8,2=270.000000
L 2.8183417 0.5210565 2.7983482 0.5210565 2 P 0 ;0,1=8,2=270.000000
L 2.8198393 3.0025687 2.8198393 3.0225622 2 P 0 ;0,1=4,2=0.000000
L 2.8198393 3.0225622 2.8248376 3.0275606 2 P 0 ;0,1=4,2=0.000000
L 2.8233401 0.4460808 2.8183417 0.4410824 2 P 0 ;0,1=8,2=270.000000
L 2.8233401 0.4560776 2.8233401 0.4460808 2 P 0 ;0,1=8,2=270.000000
L 2.8233401 0.4710727 2.808345 0.4710727 2 P 0 ;0,1=8,2=270.000000
L 2.8233401 0.4910662 2.8233401 0.4710727 2 P 0 ;0,1=8,2=270.000000
L 2.8233401 0.5060614 2.8233401 0.5160582 2 P 0 ;0,1=8,2=270.000000
L 2.8233401 0.5160582 2.8183417 0.5210565 2 P 0 ;0,1=8,2=270.000000
L 2.8248376 2.9975703 2.8198393 3.0025687 2 P 0 ;0,1=4,2=0.000000
L 2.8248376 3.0275606 2.8348344 3.0275606 2 P 0 ;0,1=4,2=0.000000
L 2.8348344 2.9975703 2.8248376 2.9975703 2 P 0 ;0,1=4,2=0.000000
L 2.8348344 3.0125655 2.8198393 3.0125655 2 P 0 ;0,1=4,2=0.000000
L 2.8348344 3.0275606 2.8398328 3.0225622 2 P 0 ;0,1=4,2=0.000000
L 2.8398328 3.0025687 2.8348344 2.9975703 2 P 0 ;0,1=4,2=0.000000
L 2.8398328 3.0175638 2.8348344 3.0125655 2 P 0 ;0,1=4,2=0.000000
L 2.8398328 3.0225622 2.8398328 3.0175638 2 P 0 ;0,1=4,2=0.000000
L 2.8498296 3.0225622 2.8548279 3.0275606 2 P 0 ;0,1=4,2=0.000000
L 2.8548279 2.9975703 2.8498296 3.0025687 2 P 0 ;0,1=4,2=0.000000
L 2.8548279 3.0275606 2.8648247 3.0275606 2 P 0 ;0,1=4,2=0.000000
L 2.8643498 0.4460808 2.8643498 0.4560776 2 P 0 ;0,1=7,2=270.000000
L 2.8643498 0.4560776 2.8693482 0.4610759 2 P 0 ;0,1=7,2=270.000000
L 2.8643498 0.4760711 2.8693482 0.4710727 2 P 0 ;0,1=7,2=270.000000
L 2.8643498 0.4860679 2.8643498 0.4760711 2 P 0 ;0,1=7,2=270.000000
L 2.8643498 0.501063 2.8643498 0.5110598 2 P 0 ;0,1=7,2=270.000000
L 2.8643498 0.5060614 2.8943401 0.5060614 2 P 0 ;0,1=7,2=270.000000
L 2.8643498 0.5110598 2.8643498 0.5060614 2 P 0 ;0,1=7,2=270.000000
L 2.8648247 2.9975703 2.8548279 2.9975703 2 P 0 ;0,1=4,2=0.000000
L 2.8648247 3.0275606 2.8698231 3.0225622 2 P 0 ;0,1=4,2=0.000000
L 2.8693482 0.4410824 2.8643498 0.4460808 2 P 0 ;0,1=7,2=270.000000
L 2.8693482 0.4910662 2.8643498 0.4860679 2 P 0 ;0,1=7,2=270.000000
L 2.8698231 3.0025687 2.8648247 2.9975703 2 P 0 ;0,1=4,2=0.000000
L 2.8698231 3.0225622 2.8698231 3.0025687 2 P 0 ;0,1=4,2=0.000000
L 2.879345 0.4710727 2.8843433 0.4810695 2 P 0 ;0,1=7,2=270.000000
L 2.879345 0.4910662 2.8693482 0.4910662 2 P 0 ;0,1=7,2=270.000000
L 2.8843433 0.4810695 2.8843433 0.4860679 2 P 0 ;0,1=7,2=270.000000
L 2.8843433 0.4860679 2.879345 0.4910662 2 P 0 ;0,1=7,2=270.000000
L 2.8893417 0.4410824 2.8693482 0.4410824 2 P 0 ;0,1=7,2=270.000000
L 2.8893417 0.4610759 2.8943401 0.4560776 2 P 0 ;0,1=7,2=270.000000
L 2.8943401 0.4460808 2.8893417 0.4410824 2 P 0 ;0,1=7,2=270.000000
L 2.8943401 0.4560776 2.8943401 0.4460808 2 P 0 ;0,1=7,2=270.000000
L 2.8943401 0.4710727 2.879345 0.4710727 2 P 0 ;0,1=7,2=270.000000
L 2.8943401 0.4910662 2.8943401 0.4710727 2 P 0 ;0,1=7,2=270.000000
L 2.8943401 0.5060614 2.8893417 0.501063 2 P 0 ;0,1=7,2=270.000000
L 2.9593498 0.4460808 2.9593498 0.4560776 2 P 0 ;0,1=6,2=270.000000
L 2.9593498 0.4560776 2.9643482 0.4610759 2 P 0 ;0,1=6,2=270.000000
L 2.9593498 0.4760711 2.9643482 0.4710727 2 P 0 ;0,1=6,2=270.000000
L 2.9593498 0.4860679 2.9593498 0.4760711 2 P 0 ;0,1=6,2=270.000000
L 2.9593498 0.501063 2.9793433 0.5210565 2 P 0 ;0,1=6,2=270.000000
L 2.9593498 0.5210565 2.9593498 0.501063 2 P 0 ;0,1=6,2=270.000000
L 2.9643482 0.4410824 2.9593498 0.4460808 2 P 0 ;0,1=6,2=270.000000
L 2.9643482 0.4910662 2.9593498 0.4860679 2 P 0 ;0,1=6,2=270.000000
L 2.974345 0.4710727 2.9793433 0.4810695 2 P 0 ;0,1=6,2=270.000000
L 2.974345 0.4910662 2.9643482 0.4910662 2 P 0 ;0,1=6,2=270.000000
L 2.9793433 0.4810695 2.9793433 0.4860679 2 P 0 ;0,1=6,2=270.000000
L 2.9793433 0.4860679 2.974345 0.4910662 2 P 0 ;0,1=6,2=270.000000
L 2.9793433 0.5210565 2.9843417 0.5210565 2 P 0 ;0,1=6,2=270.000000
L 2.9843417 0.4410824 2.9643482 0.4410824 2 P 0 ;0,1=6,2=270.000000
L 2.9843417 0.4610759 2.9893401 0.4560776 2 P 0 ;0,1=6,2=270.000000
L 2.9843417 0.5210565 2.9893401 0.5160582 2 P 0 ;0,1=6,2=270.000000
L 2.9893401 0.4460808 2.9843417 0.4410824 2 P 0 ;0,1=6,2=270.000000
L 2.9893401 0.4560776 2.9893401 0.4460808 2 P 0 ;0,1=6,2=270.000000
L 2.9893401 0.4710727 2.974345 0.4710727 2 P 0 ;0,1=6,2=270.000000
L 2.9893401 0.4910662 2.9893401 0.4710727 2 P 0 ;0,1=6,2=270.000000
L 2.9893401 0.5060614 2.9843417 0.501063 2 P 0 ;0,1=6,2=270.000000
L 2.9893401 0.5160582 2.9893401 0.5060614 2 P 0 ;0,1=6,2=270.000000
L 3.0253498 0.4460808 3.0253498 0.4560776 2 P 0 ;0,1=5,2=270.000000
L 3.0253498 0.4560776 3.0303482 0.4610759 2 P 0 ;0,1=5,2=270.000000
L 3.0253498 0.4760711 3.0303482 0.4710727 2 P 0 ;0,1=5,2=270.000000
L 3.0253498 0.4860679 3.0253498 0.4760711 2 P 0 ;0,1=5,2=270.000000
L 3.0253498 0.5060614 3.0303482 0.501063 2 P 0 ;0,1=5,2=270.000000
L 3.0253498 0.5160582 3.0253498 0.5060614 2 P 0 ;0,1=5,2=270.000000
L 3.0303482 0.4410824 3.0253498 0.4460808 2 P 0 ;0,1=5,2=270.000000
L 3.0303482 0.4910662 3.0253498 0.4860679 2 P 0 ;0,1=5,2=270.000000
L 3.0303482 0.5210565 3.0253498 0.5160582 2 P 0 ;0,1=5,2=270.000000
L 3.0353466 0.5210565 3.0303482 0.5210565 2 P 0 ;0,1=5,2=270.000000
L 3.040345 0.4710727 3.0453433 0.4810695 2 P 0 ;0,1=5,2=270.000000
L 3.040345 0.4910662 3.0303482 0.4910662 2 P 0 ;0,1=5,2=270.000000
L 3.040345 0.5110598 3.040345 0.5160582 2 P 0 ;0,1=5,2=270.000000
L 3.040345 0.5160582 3.0353466 0.5210565 2 P 0 ;0,1=5,2=270.000000
L 3.040345 0.5160582 3.040345 0.5110598 2 P 0 ;0,1=5,2=270.000000
L 3.0453433 0.4810695 3.0453433 0.4860679 2 P 0 ;0,1=5,2=270.000000
L 3.0453433 0.4860679 3.040345 0.4910662 2 P 0 ;0,1=5,2=270.000000
L 3.0453433 0.5210565 3.040345 0.5160582 2 P 0 ;0,1=5,2=270.000000
L 3.0503417 0.4410824 3.0303482 0.4410824 2 P 0 ;0,1=5,2=270.000000
L 3.0503417 0.4610759 3.0553401 0.4560776 2 P 0 ;0,1=5,2=270.000000
L 3.0503417 0.501063 3.0553401 0.5060614 2 P 0 ;0,1=5,2=270.000000
L 3.0503417 0.5210565 3.0453433 0.5210565 2 P 0 ;0,1=5,2=270.000000
L 3.0553401 0.4460808 3.0503417 0.4410824 2 P 0 ;0,1=5,2=270.000000
L 3.0553401 0.4560776 3.0553401 0.4460808 2 P 0 ;0,1=5,2=270.000000
L 3.0553401 0.4710727 3.040345 0.4710727 2 P 0 ;0,1=5,2=270.000000
L 3.0553401 0.4910662 3.0553401 0.4710727 2 P 0 ;0,1=5,2=270.000000
L 3.0553401 0.5060614 3.0553401 0.5160582 2 P 0 ;0,1=5,2=270.000000
L 3.0553401 0.5160582 3.0503417 0.5210565 2 P 0 ;0,1=5,2=270.000000

### steps/pcb/layers/bottom_paste/features
#Layer_Color=128
#
#Feature symbol names
#
$0 r3.937
$1 r1
$2 rect82.874x44.0945
$3 rect28x165
$4 rect28x126
$5 rect25.1969x26.7717
$6 rect57.0866x45.2756
$7 rect26.7717x25.1969
$8 rect45.2756x57.0866

#
#Feature attribute names
#
@0 .geometry
@1 .pad_usage

#
#Feature attribute text strings
#
&0 SMD_RoundX82.8740Y44.0945
&1 SMD_RoundX28.0000Y165.0000
&2 SMD_RoundX28.0000Y126.0000
&3 SMD_RoundX25.1969Y26.7717
&4 SMD_RoundX57.0866Y45.2756
&5 SMD_RoundX26.7717Y25.1969
&6 SMD_RoundX45.2756Y57.0866

#
#Layer features
#
A 1.7712204 0.4310709 1.6275196 0.4310709 1.69937 0.4310709 0 P 0 N
L -0.0001175 0.177913 0.5908825 0.177913 1 P 0
L -0.0004331 0.1781182 0.5901181 0.1781182 0 P 0
L 0.5901181 0.1781182 0.5901181 0.5029213 0 P 0
L 0.5901181 0.5029213 1.312559 0.5029213 0 P 0
L 0.5908825 0.177913 0.5908825 0.502913 1 P 0
L 1.312559 0.313945 1.312559 0.5029213 0 P 0
L 1.312559 0.313945 1.6275197 0.313945 0 P 0
L 1.6275197 0.313945 1.6275197 0.4310709 0 P 0
P 1.7972451 0.1572953 4 P 0 0 ;0=2,1=0
P 1.8366151 0.1377953 3 P 0 0 ;0=1,1=0
P 1.8759851 0.1377953 3 P 0 0 ;0=1,1=0
P 1.9153551 0.1377953 3 P 0 0 ;0=1,1=0
P 1.9547251 0.1377953 3 P 0 0 ;0=1,1=0
P 1.9940951 0.1377953 3 P 0 0 ;0=1,1=0
P 2.0334651 0.1377953 3 P 0 0 ;0=1,1=0
P 2.0728351 0.1377953 3 P 0 0 ;0=1,1=0
P 2.1122051 0.1377953 3 P 0 0 ;0=1,1=0
P 2.1515751 0.1377953 3 P 0 0 ;0=1,1=0
P 2.1909451 0.1377953 3 P 0 0 ;0=1,1=0
P 2.3090551 0.1377953 3 P 0 0 ;0=1,1=0
P 2.3274094 2.944063 8 P 0 0 ;0=6,1=0
P 2.3348425 3.0428426 2 P 0 0 ;0=0,1=0
P 2.3348425 3.1215827 2 P 0 0 ;0=0,1=0
P 2.3348425 3.2003229 2 P 0 0 ;0=0,1=0
P 2.3348425 3.279063 2 P 0 0 ;0=0,1=0
P 2.3484251 0.1377953 3 P 0 0 ;0=1,1=0
P 2.3498425 0.3291339 5 P 0 0 ;0=3,1=0
P 2.3498425 0.3629922 5 P 0 0 ;0=3,1=0
P 2.3519134 2.854063 7 P 0 0 ;0=5,1=0
P 2.3857717 2.854063 7 P 0 0 ;0=5,1=0
P 2.3877951 0.1377953 3 P 0 0 ;0=1,1=0
P 2.3898425 0.3291339 5 P 0 0 ;0=3,1=0
P 2.3898425 0.3629922 5 P 0 0 ;0=3,1=0
P 2.3982756 2.944063 8 P 0 0 ;0=6,1=0
P 2.4271651 0.1377953 3 P 0 0 ;0=1,1=0
P 2.4665351 0.1377953 3 P 0 0 ;0=1,1=0
P 2.4688425 0.3291339 5 P 0 0 ;0=3,1=0
P 2.4688425 0.3629922 5 P 0 0 ;0=3,1=0
P 2.5059051 0.1377953 3 P 0 0 ;0=1,1=0
P 2.5098425 3.0428426 2 P 0 0 ;0=0,1=0
P 2.5098425 3.1215827 2 P 0 0 ;0=0,1=0
P 2.5098425 3.2003229 2 P 0 0 ;0=0,1=0
P 2.5098425 3.279063 2 P 0 0 ;0=0,1=0
P 2.5118425 0.3291339 5 P 0 0 ;0=3,1=0
P 2.5118425 0.3629922 5 P 0 0 ;0=3,1=0
P 2.5452751 0.1377953 3 P 0 0 ;0=1,1=0
P 2.5846451 0.1377953 3 P 0 0 ;0=1,1=0
P 2.6240151 0.1377953 3 P 0 0 ;0=1,1=0
P 2.6328425 2.9716299 6 P 0 0 ;0=4,1=0
P 2.6328425 3.0424961 6 P 0 0 ;0=4,1=0
P 2.6633851 0.1377953 3 P 0 0 ;0=1,1=0
P 2.6648425 0.3291339 5 P 0 0 ;0=3,1=0
P 2.6648425 0.3629922 5 P 0 0 ;0=3,1=0
P 2.7027551 0.1377953 3 P 0 0 ;0=1,1=0
P 2.7048425 0.3291339 5 P 0 0 ;0=3,1=0
P 2.7048425 0.3629922 5 P 0 0 ;0=3,1=0
P 2.7118425 3.0031338 5 P 0 0 ;0=3,1=0
P 2.7118425 3.0369921 5 P 0 0 ;0=3,1=0
P 2.7421251 0.1377953 3 P 0 0 ;0=1,1=0
P 2.7814951 0.1377953 3 P 0 0 ;0=1,1=0
P 2.8198425 0.3291339 5 P 0 0 ;0=3,1=0
P 2.8198425 0.3629922 5 P 0 0 ;0=3,1=0
P 2.8208651 0.1377953 3 P 0 0 ;0=1,1=0
P 2.8548425 0.3291339 5 P 0 0 ;0=3,1=0
P 2.8548425 0.3629922 5 P 0 0 ;0=3,1=0
P 2.8602351 0.1377953 3 P 0 0 ;0=1,1=0
P 2.8996051 0.1377953 3 P 0 0 ;0=1,1=0
P 2.9389751 0.1377953 3 P 0 0 ;0=1,1=0
P 2.9783451 0.1377953 3 P 0 0 ;0=1,1=0
P 2.9798425 0.3291339 5 P 0 0 ;0=3,1=0
P 2.9798425 0.3629922 5 P 0 0 ;0=3,1=0
P 3.0177151 0.1377953 3 P 0 0 ;0=1,1=0
P 3.0198425 0.3291339 5 P 0 0 ;0=3,1=0
P 3.0198425 0.3629922 5 P 0 0 ;0=3,1=0
P 3.0570851 0.1377953 3 P 0 0 ;0=1,1=0
P 3.0964551 0.1377953 3 P 0 0 ;0=1,1=0

### steps/pcb/layers/bottom_solder/features
#Layer_Color=16711935
#
#Feature symbol names
#
$0 r3.937
$1 r1
$2 rect314.9607x135.8267
$3 rect1354.3307x230.315
$4 rect90.874x52.0945
$5 rect36x173
$6 rect36x134
$7 rect33.1969x34.7717
$8 rect65.0866x53.2756
$9 rect34.7717x33.1969
$10 rect53.2756x65.0866
$11 r39.4961
$12 r73.9843
$13 r8
$14 r69.0236
$15 s69.0236
$16 r83
$17 r106.4252
$18 oval96.5827x185.1654
$19 oval185.1654x96.5827
$20 oval204.8504x106.4252
$21 r120
$22 r128
$23 s8
$24 r29.66
$25 r63
$26 s63
$27 r58
$28 r258
$29 r24
$30 r208

#
#Feature attribute names
#
@0 .geometry
@1 .pad_usage

#
#Feature attribute text strings
#
&0 SMD_RoundX82.8740Y44.0945
&1 SMD_RoundX28.0000Y165.0000
&2 SMD_RoundX28.0000Y126.0000
&3 SMD_RoundX25.1969Y26.7717
&4 SMD_RoundX57.0866Y45.2756
&5 SMD_RoundX26.7717Y25.1969
&6 SMD_RoundX45.2756Y57.0866
&7 Pad_Simple_X31.4961Y31.4961H35.4331C75.4331
&8 Pad_Simple_X65.9843Y65.9843H65.9843C105.9843
&9 Pad_Simple_X0.0000Y0.0000H29.9213C69.9213
&10 Pad_Simple_X61.0236Y61.0236H41.3386C81.3386
&11 Pad_Simple_X75.0000Y75.0000H50.0000C90.0000
&12 Pad_Simple_X98.4252Y98.4252H64.9606C104.9606
&13 Pad_Simple_X88.5827Y177.1654H39.3701C79.3701
&14 Pad_Simple_X177.1654Y88.5827H39.3701C79.3701
&15 Pad_Simple_X196.8504Y98.4252H39.3701C79.3701
&16 Pad_Simple_X112.0000Y112.0000H60.0000C100.0000
&17 Pad_Simple_X120.0000Y120.0000H68.0000C108.0000
&18 Pad_Simple_X0.0000Y0.0000H118.1100C158.1100
&19 Pad_Simple_X21.6600Y21.6600H21.6600C61.6600
&20 Pad_Simple_X55.0000Y55.0000H30.0000C70.0000
&21 Pad_Simple_X50.0000Y50.0000H118.1102C158.1102
&22 Pad_Simple_X98.4252Y98.4252H70.8661C110.8661
&23 Pad_Complex_X50.0000Y50.0000H118.1102C158.1102
&24 Pad_Simple_X250.0000Y250.0000H125.1969C165.1969
&25 VIA_RoundD16.0000H8.0000C48.0000
&26 VIA_RoundD200.0000H125.9843C165.9843

#
#Layer features
#
A 1.7712204 0.4310709 1.6275196 0.4310709 1.69937 0.4310709 0 P 0 N
L -0.0001175 0.177913 0.5908825 0.177913 1 P 0
L -0.0004331 0.1781182 0.5901181 0.1781182 0 P 0
L 0.5901181 0.1781182 0.5901181 0.5029213 0 P 0
L 0.5901181 0.5029213 1.312559 0.5029213 0 P 0
L 0.5908825 0.177913 0.5908825 0.502913 1 P 0
L 1.312559 0.313945 1.312559 0.5029213 0 P 0
L 1.312559 0.313945 1.6275197 0.313945 0 P 0
L 1.6275197 0.313945 1.6275197 0.4310709 0 P 0
P 0.0998425 0.806063 22 P 0 0 ;0=17,1=0
P 0.0998425 1.006063 22 P 0 0 ;0=17,1=0
P 0.0998425 1.331063 22 P 0 0 ;0=17,1=0
P 0.0998425 1.531063 22 P 0 0 ;0=17,1=0
P 0.0998425 1.856063 22 P 0 0 ;0=17,1=0
P 0.0998425 2.056063 22 P 0 0 ;0=17,1=0
P 0.0998425 2.381063 22 P 0 0 ;0=17,1=0
P 0.0998425 2.581063 22 P 0 0 ;0=17,1=0
P 0.1998425 0.906063 21 P 0 0 ;0=16,1=0
P 0.1998425 1.431063 21 P 0 0 ;0=16,1=0
P 0.1998425 1.956063 21 P 0 0 ;0=16,1=0
P 0.1998425 2.481063 21 P 0 0 ;0=16,1=0
P 0.285433 4.152063 28 P 0 0 ;0=24,1=0
P 0.2854331 0.3681102 28 P 0 0 ;0=24,1=0
P 0.2998425 0.806063 22 P 0 0 ;0=17,1=0
P 0.2998425 1.006063 22 P 0 0 ;0=17,1=0
P 0.2998425 1.331063 22 P 0 0 ;0=17,1=0
P 0.2998425 1.531063 22 P 0 0 ;0=17,1=0
P 0.2998425 1.856063 22 P 0 0 ;0=17,1=0
P 0.2998425 2.056063 22 P 0 0 ;0=17,1=0
P 0.2998425 2.381063 22 P 0 0 ;0=17,1=0
P 0.2998425 2.581063 22 P 0 0 ;0=17,1=0
P 1.4576771 4.053937 25 P 0 0 ;0=20,1=0
P 1.4576771 4.153937 25 P 0 0 ;0=20,1=0
P 1.4576771 4.253937 26 P 0 0 ;0=20,1=0
P 1.4704724 0.2450787 2 P 0 0
P 1.6519425 2.486293 23 P 0 0 ;0=18,1=0
P 1.6529425 0.916293 23 P 0 0 ;0=18,1=0
P 1.6968325 1.309833 24 P 0 0 ;0=19,1=0
P 1.6968325 2.097233 24 P 0 0 ;0=19,1=0
P 1.7972451 0.1572953 6 P 0 0 ;0=2,1=0
P 1.8366151 0.1377953 5 P 0 0 ;0=1,1=0
P 1.8759851 0.1377953 5 P 0 0 ;0=1,1=0
P 1.9153551 0.1377953 5 P 0 0 ;0=1,1=0
P 1.9547251 0.1377953 5 P 0 0 ;0=1,1=0
P 1.9940951 0.1377953 5 P 0 0 ;0=1,1=0
P 2.0334651 0.1377953 5 P 0 0 ;0=1,1=0
P 2.0433071 4.057874 25 P 0 0 ;0=20,1=0
P 2.0433071 4.157874 25 P 0 0 ;0=20,1=0
P 2.0433071 4.257874 26 P 0 0 ;0=20,1=0
P 2.0728351 0.1377953 5 P 0 0 ;0=1,1=0
P 2.1122051 0.1377953 5 P 0 0 ;0=1,1=0
P 2.1515751 0.1377953 5 P 0 0 ;0=1,1=0
P 2.1909451 0.1377953 5 P 0 0 ;0=1,1=0
P 2.2031325 2.438533 24 P 0 0 ;0=19,1=0
P 2.2031425 0.958593 24 P 0 0 ;0=19,1=0
P 2.3090551 0.1377953 5 P 0 0 ;0=1,1=0
P 2.3274094 2.944063 10 P 0 0 ;0=6,1=0
P 2.3348425 3.0428426 4 P 0 0 ;0=0,1=0
P 2.3348425 3.1215827 4 P 0 0 ;0=0,1=0
P 2.3348425 3.2003229 4 P 0 0 ;0=0,1=0
P 2.3348425 3.279063 4 P 0 0 ;0=0,1=0
P 2.3484251 0.1377953 5 P 0 0 ;0=1,1=0
P 2.3498425 0.3291339 7 P 0 0 ;0=3,1=0
P 2.3498425 0.3629922 7 P 0 0 ;0=3,1=0
P 2.3519134 2.854063 9 P 0 0 ;0=5,1=0
P 2.3857717 2.854063 9 P 0 0 ;0=5,1=0
P 2.3877951 0.1377953 5 P 0 0 ;0=1,1=0
P 2.3898425 0.3291339 7 P 0 0 ;0=3,1=0
P 2.3898425 0.3629922 7 P 0 0 ;0=3,1=0
P 2.3982756 2.944063 10 P 0 0 ;0=6,1=0
P 2.4223425 3.0822126 13 P 0 0 ;0=9,1=0
P 2.4223425 3.2396929 13 P 0 0 ;0=9,1=0
P 2.4223425 3.4438977 13 P 0 0 ;0=9,1=0
P 2.4223425 3.601378 13 P 0 0 ;0=9,1=0
P 2.4271651 0.1377953 5 P 0 0 ;0=1,1=0
P 2.4468503 0.1112205 3 P 0 0
P 2.4665351 0.1377953 5 P 0 0 ;0=1,1=0
P 2.4688425 0.3291339 7 P 0 0 ;0=3,1=0
P 2.4688425 0.3629922 7 P 0 0 ;0=3,1=0
P 2.5059051 0.1377953 5 P 0 0 ;0=1,1=0
P 2.5098425 3.0428426 4 P 0 0 ;0=0,1=0
P 2.5098425 3.1215827 4 P 0 0 ;0=0,1=0
P 2.5098425 3.2003229 4 P 0 0 ;0=0,1=0
P 2.5098425 3.279063 4 P 0 0 ;0=0,1=0
P 2.5118425 0.3291339 7 P 0 0 ;0=3,1=0
P 2.5118425 0.3629922 7 P 0 0 ;0=3,1=0
P 2.5452751 0.1377953 5 P 0 0 ;0=1,1=0
P 2.5846451 0.1377953 5 P 0 0 ;0=1,1=0
P 2.6240151 0.1377953 5 P 0 0 ;0=1,1=0
P 2.6328425 2.9716299 8 P 0 0 ;0=4,1=0
P 2.6328425 3.0424961 8 P 0 0 ;0=4,1=0
P 2.6633851 0.1377953 5 P 0 0 ;0=1,1=0
P 2.6648425 0.3291339 7 P 0 0 ;0=3,1=0
P 2.6648425 0.3629922 7 P 0 0 ;0=3,1=0
P 2.7027551 0.1377953 5 P 0 0 ;0=1,1=0
P 2.7048425 0.3291339 7 P 0 0 ;0=3,1=0
P 2.7048425 0.3629922 7 P 0 0 ;0=3,1=0
P 2.7118425 3.0031338 7 P 0 0 ;0=3,1=0
P 2.7118425 3.0369921 7 P 0 0 ;0=3,1=0
P 2.7421251 0.1377953 5 P 0 0 ;0=1,1=0
P 2.7814951 0.1377953 5 P 0 0 ;0=1,1=0
P 2.8198425 0.3291339 7 P 0 0 ;0=3,1=0
P 2.8198425 0.3629922 7 P 0 0 ;0=3,1=0
P 2.8208651 0.1377953 5 P 0 0 ;0=1,1=0
P 2.8548425 0.3291339 7 P 0 0 ;0=3,1=0
P 2.8548425 0.3629922 7 P 0 0 ;0=3,1=0
P 2.8602351 0.1377953 5 P 0 0 ;0=1,1=0
P 2.8996051 0.1377953 5 P 0 0 ;0=1,1=0
P 2.9389751 0.1377953 5 P 0 0 ;0=1,1=0
P 2.9783451 0.1377953 5 P 0 0 ;0=1,1=0
P 2.9798425 0.3291339 7 P 0 0 ;0=3,1=0
P 2.9798425 0.3629922 7 P 0 0 ;0=3,1=0
P 2.9905325 2.438533 24 P 0 0 ;0=19,1=0
P 2.9905425 0.958593 24 P 0 0 ;0=19,1=0
P 2.9948425 4.0861024 12 P 0 0 ;0=8,1=0
P 3.0177151 0.1377953 5 P 0 0 ;0=1,1=0
P 3.0198425 0.3291339 7 P 0 0 ;0=3,1=0
P 3.0198425 0.3629922 7 P 0 0 ;0=3,1=0
P 3.0570851 0.1377953 5 P 0 0 ;0=1,1=0
P 3.0964551 0.1377953 5 P 0 0 ;0=1,1=0
P 3.2948425 4.0861024 12 P 0 0 ;0=8,1=0
P 3.5717425 1.309793 24 P 0 0 ;0=19,1=0
P 3.5717425 2.097193 24 P 0 0 ;0=19,1=0
P 3.6179425 0.916293 23 P 0 0 ;0=18,1=0
P 3.6179425 2.486293 23 P 0 0 ;0=18,1=0
P 3.7848425 4.126063 11 P 0 0 ;0=7,1=0
P 3.9580709 4.126063 11 P 0 0 ;0=7,1=0
P 3.9797272 0.8906186 16 P 0 0 ;0=11,1=0
P 3.9797272 2.4890438 16 P 0 0 ;0=11,1=0
P 4.0624044 2.595343 16 P 0 0 ;0=11,1=0
P 4.1805146 2.595343 16 P 0 0 ;0=11,1=0
P 4.2986248 2.595343 16 P 0 0 ;0=11,1=0
P 4.3277559 1.0074803 15 P 0 0 ;0=10,1=0
P 4.3277559 2.3074803 14 P 0 0 ;0=10,1=0
P 4.7277559 2.3074803 14 P 0 0 ;0=10,1=0
P 4.9277559 1.0074803 14 P 0 0 ;0=10,1=0
P 4.9277559 2.3074803 14 P 0 0 ;0=10,1=0
P 5.1277559 1.0074803 14 P 0 0 ;0=10,1=0
P 5.1277559 2.3074803 14 P 0 0 ;0=10,1=0
P 5.3277559 1.0074803 14 P 0 0 ;0=10,1=0
P 5.3277559 2.3074803 14 P 0 0 ;0=10,1=0
P 5.5781524 0.8906186 16 P 0 0 ;0=11,1=0
P 5.5781524 1.6898312 16 P 0 0 ;0=11,1=0
P 5.5781524 2.4890438 16 P 0 0 ;0=11,1=0
P 5.7234252 3.8444882 17 P 0 0 ;0=12,1=0
P 5.7234252 4.0255906 17 P 0 0 ;0=12,1=0
P 5.9348031 3.9379527 18 P 0 0 ;0=13,1=0
P 6.1198425 3.8198425 20 P 0 0 ;0=15,1=0
P 6.1198425 4.056063 19 P 0 0 ;0=14,1=0
P 6.5694882 3.5895276 17 P 0 0 ;0=22,1=0
P 6.5694882 3.806063 17 P 0 0 ;0=22,1=0
P 6.5694882 4.0934646 27 P 0 0 ;0=23,1=0
P 6.7348425 3.5895276 17 P 0 0 ;0=22,1=0
P 6.7348425 3.806063 17 P 0 0 ;0=22,1=0
P 6.9001969 3.5895276 17 P 0 0 ;0=22,1=0
P 6.9001969 3.806063 17 P 0 0 ;0=22,1=0
P 6.9001969 4.0934646 27 P 0 0 ;0=21,1=0
P 0.149508 2.830047 30 P 0 0 ;0=26,1=1
P 0.149508 3.853669 30 P 0 0 ;0=26,1=1
P 0.6538425 1.551063 29 P 0 0 ;0=25,1=1
P 0.6539669 2.5938902 29 P 0 0 ;0=25,1=1
P 0.6548425 0.790063 29 P 0 0 ;0=25,1=1
P 0.6548425 1.314063 29 P 0 0 ;0=25,1=1
P 0.6548425 1.839063 29 P 0 0 ;0=25,1=1
P 0.6548425 2.073063 29 P 0 0 ;0=25,1=1
P 0.6548425 2.365063 29 P 0 0 ;0=25,1=1
P 0.6558425 1.028063 29 P 0 0 ;0=25,1=1
P 0.9370078 2.3179133 29 P 0 0 ;0=25,1=1
P 0.988189 1.7175197 29 P 0 0 ;0=25,1=1
P 0.9901575 0.6870079 29 P 0 0 ;0=25,1=1
P 0.996063 1.1870079 29 P 0 0 ;0=25,1=1
P 0.9968357 2.256036 29 P 0 0 ;0=25,1=1
P 1.0048425 0.906063 29 P 0 0 ;0=25,1=1
P 1.0088425 1.430063 29 P 0 0 ;0=25,1=1
P 1.0098425 1.956063 29 P 0 0 ;0=25,1=1
P 1.0208425 2.481063 29 P 0 0 ;0=25,1=1
P 1.2428425 1.472063 29 P 0 0 ;0=25,1=1
P 1.2488425 2.000063 29 P 0 0 ;0=25,1=1
P 1.2568425 0.942063 29 P 0 0 ;0=25,1=1
P 1.2618425 2.482063 29 P 0 0 ;0=25,1=1
P 1.2948425 4.256063 29 P 0 0 ;0=25,1=1
P 1.3454724 4.1751969 29 P 0 0 ;0=25,1=1
P 1.3937008 1.8169291 29 P 0 0 ;0=25,1=1
P 1.4084645 3.980315 29 P 0 0 ;0=25,1=1
P 1.4408425 3.557063 29 P 0 0 ;0=25,1=1
P 1.4598425 3.147063 29 P 0 0 ;0=25,1=1
P 1.5498425 3.621063 29 P 0 0 ;0=25,1=1
P 1.5578425 4.229063 29 P 0 0 ;0=25,1=1
P 1.5679134 1.2854331 29 P 0 0 ;0=25,1=1
P 1.5682025 2.067703 29 P 0 0 ;0=25,1=1
P 1.5698819 4.1712599 29 P 0 0 ;0=25,1=1
P 1.5748425 3.596063 29 P 0 0 ;0=25,1=1
P 1.6198425 2.121063 29 P 0 0 ;0=25,1=1
P 1.6708425 1.595063 29 P 0 0 ;0=25,1=1
P 1.6708425 1.694063 29 P 0 0 ;0=25,1=1
P 1.6718425 1.399063 29 P 0 0 ;0=25,1=1
P 1.6718425 1.497063 29 P 0 0 ;0=25,1=1
P 1.6718425 1.792063 29 P 0 0 ;0=25,1=1
P 1.6748425 1.989063 29 P 0 0 ;0=25,1=1
P 1.6758425 1.891063 29 P 0 0 ;0=25,1=1
P 1.6918425 4.079063 29 P 0 0 ;0=25,1=1
P 1.7148425 1.595063 29 P 0 0 ;0=25,1=1
P 1.7168425 1.399063 29 P 0 0 ;0=25,1=1
P 1.7188425 1.497063 29 P 0 0 ;0=25,1=1
P 1.7188425 1.792063 29 P 0 0 ;0=25,1=1
P 1.7198425 1.536063 29 P 0 0 ;0=25,1=1
P 1.7218425 1.694063 29 P 0 0 ;0=25,1=1
P 1.7218425 1.890063 29 P 0 0 ;0=25,1=1
P 1.7218425 1.989063 29 P 0 0 ;0=25,1=1
P 1.7268425 4.329374 29 P 0 0 ;0=25,1=1
P 1.7498425 4.110063 29 P 0 0 ;0=25,1=1
P 1.7548425 2.126063 29 P 0 0 ;0=25,1=1
P 1.7548425 3.661063 29 P 0 0 ;0=25,1=1
P 1.7798425 4.156063 29 P 0 0 ;0=25,1=1
P 1.7888425 4.329374 29 P 0 0 ;0=25,1=1
P 1.7978425 0.355063 29 P 0 0 ;0=25,1=1
P 1.7982283 1.3041339 29 P 0 0 ;0=25,1=1
P 1.8227825 1.674003 29 P 0 0 ;0=25,1=1
P 1.8326771 0.2559055 29 P 0 0 ;0=25,1=1
P 1.8326771 0.2874016 29 P 0 0 ;0=25,1=1
P 1.8498425 3.701063 29 P 0 0 ;0=25,1=1
P 1.8523622 0.2559055 29 P 0 0 ;0=25,1=1
P 1.8523622 0.2874016 29 P 0 0 ;0=25,1=1
P 1.8720472 0.2559055 29 P 0 0 ;0=25,1=1
P 1.8720472 0.2874016 29 P 0 0 ;0=25,1=1
P 1.8799377 1.811803 29 P 0 0 ;0=25,1=1
P 1.8848425 2.071063 29 P 0 0 ;0=25,1=1
P 1.8848425 3.601063 29 P 0 0 ;0=25,1=1
P 1.8938425 1.693063 29 P 0 0 ;0=25,1=1
P 1.8973025 1.516523 29 P 0 0 ;0=25,1=1
P 1.9038425 4.018063 29 P 0 0 ;0=25,1=1
P 1.9161425 0.244763 29 P 0 0 ;0=25,1=1
P 2.0048425 1.336063 29 P 0 0 ;0=25,1=1
P 2.0048425 3.816063 29 P 0 0 ;0=25,1=1
P 2.0288425 1.361663 29 P 0 0 ;0=25,1=1
P 2.0298425 3.836063 29 P 0 0 ;0=25,1=1
P 2.0348425 0.246063 29 P 0 0 ;0=25,1=1
P 2.0598425 1.386063 29 P 0 0 ;0=25,1=1
P 2.0598425 3.871063 29 P 0 0 ;0=25,1=1
P 2.0767716 0.2559055 29 P 0 0 ;0=25,1=1
P 2.0767716 0.2874016 29 P 0 0 ;0=25,1=1
P 2.0838425 1.411663 29 P 0 0 ;0=25,1=1
P 2.0848425 3.896063 29 P 0 0 ;0=25,1=1
P 2.1122047 0.2559055 29 P 0 0 ;0=25,1=1
P 2.1122047 0.2874016 29 P 0 0 ;0=25,1=1
P 2.1398425 3.611063 29 P 0 0 ;0=25,1=1
P 2.1398425 3.738063 29 P 0 0 ;0=25,1=1
P 2.1460663 4.1037909 29 P 0 0 ;0=25,1=1
P 2.1468425 2.753063 29 P 0 0 ;0=25,1=1
P 2.1515748 0.2559055 29 P 0 0 ;0=25,1=1
P 2.1515748 0.2874016 29 P 0 0 ;0=25,1=1
P 2.2058425 3.200063 29 P 0 0 ;0=25,1=1
P 2.2068425 1.298063 29 P 0 0 ;0=25,1=1
P 2.2317425 2.584163 29 P 0 0 ;0=25,1=1
P 2.2348425 3.506063 29 P 0 0 ;0=25,1=1
P 2.2523425 2.613563 29 P 0 0 ;0=25,1=1
P 2.2538425 2.279063 29 P 0 0 ;0=25,1=1
P 2.253937 4.0866142 29 P 0 0 ;0=25,1=1
P 2.2548425 3.536063 29 P 0 0 ;0=25,1=1
P 2.2588425 3.741063 29 P 0 0 ;0=25,1=1
P 2.2598425 3.261063 29 P 0 0 ;0=25,1=1
P 2.2720325 2.463873 29 P 0 0 ;0=25,1=1
P 2.2748425 1.506063 29 P 0 0 ;0=25,1=1
P 2.2908425 4.217063 29 P 0 0 ;0=25,1=1
P 2.2998425 1.916063 29 P 0 0 ;0=25,1=1
P 2.3098425 0.246063 29 P 0 0 ;0=25,1=1
P 2.3114125 1.0900094 29 P 0 0 ;0=25,1=1
P 2.3118425 0.934063 29 P 0 0 ;0=25,1=1
P 2.3215354 2.586063 29 P 0 0 ;0=25,1=1
P 2.3215354 3.361063 29 P 0 0 ;0=25,1=1
P 2.3308425 2.215063 29 P 0 0 ;0=25,1=1
P 2.3503937 0.4055118 29 P 0 0 ;0=25,1=1
P 2.3533464 4.0177165 29 P 0 0 ;0=25,1=1
P 2.3848425 1.941063 29 P 0 0 ;0=25,1=1
P 2.3897638 0.4055118 29 P 0 0 ;0=25,1=1
P 2.3898425 3.481063 29 P 0 0 ;0=25,1=1
P 2.394685 2.7204724 29 P 0 0 ;0=25,1=1
P 2.4048425 2.412063 29 P 0 0 ;0=25,1=1
P 2.4098325 0.932053 29 P 0 0 ;0=25,1=1
P 2.4098325 1.088053 29 P 0 0 ;0=25,1=1
P 2.4098425 1.967063 29 P 0 0 ;0=25,1=1
P 2.4098425 2.283063 29 P 0 0 ;0=25,1=1
P 2.4098425 2.314063 29 P 0 0 ;0=25,1=1
P 2.4098425 2.579063 29 P 0 0 ;0=25,1=1
P 2.4133858 0.2795276 29 P 0 0 ;0=25,1=1
P 2.4138425 3.295063 29 P 0 0 ;0=25,1=1
P 2.4140551 3.1998504 29 P 0 0 ;0=25,1=1
P 2.4187174 3.1185066 29 P 0 0 ;0=25,1=1
P 2.4192759 2.7886295 29 P 0 0 ;0=25,1=1
P 2.4291925 2.621063 29 P 0 0 ;0=25,1=1
P 2.4348425 3.546063 29 P 0 0 ;0=25,1=1
P 2.4448819 0.2795276 29 P 0 0 ;0=25,1=1
P 2.4468425 1.437063 29 P 0 0 ;0=25,1=1
P 2.4470546 0.2425914 29 P 0 0 ;0=25,1=1
P 2.4508425 2.282063 29 P 0 0 ;0=25,1=1
P 2.462374 3.1722441 29 P 0 0 ;0=25,1=1
P 2.4698827 0.4109883 29 P 0 0 ;0=25,1=1
P 2.4738425 2.980063 29 P 0 0 ;0=25,1=1
P 2.4758425 2.291063 29 P 0 0 ;0=25,1=1
P 2.4758425 2.456063 29 P 0 0 ;0=25,1=1
P 2.4788425 0.937063 29 P 0 0 ;0=25,1=1
P 2.4888425 2.413063 29 P 0 0 ;0=25,1=1
P 2.4948425 2.661063 29 P 0 0 ;0=25,1=1
P 2.4948425 2.696063 29 P 0 0 ;0=25,1=1
P 2.4998425 2.236063 29 P 0 0 ;0=25,1=1
P 2.5028425 1.316063 29 P 0 0 ;0=25,1=1
P 2.5082625 0.931483 29 P 0 0 ;0=25,1=1
P 2.5088425 1.090063 29 P 0 0 ;0=25,1=1
P 2.511811 0.4055118 29 P 0 0 ;0=25,1=1
P 2.5258425 2.463063 29 P 0 0 ;0=25,1=1
P 2.531398 2.830047 30 P 0 0 ;0=26,1=1
P 2.531398 3.853669 30 P 0 0 ;0=26,1=1
P 2.5460625 0.244843 29 P 0 0 ;0=25,1=1
P 2.5498425 1.755063 29 P 0 0 ;0=25,1=1
P 2.5708425 4.283063 29 P 0 0 ;0=25,1=1
P 2.5758425 2.412063 29 P 0 0 ;0=25,1=1
P 2.5787402 0.2795276 29 P 0 0 ;0=25,1=1
P 2.5798425 1.790063 29 P 0 0 ;0=25,1=1
P 2.5798425 2.281063 29 P 0 0 ;0=25,1=1
P 2.5798425 3.486063 29 P 0 0 ;0=25,1=1
P 2.5818425 2.308063 29 P 0 0 ;0=25,1=1
P 2.5868425 2.569063 29 P 0 0 ;0=25,1=1
P 2.5908425 3.288063 29 P 0 0 ;0=25,1=1
P 2.5918425 3.1862205 29 P 0 0 ;0=25,1=1
P 2.5984252 0.7952756 29 P 0 0 ;0=25,1=1
P 2.5998425 2.436063 29 P 0 0 ;0=25,1=1
P 2.6048425 1.734063 29 P 0 0 ;0=25,1=1
P 2.6066825 0.931903 29 P 0 0 ;0=25,1=1
P 2.6068425 1.091063 29 P 0 0 ;0=25,1=1
P 2.6102362 0.2795276 29 P 0 0 ;0=25,1=1
P 2.6220472 0.976378 29 P 0 0 ;0=25,1=1
P 2.6248425 2.461063 29 P 0 0 ;0=25,1=1
P 2.6259843 0.7952756 29 P 0 0 ;0=25,1=1
P 2.6268425 1.770063 29 P 0 0 ;0=25,1=1
P 2.6318425 2.876063 29 P 0 0 ;0=25,1=1
P 2.6348425 3.406063 29 P 0 0 ;0=25,1=1
P 2.636874 0.2479055 29 P 0 0 ;0=25,1=1
P 2.6438425 1.616063 29 P 0 0 ;0=25,1=1
P 2.6458425 2.274063 29 P 0 0 ;0=25,1=1
P 2.6496063 0.976378 29 P 0 0 ;0=25,1=1
P 2.6653543 0.4055118 29 P 0 0 ;0=25,1=1
P 2.6653543 0.7952756 29 P 0 0 ;0=25,1=1
P 2.6658425 1.092063 29 P 0 0 ;0=25,1=1
P 2.6658425 2.291063 29 P 0 0 ;0=25,1=1
P 2.6668425 1.640063 29 P 0 0 ;0=25,1=1
P 2.6748425 3.501063 29 P 0 0 ;0=25,1=1
P 2.6798425 3.661063 29 P 0 0 ;0=25,1=1
P 2.6811024 0.976378 29 P 0 0 ;0=25,1=1
P 2.6858425 2.311063 29 P 0 0 ;0=25,1=1
P 2.6858425 2.568063 29 P 0 0 ;0=25,1=1
P 2.6929134 0.7952756 29 P 0 0 ;0=25,1=1
P 2.6929134 2.7214567 29 P 0 0 ;0=25,1=1
P 2.6948425 1.481063 29 P 0 0 ;0=25,1=1
P 2.7028425 2.289063 29 P 0 0 ;0=25,1=1
P 2.7047244 0.4055118 29 P 0 0 ;0=25,1=1
P 2.7086614 0.976378 29 P 0 0 ;0=25,1=1
P 2.7198425 1.591063 29 P 0 0 ;0=25,1=1
P 2.7224094 3.7860709 29 P 0 0 ;0=25,1=1
P 2.7244825 1.093063 29 P 0 0 ;0=25,1=1
P 2.7248425 3.521063 29 P 0 0 ;0=25,1=1
P 2.7248425 3.729063 29 P 0 0 ;0=25,1=1
P 2.7268425 2.293063 29 P 0 0 ;0=25,1=1
P 2.7322835 0.7952756 29 P 0 0 ;0=25,1=1
P 2.7401575 0.976378 29 P 0 0 ;0=25,1=1
P 2.74882 0.282312 29 P 0 0 ;0=25,1=1
P 2.7598425 0.7952756 29 P 0 0 ;0=25,1=1
P 2.7677165 0.976378 29 P 0 0 ;0=25,1=1
P 2.7748425 3.566063 29 P 0 0 ;0=25,1=1
P 2.7795276 0.2795276 29 P 0 0 ;0=25,1=1
P 2.7838425 2.429063 29 P 0 0 ;0=25,1=1
P 2.7838425 2.568063 29 P 0 0 ;0=25,1=1
P 2.7841625 1.094063 29 P 0 0 ;0=25,1=1
P 2.7992126 0.7952756 29 P 0 0 ;0=25,1=1
P 2.7992126 0.976378 29 P 0 0 ;0=25,1=1
P 2.7998425 3.616063 29 P 0 0 ;0=25,1=1
P 2.7999951 0.2519685 29 P 0 0 ;0=25,1=1
P 2.8038425 2.307063 29 P 0 0 ;0=25,1=1
P 2.8218425 2.601063 29 P 0 0 ;0=25,1=1
P 2.8219832 0.4078519 29 P 0 0 ;0=25,1=1
P 2.8267717 0.7952756 29 P 0 0 ;0=25,1=1
P 2.8267717 0.976378 29 P 0 0 ;0=25,1=1
P 2.8418425 2.263063 29 P 0 0 ;0=25,1=1
P 2.8428425 1.095063 29 P 0 0 ;0=25,1=1
P 2.8543307 0.4055118 29 P 0 0 ;0=25,1=1
P 2.8608425 3.787063 29 P 0 0 ;0=25,1=1
P 2.8622047 0.7952756 29 P 0 0 ;0=25,1=1
P 2.8718425 2.297063 29 P 0 0 ;0=25,1=1
P 2.8782843 0.2495967 29 P 0 0 ;0=25,1=1
P 2.8818425 2.566063 29 P 0 0 ;0=25,1=1
P 2.8888425 4.221063 29 P 0 0 ;0=25,1=1
P 2.8937008 0.7952756 29 P 0 0 ;0=25,1=1
P 2.8948425 1.561063 29 P 0 0 ;0=25,1=1
P 2.8948425 2.431063 29 P 0 0 ;0=25,1=1
P 2.9018425 1.095063 29 P 0 0 ;0=25,1=1
P 2.9054946 0.2795104 29 P 0 0 ;0=25,1=1
P 2.9198425 1.536063 29 P 0 0 ;0=25,1=1
P 2.9208425 2.428063 29 P 0 0 ;0=25,1=1
P 2.9338425 0.953063 29 P 0 0 ;0=25,1=1
P 2.9370079 0.2795276 29 P 0 0 ;0=25,1=1
P 2.9428425 2.286063 29 P 0 0 ;0=25,1=1
P 2.9488425 2.456063 29 P 0 0 ;0=25,1=1
P 2.9574751 0.2519685 29 P 0 0 ;0=25,1=1
P 2.9588425 2.621063 29 P 0 0 ;0=25,1=1
P 2.980457 0.4091539 29 P 0 0 ;0=25,1=1
P 2.9858425 2.287063 29 P 0 0 ;0=25,1=1
P 2.9933858 3.751063 29 P 0 0 ;0=25,1=1
P 3.0148425 3.831063 29 P 0 0 ;0=25,1=1
P 3.019685 0.4055118 29 P 0 0 ;0=25,1=1
P 3.0568817 1.811803 29 P 0 0 ;0=25,1=1
P 3.0688976 3.3956693 29 P 0 0 ;0=25,1=1
P 3.0974409 0.2519685 29 P 0 0 ;0=25,1=1
P 3.1830708 3.1358268 29 P 0 0 ;0=25,1=1
P 3.1889764 3.1870079 29 P 0 0 ;0=25,1=1
P 3.1972633 1.714063 29 P 0 0 ;0=25,1=1
P 3.1978425 2.970063 29 P 0 0 ;0=25,1=1
P 3.2198425 3.806063 29 P 0 0 ;0=25,1=1
P 3.2248425 1.6613472 29 P 0 0 ;0=25,1=1
P 3.2308425 3.235063 29 P 0 0 ;0=25,1=1
P 3.2398425 3.596063 29 P 0 0 ;0=25,1=1
P 3.2528425 1.661063 29 P 0 0 ;0=25,1=1
P 3.2636972 3.3039177 29 P 0 0 ;0=25,1=1
P 3.2698425 3.788063 29 P 0 0 ;0=25,1=1
P 3.2755905 3.1417323 29 P 0 0 ;0=25,1=1
P 3.277559 2.9635827 29 P 0 0 ;0=25,1=1
P 3.2988425 1.971063 29 P 0 0 ;0=25,1=1
P 3.3028425 3.344063 29 P 0 0 ;0=25,1=1
P 3.3291721 1.826063 29 P 0 0 ;0=25,1=1
P 3.3308425 3.301063 29 P 0 0 ;0=25,1=1
P 3.3428425 2.263063 29 P 0 0 ;0=25,1=1
P 3.3448425 2.996063 29 P 0 0 ;0=25,1=1
P 3.3588425 3.448063 29 P 0 0 ;0=25,1=1
P 3.3688425 3.050063 29 P 0 0 ;0=25,1=1
P 3.3708425 2.888063 29 P 0 0 ;0=25,1=1
P 3.3748425 3.273063 29 P 0 0 ;0=25,1=1
P 3.3798425 1.336063 29 P 0 0 ;0=25,1=1
P 3.3798425 1.386063 29 P 0 0 ;0=25,1=1
P 3.3928425 1.871063 29 P 0 0 ;0=25,1=1
P 3.3948425 3.447063 29 P 0 0 ;0=25,1=1
P 3.3958425 4.222063 29 P 0 0 ;0=25,1=1
P 3.4048425 1.363323 29 P 0 0 ;0=25,1=1
P 3.4068425 1.461063 29 P 0 0 ;0=25,1=1
P 3.4072822 1.411323 29 P 0 0 ;0=25,1=1
P 3.4108425 1.7136509 29 P 0 0 ;0=25,1=1
P 3.4138425 1.573063 29 P 0 0 ;0=25,1=1
P 3.4144661 1.805063 29 P 0 0 ;0=25,1=1
P 3.4248425 3.636063 29 P 0 0 ;0=25,1=1
P 3.4368425 3.457063 29 P 0 0 ;0=25,1=1
P 3.4392507 1.870938 29 P 0 0 ;0=25,1=1
P 3.4698425 3.456063 29 P 0 0 ;0=25,1=1
P 3.4918425 3.103063 29 P 0 0 ;0=25,1=1
P 3.4918425 3.297063 29 P 0 0 ;0=25,1=1
P 3.4988425 2.341063 29 P 0 0 ;0=25,1=1
P 3.5048425 4.086063 29 P 0 0 ;0=25,1=1
P 3.5298425 3.481063 29 P 0 0 ;0=25,1=1
P 3.5318425 3.660063 29 P 0 0 ;0=25,1=1
P 3.5398425 3.806063 29 P 0 0 ;0=25,1=1
P 3.542865 3.3190405 29 P 0 0 ;0=25,1=1
P 3.5498425 1.413063 29 P 0 0 ;0=25,1=1
P 3.5498425 1.441063 29 P 0 0 ;0=25,1=1
P 3.5548425 1.841063 29 P 0 0 ;0=25,1=1
P 3.5548425 1.891063 29 P 0 0 ;0=25,1=1
P 3.5548425 1.941063 29 P 0 0 ;0=25,1=1
P 3.5548425 1.991063 29 P 0 0 ;0=25,1=1
P 3.5718425 2.033063 29 P 0 0 ;0=25,1=1
P 3.5718425 2.058063 29 P 0 0 ;0=25,1=1
P 3.5898425 1.711063 29 P 0 0 ;0=25,1=1
P 3.5908425 1.662063 29 P 0 0 ;0=25,1=1
P 3.5948425 1.514063 29 P 0 0 ;0=25,1=1
P 3.6038425 0.682063 29 P 0 0 ;0=25,1=1
P 3.6228425 3.486063 29 P 0 0 ;0=25,1=1
P 3.6238425 2.587063 29 P 0 0 ;0=25,1=1
P 3.6428425 0.636063 29 P 0 0 ;0=25,1=1
P 3.6538425 3.293063 29 P 0 0 ;0=25,1=1
P 3.6998425 3.751063 29 P 0 0 ;0=25,1=1
P 3.6998425 3.836063 29 P 0 0 ;0=25,1=1
P 3.7178425 3.072063 29 P 0 0 ;0=25,1=1
P 3.7188425 1.713063 29 P 0 0 ;0=25,1=1
P 3.7198425 1.766063 29 P 0 0 ;0=25,1=1
P 3.7198425 1.921063 29 P 0 0 ;0=25,1=1
P 3.7198425 1.996063 29 P 0 0 ;0=25,1=1
P 3.7248425 1.675063 29 P 0 0 ;0=25,1=1
P 3.7328425 1.418063 29 P 0 0 ;0=25,1=1
P 3.7448425 3.261063 29 P 0 0 ;0=25,1=1
P 3.7448425 3.342063 29 P 0 0 ;0=25,1=1
P 3.7738632 1.6661021 29 P 0 0 ;0=25,1=1
P 3.7778425 4.023063 29 P 0 0 ;0=25,1=1
P 3.7998425 3.201063 29 P 0 0 ;0=25,1=1
P 3.8038425 1.691063 29 P 0 0 ;0=25,1=1
P 3.8048425 1.840063 29 P 0 0 ;0=25,1=1
P 3.8068425 3.235063 29 P 0 0 ;0=25,1=1
P 3.8298425 3.176063 29 P 0 0 ;0=25,1=1
P 3.8298425 3.806063 29 P 0 0 ;0=25,1=1
P 3.8308425 3.762063 29 P 0 0 ;0=25,1=1
P 3.8348425 1.481063 29 P 0 0 ;0=25,1=1
P 3.8548425 3.151063 29 P 0 0 ;0=25,1=1
P 3.8648425 1.511063 29 P 0 0 ;0=25,1=1
P 3.8808425 3.109063 29 P 0 0 ;0=25,1=1
P 3.8948425 1.566063 29 P 0 0 ;0=25,1=1
P 3.9248425 1.536063 29 P 0 0 ;0=25,1=1
P 3.9398425 3.121063 29 P 0 0 ;0=25,1=1
P 3.9448425 1.816063 29 P 0 0 ;0=25,1=1
P 3.9608425 2.724063 29 P 0 0 ;0=25,1=1
P 3.9688425 1.671063 29 P 0 0 ;0=25,1=1
P 3.9698425 1.552063 29 P 0 0 ;0=25,1=1
P 3.9948425 1.551063 29 P 0 0 ;0=25,1=1
P 3.9968425 1.711063 29 P 0 0 ;0=25,1=1
P 4.0348425 1.546063 29 P 0 0 ;0=25,1=1
P 4.0398425 2.406063 29 P 0 0 ;0=25,1=1
P 4.0398425 3.784063 29 P 0 0 ;0=25,1=1
P 4.0498425 3.665063 29 P 0 0 ;0=25,1=1
P 4.0648425 1.511063 29 P 0 0 ;0=25,1=1
P 4.0648425 1.796063 29 P 0 0 ;0=25,1=1
P 4.0648425 2.722063 29 P 0 0 ;0=25,1=1
P 4.0688425 3.135063 29 P 0 0 ;0=25,1=1
P 4.0858425 3.892063 29 P 0 0 ;0=25,1=1
P 4.1148425 3.135063 29 P 0 0 ;0=25,1=1
P 4.1203866 3.5941508 29 P 0 0 ;0=25,1=1
P 4.1318425 1.686063 29 P 0 0 ;0=25,1=1
P 4.1348425 1.651063 29 P 0 0 ;0=25,1=1
P 4.1348425 1.751063 29 P 0 0 ;0=25,1=1
P 4.1513063 1.6236232 29 P 0 0 ;0=25,1=1
P 4.1528425 3.135063 29 P 0 0 ;0=25,1=1
P 4.1798425 1.601063 29 P 0 0 ;0=25,1=1
P 4.1948425 3.884063 29 P 0 0 ;0=25,1=1
P 4.2088425 3.135063 29 P 0 0 ;0=25,1=1
P 4.2348425 2.725063 29 P 0 0 ;0=25,1=1
P 4.2548425 3.776063 29 P 0 0 ;0=25,1=1
P 4.2728425 3.135063 29 P 0 0 ;0=25,1=1
P 4.3338425 3.135063 29 P 0 0 ;0=25,1=1
P 4.3398425 2.725063 29 P 0 0 ;0=25,1=1
P 4.3878425 4.206063 29 P 0 0 ;0=25,1=1
P 4.4318425 3.135063 29 P 0 0 ;0=25,1=1
P 4.4778425 3.135063 29 P 0 0 ;0=25,1=1
P 4.5036614 2.7898819 29 P 0 0 ;0=25,1=1
P 4.7547119 4.1159324 29 P 0 0 ;0=25,1=1
P 4.7942913 2.8080709 29 P 0 0 ;0=25,1=1
P 4.9108425 4.203063 29 P 0 0 ;0=25,1=1
P 5.2670079 4.0888976 29 P 0 0 ;0=25,1=1
P 5.2748425 3.511063 29 P 0 0 ;0=25,1=1
P 5.5778425 2.214063 29 P 0 0 ;0=25,1=1
P 5.6348425 2.236063 29 P 0 0 ;0=25,1=1
P 5.6768425 3.546063 29 P 0 0 ;0=25,1=1
P 5.7338425 3.556063 29 P 0 0 ;0=25,1=1
P 5.9948425 3.552063 29 P 0 0 ;0=25,1=1
P 6.0048425 2.434063 29 P 0 0 ;0=25,1=1
P 6.0488425 2.171063 29 P 0 0 ;0=25,1=1
P 6.253937 2.9094488 29 P 0 0 ;0=25,1=1
P 6.2748425 2.391063 29 P 0 0 ;0=25,1=1
P 6.2824161 3.226063 29 P 0 0 ;0=25,1=1
P 6.2848425 2.501063 29 P 0 0 ;0=25,1=1
P 6.2948425 3.701063 29 P 0 0 ;0=25,1=1
P 6.3048425 3.121063 29 P 0 0 ;0=25,1=1
P 6.3094161 3.199063 29 P 0 0 ;0=25,1=1
P 6.3348425 3.266063 29 P 0 0 ;0=25,1=1
P 6.3398425 3.151063 29 P 0 0 ;0=25,1=1
P 6.3547483 3.3311384 29 P 0 0 ;0=25,1=1
P 6.3720472 2.9094488 29 P 0 0 ;0=25,1=1
P 6.3958425 2.111063 29 P 0 0 ;0=25,1=1
P 6.3968425 2.556063 29 P 0 0 ;0=25,1=1
P 6.3978425 2.501063 29 P 0 0 ;0=25,1=1
P 6.3978425 2.610063 29 P 0 0 ;0=25,1=1
P 6.3988425 2.453063 29 P 0 0 ;0=25,1=1
P 6.3988425 2.657063 29 P 0 0 ;0=25,1=1
P 6.4098425 3.371063 29 P 0 0 ;0=25,1=1
P 6.4248425 2.181063 29 P 0 0 ;0=25,1=1
P 6.4398425 3.191063 29 P 0 0 ;0=25,1=1
P 6.4448425 3.291063 29 P 0 0 ;0=25,1=1
P 6.4475772 3.396063 29 P 0 0 ;0=25,1=1
P 6.4568425 3.009063 29 P 0 0 ;0=25,1=1
P 6.4768425 3.231063 29 P 0 0 ;0=25,1=1
P 6.4798425 3.426063 29 P 0 0 ;0=25,1=1
P 6.5098425 3.456063 29 P 0 0 ;0=25,1=1
P 6.5488425 1.531063 29 P 0 0 ;0=25,1=1
P 6.6018425 1.777063 29 P 0 0 ;0=25,1=1
P 6.6028425 1.612063 29 P 0 0 ;0=25,1=1
P 6.6028425 1.672063 29 P 0 0 ;0=25,1=1
P 6.6028425 1.722063 29 P 0 0 ;0=25,1=1
P 6.6078425 2.176063 29 P 0 0 ;0=25,1=1
P 6.6268425 3.032063 29 P 0 0 ;0=25,1=1
P 6.6288425 1.372063 29 P 0 0 ;0=25,1=1
P 6.6476378 3.1299213 29 P 0 0 ;0=25,1=1
P 6.6488425 3.341063 29 P 0 0 ;0=25,1=1
P 6.6858425 1.828063 29 P 0 0 ;0=25,1=1
P 6.6998425 1.881063 29 P 0 0 ;0=25,1=1
P 6.8448425 1.661063 29 P 0 0 ;0=25,1=1
P 6.9498425 2.095063 29 P 0 0 ;0=25,1=1
P 6.9744094 1.9399606 29 P 0 0 ;0=25,1=1

### steps/pcb/layers/comp_+_bot/features


### steps/pcb/layers/comp_+_top/features


### steps/pcb/layers/drill/features
#Layer_Color=9474304
#
#Feature symbol names
#
$0 r8
$1 r21.66
$2 r29.9213
$3 r30
$4 r39.3701
$5 r41.3386
$6 r50
$7 r60
$8 r64.9606
$9 r68
$10 r70.8661
$11 r118.11
$12 r125.9843
$13 r35.4331
$14 r65.9843
$15 r118.1102
$16 r125.1969

#
#Feature attribute names
#
@0 .geometry
@1 .drill

#
#Feature attribute text strings
#
&0 Pad_Simple_X0.0000Y0.0000H118.1100C158.1100
&1 Pad_Complex_X50.0000Y50.0000H118.1102C158.1102
&2 Pad_Simple_X50.0000Y50.0000H118.1102C158.1102
&3 Pad_Simple_X250.0000Y250.0000H125.1969C165.1969
&4 VIA_RoundD200.0000H125.9843C165.9843
&5 Pad_Simple_X21.6600Y21.6600H21.6600C61.6600
&6 Pad_Simple_X0.0000Y0.0000H29.9213C69.9213
&7 Pad_Simple_X55.0000Y55.0000H30.0000C70.0000
&8 Pad_Simple_X31.4961Y31.4961H35.4331C75.4331
&9 Pad_Simple_196.8504X98.4252D137.7953X39.3701
&10 Pad_Simple_177.1654X88.5827D118.1102X39.3701
&11 Pad_Simple_88.5827X177.1654D118.1102X39.3701
&12 Pad_Simple_X61.0236Y61.0236H41.3386C81.3386
&13 Pad_Simple_X75.0000Y75.0000H50.0000C90.0000
&14 Pad_Simple_X112.0000Y112.0000H60.0000C100.0000
&15 Pad_Simple_X98.4252Y98.4252H64.9606C104.9606
&16 Pad_Simple_X65.9843Y65.9843H65.9843C105.9843
&17 Pad_Simple_X120.0000Y120.0000H68.0000C108.0000
&18 Pad_Simple_X98.4252Y98.4252H70.8661C110.8661
&19 VIA_RoundD16.0000H8.0000C48.0000

#
#Layer features
#
P 0.0998425 0.806063 9 P 0 0 ;0=17,1=0
P 0.0998425 1.006063 9 P 0 0 ;0=17,1=0
P 0.0998425 1.331063 9 P 0 0 ;0=17,1=0
P 0.0998425 1.531063 9 P 0 0 ;0=17,1=0
P 0.0998425 1.856063 9 P 0 0 ;0=17,1=0
P 0.0998425 2.056063 9 P 0 0 ;0=17,1=0
P 0.0998425 2.381063 9 P 0 0 ;0=17,1=0
P 0.0998425 2.581063 9 P 0 0 ;0=17,1=0
P 0.1998425 0.906063 7 P 0 0 ;0=14,1=0
P 0.1998425 1.431063 7 P 0 0 ;0=14,1=0
P 0.1998425 1.956063 7 P 0 0 ;0=14,1=0
P 0.1998425 2.481063 7 P 0 0 ;0=14,1=0
P 0.285433 4.152063 16 P 0 0 ;0=3,1=1
P 0.2854331 0.3681102 16 P 0 0 ;0=3,1=1
P 0.2998425 0.806063 9 P 0 0 ;0=17,1=0
P 0.2998425 1.006063 9 P 0 0 ;0=17,1=0
P 0.2998425 1.331063 9 P 0 0 ;0=17,1=0
P 0.2998425 1.531063 9 P 0 0 ;0=17,1=0
P 0.2998425 1.856063 9 P 0 0 ;0=17,1=0
P 0.2998425 2.056063 9 P 0 0 ;0=17,1=0
P 0.2998425 2.381063 9 P 0 0 ;0=17,1=0
P 0.2998425 2.581063 9 P 0 0 ;0=17,1=0
P 1.4576771 4.053937 3 P 0 0 ;0=7,1=0
P 1.4576771 4.153937 3 P 0 0 ;0=7,1=0
P 1.4576771 4.253937 3 P 0 0 ;0=7,1=0
P 1.6519425 2.486293 11 P 0 0 ;0=0,1=0
P 1.6529425 0.916293 11 P 0 0 ;0=0,1=0
P 1.6968325 1.309833 1 P 0 0 ;0=5,1=0
P 1.6968325 2.097233 1 P 0 0 ;0=5,1=0
P 2.0433071 4.057874 3 P 0 0 ;0=7,1=0
P 2.0433071 4.157874 3 P 0 0 ;0=7,1=0
P 2.0433071 4.257874 3 P 0 0 ;0=7,1=0
P 2.2031325 2.438533 1 P 0 0 ;0=5,1=0
P 2.2031425 0.958593 1 P 0 0 ;0=5,1=0
P 2.4223425 3.0822126 2 P 0 0 ;0=6,1=0
P 2.4223425 3.2396929 2 P 0 0 ;0=6,1=0
P 2.4223425 3.4438977 2 P 0 0 ;0=6,1=0
P 2.4223425 3.601378 2 P 0 0 ;0=6,1=0
P 2.9905325 2.438533 1 P 0 0 ;0=5,1=0
P 2.9905425 0.958593 1 P 0 0 ;0=5,1=0
P 2.9948425 4.0861024 14 P 0 0 ;0=16,1=1
P 3.2948425 4.0861024 14 P 0 0 ;0=16,1=1
P 3.5717425 1.309793 1 P 0 0 ;0=5,1=0
P 3.5717425 2.097193 1 P 0 0 ;0=5,1=0
P 3.6179425 0.916293 11 P 0 0 ;0=0,1=0
P 3.6179425 2.486293 11 P 0 0 ;0=0,1=0
P 3.7848425 4.126063 13 P 0 0 ;0=8,1=1
P 3.9580709 4.126063 13 P 0 0 ;0=8,1=1
P 3.9797272 0.8906186 6 P 0 0 ;0=13,1=0
P 3.9797272 2.4890438 6 P 0 0 ;0=13,1=0
P 4.0624044 2.595343 6 P 0 0 ;0=13,1=0
P 4.1805146 2.595343 6 P 0 0 ;0=13,1=0
P 4.2986248 2.595343 6 P 0 0 ;0=13,1=0
P 4.3277559 1.0074803 5 P 0 0 ;0=12,1=0
P 4.3277559 2.3074803 5 P 0 0 ;0=12,1=0
P 4.7277559 2.3074803 5 P 0 0 ;0=12,1=0
P 4.9277559 1.0074803 5 P 0 0 ;0=12,1=0
P 4.9277559 2.3074803 5 P 0 0 ;0=12,1=0
P 5.1277559 1.0074803 5 P 0 0 ;0=12,1=0
P 5.1277559 2.3074803 5 P 0 0 ;0=12,1=0
P 5.3277559 1.0074803 5 P 0 0 ;0=12,1=0
P 5.3277559 2.3074803 5 P 0 0 ;0=12,1=0
P 5.5781524 0.8906186 6 P 0 0 ;0=13,1=0
P 5.5781524 1.6898312 6 P 0 0 ;0=13,1=0
P 5.5781524 2.4890438 6 P 0 0 ;0=13,1=0
P 5.7234252 3.8444882 8 P 0 0 ;0=15,1=0
P 5.7234252 4.0255906 8 P 0 0 ;0=15,1=0
L 5.9348031 3.9773227 5.9348031 3.8985827 4 P 0 ;0=11,1=0
L 6.1690551 3.8198425 6.0706299 3.8198425 4 P 0 ;0=9,1=0
L 6.1592125 4.056063 6.0804725 4.056063 4 P 0 ;0=10,1=0
P 6.5694882 3.5895276 10 P 0 0 ;0=18,1=0
P 6.5694882 3.806063 10 P 0 0 ;0=18,1=0
P 6.5694882 4.0934646 15 P 0 0 ;0=1,1=1
P 6.7348425 3.5895276 10 P 0 0 ;0=18,1=0
P 6.7348425 3.806063 10 P 0 0 ;0=18,1=0
P 6.9001969 3.5895276 10 P 0 0 ;0=18,1=0
P 6.9001969 3.806063 10 P 0 0 ;0=18,1=0
P 6.9001969 4.0934646 15 P 0 0 ;0=2,1=1
P 0.149508 2.830047 12 P 0 0 ;0=4,1=2
P 0.149508 3.853669 12 P 0 0 ;0=4,1=2
P 0.6538425 1.551063 0 P 0 0 ;0=19,1=2
P 0.6539669 2.5938902 0 P 0 0 ;0=19,1=2
P 0.6548425 0.790063 0 P 0 0 ;0=19,1=2
P 0.6548425 1.314063 0 P 0 0 ;0=19,1=2
P 0.6548425 1.839063 0 P 0 0 ;0=19,1=2
P 0.6548425 2.073063 0 P 0 0 ;0=19,1=2
P 0.6548425 2.365063 0 P 0 0 ;0=19,1=2
P 0.6558425 1.028063 0 P 0 0 ;0=19,1=2
P 0.9370078 2.3179133 0 P 0 0 ;0=19,1=2
P 0.988189 1.7175197 0 P 0 0 ;0=19,1=2
P 0.9901575 0.6870079 0 P 0 0 ;0=19,1=2
P 0.996063 1.1870079 0 P 0 0 ;0=19,1=2
P 0.9968357 2.256036 0 P 0 0 ;0=19,1=2
P 1.0048425 0.906063 0 P 0 0 ;0=19,1=2
P 1.0088425 1.430063 0 P 0 0 ;0=19,1=2
P 1.0098425 1.956063 0 P 0 0 ;0=19,1=2
P 1.0208425 2.481063 0 P 0 0 ;0=19,1=2
P 1.2428425 1.472063 0 P 0 0 ;0=19,1=2
P 1.2488425 2.000063 0 P 0 0 ;0=19,1=2
P 1.2568425 0.942063 0 P 0 0 ;0=19,1=2
P 1.2618425 2.482063 0 P 0 0 ;0=19,1=2
P 1.2948425 4.256063 0 P 0 0 ;0=19,1=2
P 1.3454724 4.1751969 0 P 0 0 ;0=19,1=2
P 1.3937008 1.8169291 0 P 0 0 ;0=19,1=2
P 1.4084645 3.980315 0 P 0 0 ;0=19,1=2
P 1.4408425 3.557063 0 P 0 0 ;0=19,1=2
P 1.4598425 3.147063 0 P 0 0 ;0=19,1=2
P 1.5498425 3.621063 0 P 0 0 ;0=19,1=2
P 1.5578425 4.229063 0 P 0 0 ;0=19,1=2
P 1.5679134 1.2854331 0 P 0 0 ;0=19,1=2
P 1.5682025 2.067703 0 P 0 0 ;0=19,1=2
P 1.5698819 4.1712599 0 P 0 0 ;0=19,1=2
P 1.5748425 3.596063 0 P 0 0 ;0=19,1=2
P 1.6198425 2.121063 0 P 0 0 ;0=19,1=2
P 1.6708425 1.595063 0 P 0 0 ;0=19,1=2
P 1.6708425 1.694063 0 P 0 0 ;0=19,1=2
P 1.6718425 1.399063 0 P 0 0 ;0=19,1=2
P 1.6718425 1.497063 0 P 0 0 ;0=19,1=2
P 1.6718425 1.792063 0 P 0 0 ;0=19,1=2
P 1.6748425 1.989063 0 P 0 0 ;0=19,1=2
P 1.6758425 1.891063 0 P 0 0 ;0=19,1=2
P 1.6918425 4.079063 0 P 0 0 ;0=19,1=2
P 1.7148425 1.595063 0 P 0 0 ;0=19,1=2
P 1.7168425 1.399063 0 P 0 0 ;0=19,1=2
P 1.7188425 1.497063 0 P 0 0 ;0=19,1=2
P 1.7188425 1.792063 0 P 0 0 ;0=19,1=2
P 1.7198425 1.536063 0 P 0 0 ;0=19,1=2
P 1.7218425 1.694063 0 P 0 0 ;0=19,1=2
P 1.7218425 1.890063 0 P 0 0 ;0=19,1=2
P 1.7218425 1.989063 0 P 0 0 ;0=19,1=2
P 1.7268425 4.329374 0 P 0 0 ;0=19,1=2
P 1.7498425 4.110063 0 P 0 0 ;0=19,1=2
P 1.7548425 2.126063 0 P 0 0 ;0=19,1=2
P 1.7548425 3.661063 0 P 0 0 ;0=19,1=2
P 1.7798425 4.156063 0 P 0 0 ;0=19,1=2
P 1.7888425 4.329374 0 P 0 0 ;0=19,1=2
P 1.7978425 0.355063 0 P 0 0 ;0=19,1=2
P 1.7982283 1.3041339 0 P 0 0 ;0=19,1=2
P 1.8227825 1.674003 0 P 0 0 ;0=19,1=2
P 1.8326771 0.2559055 0 P 0 0 ;0=19,1=2
P 1.8326771 0.2874016 0 P 0 0 ;0=19,1=2
P 1.8498425 3.701063 0 P 0 0 ;0=19,1=2
P 1.8523622 0.2559055 0 P 0 0 ;0=19,1=2
P 1.8523622 0.2874016 0 P 0 0 ;0=19,1=2
P 1.8720472 0.2559055 0 P 0 0 ;0=19,1=2
P 1.8720472 0.2874016 0 P 0 0 ;0=19,1=2
P 1.8799377 1.811803 0 P 0 0 ;0=19,1=2
P 1.8848425 2.071063 0 P 0 0 ;0=19,1=2
P 1.8848425 3.601063 0 P 0 0 ;0=19,1=2
P 1.8938425 1.693063 0 P 0 0 ;0=19,1=2
P 1.8973025 1.516523 0 P 0 0 ;0=19,1=2
P 1.9038425 4.018063 0 P 0 0 ;0=19,1=2
P 1.9161425 0.244763 0 P 0 0 ;0=19,1=2
P 2.0048425 1.336063 0 P 0 0 ;0=19,1=2
P 2.0048425 3.816063 0 P 0 0 ;0=19,1=2
P 2.0288425 1.361663 0 P 0 0 ;0=19,1=2
P 2.0298425 3.836063 0 P 0 0 ;0=19,1=2
P 2.0348425 0.246063 0 P 0 0 ;0=19,1=2
P 2.0598425 1.386063 0 P 0 0 ;0=19,1=2
P 2.0598425 3.871063 0 P 0 0 ;0=19,1=2
P 2.0767716 0.2559055 0 P 0 0 ;0=19,1=2
P 2.0767716 0.2874016 0 P 0 0 ;0=19,1=2
P 2.0838425 1.411663 0 P 0 0 ;0=19,1=2
P 2.0848425 3.896063 0 P 0 0 ;0=19,1=2
P 2.1122047 0.2559055 0 P 0 0 ;0=19,1=2
P 2.1122047 0.2874016 0 P 0 0 ;0=19,1=2
P 2.1398425 3.611063 0 P 0 0 ;0=19,1=2
P 2.1398425 3.738063 0 P 0 0 ;0=19,1=2
P 2.1460663 4.1037909 0 P 0 0 ;0=19,1=2
P 2.1468425 2.753063 0 P 0 0 ;0=19,1=2
P 2.1515748 0.2559055 0 P 0 0 ;0=19,1=2
P 2.1515748 0.2874016 0 P 0 0 ;0=19,1=2
P 2.2058425 3.200063 0 P 0 0 ;0=19,1=2
P 2.2068425 1.298063 0 P 0 0 ;0=19,1=2
P 2.2317425 2.584163 0 P 0 0 ;0=19,1=2
P 2.2348425 3.506063 0 P 0 0 ;0=19,1=2
P 2.2523425 2.613563 0 P 0 0 ;0=19,1=2
P 2.2538425 2.279063 0 P 0 0 ;0=19,1=2
P 2.253937 4.0866142 0 P 0 0 ;0=19,1=2
P 2.2548425 3.536063 0 P 0 0 ;0=19,1=2
P 2.2588425 3.741063 0 P 0 0 ;0=19,1=2
P 2.2598425 3.261063 0 P 0 0 ;0=19,1=2
P 2.2720325 2.463873 0 P 0 0 ;0=19,1=2
P 2.2748425 1.506063 0 P 0 0 ;0=19,1=2
P 2.2908425 4.217063 0 P 0 0 ;0=19,1=2
P 2.2998425 1.916063 0 P 0 0 ;0=19,1=2
P 2.3098425 0.246063 0 P 0 0 ;0=19,1=2
P 2.3114125 1.0900094 0 P 0 0 ;0=19,1=2
P 2.3118425 0.934063 0 P 0 0 ;0=19,1=2
P 2.3215354 2.586063 0 P 0 0 ;0=19,1=2
P 2.3215354 3.361063 0 P 0 0 ;0=19,1=2
P 2.3308425 2.215063 0 P 0 0 ;0=19,1=2
P 2.3503937 0.4055118 0 P 0 0 ;0=19,1=2
P 2.3533464 4.0177165 0 P 0 0 ;0=19,1=2
P 2.3848425 1.941063 0 P 0 0 ;0=19,1=2
P 2.3897638 0.4055118 0 P 0 0 ;0=19,1=2
P 2.3898425 3.481063 0 P 0 0 ;0=19,1=2
P 2.394685 2.7204724 0 P 0 0 ;0=19,1=2
P 2.4048425 2.412063 0 P 0 0 ;0=19,1=2
P 2.4098325 0.932053 0 P 0 0 ;0=19,1=2
P 2.4098325 1.088053 0 P 0 0 ;0=19,1=2
P 2.4098425 1.967063 0 P 0 0 ;0=19,1=2
P 2.4098425 2.283063 0 P 0 0 ;0=19,1=2
P 2.4098425 2.314063 0 P 0 0 ;0=19,1=2
P 2.4098425 2.579063 0 P 0 0 ;0=19,1=2
P 2.4133858 0.2795276 0 P 0 0 ;0=19,1=2
P 2.4138425 3.295063 0 P 0 0 ;0=19,1=2
P 2.4140551 3.1998504 0 P 0 0 ;0=19,1=2
P 2.4187174 3.1185066 0 P 0 0 ;0=19,1=2
P 2.4192759 2.7886295 0 P 0 0 ;0=19,1=2
P 2.4291925 2.621063 0 P 0 0 ;0=19,1=2
P 2.4348425 3.546063 0 P 0 0 ;0=19,1=2
P 2.4448819 0.2795276 0 P 0 0 ;0=19,1=2
P 2.4468425 1.437063 0 P 0 0 ;0=19,1=2
P 2.4470546 0.2425914 0 P 0 0 ;0=19,1=2
P 2.4508425 2.282063 0 P 0 0 ;0=19,1=2
P 2.462374 3.1722441 0 P 0 0 ;0=19,1=2
P 2.4698827 0.4109883 0 P 0 0 ;0=19,1=2
P 2.4738425 2.980063 0 P 0 0 ;0=19,1=2
P 2.4758425 2.291063 0 P 0 0 ;0=19,1=2
P 2.4758425 2.456063 0 P 0 0 ;0=19,1=2
P 2.4788425 0.937063 0 P 0 0 ;0=19,1=2
P 2.4888425 2.413063 0 P 0 0 ;0=19,1=2
P 2.4948425 2.661063 0 P 0 0 ;0=19,1=2
P 2.4948425 2.696063 0 P 0 0 ;0=19,1=2
P 2.4998425 2.236063 0 P 0 0 ;0=19,1=2
P 2.5028425 1.316063 0 P 0 0 ;0=19,1=2
P 2.5082625 0.931483 0 P 0 0 ;0=19,1=2
P 2.5088425 1.090063 0 P 0 0 ;0=19,1=2
P 2.511811 0.4055118 0 P 0 0 ;0=19,1=2
P 2.5258425 2.463063 0 P 0 0 ;0=19,1=2
P 2.531398 2.830047 12 P 0 0 ;0=4,1=2
P 2.531398 3.853669 12 P 0 0 ;0=4,1=2
P 2.5460625 0.244843 0 P 0 0 ;0=19,1=2
P 2.5498425 1.755063 0 P 0 0 ;0=19,1=2
P 2.5708425 4.283063 0 P 0 0 ;0=19,1=2
P 2.5758425 2.412063 0 P 0 0 ;0=19,1=2
P 2.5787402 0.2795276 0 P 0 0 ;0=19,1=2
P 2.5798425 1.790063 0 P 0 0 ;0=19,1=2
P 2.5798425 2.281063 0 P 0 0 ;0=19,1=2
P 2.5798425 3.486063 0 P 0 0 ;0=19,1=2
P 2.5818425 2.308063 0 P 0 0 ;0=19,1=2
P 2.5868425 2.569063 0 P 0 0 ;0=19,1=2
P 2.5908425 3.288063 0 P 0 0 ;0=19,1=2
P 2.5918425 3.1862205 0 P 0 0 ;0=19,1=2
P 2.5984252 0.7952756 0 P 0 0 ;0=19,1=2
P 2.5998425 2.436063 0 P 0 0 ;0=19,1=2
P 2.6048425 1.734063 0 P 0 0 ;0=19,1=2
P 2.6066825 0.931903 0 P 0 0 ;0=19,1=2
P 2.6068425 1.091063 0 P 0 0 ;0=19,1=2
P 2.6102362 0.2795276 0 P 0 0 ;0=19,1=2
P 2.6220472 0.976378 0 P 0 0 ;0=19,1=2
P 2.6248425 2.461063 0 P 0 0 ;0=19,1=2
P 2.6259843 0.7952756 0 P 0 0 ;0=19,1=2
P 2.6268425 1.770063 0 P 0 0 ;0=19,1=2
P 2.6318425 2.876063 0 P 0 0 ;0=19,1=2
P 2.6348425 3.406063 0 P 0 0 ;0=19,1=2
P 2.636874 0.2479055 0 P 0 0 ;0=19,1=2
P 2.6438425 1.616063 0 P 0 0 ;0=19,1=2
P 2.6458425 2.274063 0 P 0 0 ;0=19,1=2
P 2.6496063 0.976378 0 P 0 0 ;0=19,1=2
P 2.6653543 0.4055118 0 P 0 0 ;0=19,1=2
P 2.6653543 0.7952756 0 P 0 0 ;0=19,1=2
P 2.6658425 1.092063 0 P 0 0 ;0=19,1=2
P 2.6658425 2.291063 0 P 0 0 ;0=19,1=2
P 2.6668425 1.640063 0 P 0 0 ;0=19,1=2
P 2.6748425 3.501063 0 P 0 0 ;0=19,1=2
P 2.6798425 3.661063 0 P 0 0 ;0=19,1=2
P 2.6811024 0.976378 0 P 0 0 ;0=19,1=2
P 2.6858425 2.311063 0 P 0 0 ;0=19,1=2
P 2.6858425 2.568063 0 P 0 0 ;0=19,1=2
P 2.6929134 0.7952756 0 P 0 0 ;0=19,1=2
P 2.6929134 2.7214567 0 P 0 0 ;0=19,1=2
P 2.6948425 1.481063 0 P 0 0 ;0=19,1=2
P 2.7028425 2.289063 0 P 0 0 ;0=19,1=2
P 2.7047244 0.4055118 0 P 0 0 ;0=19,1=2
P 2.7086614 0.976378 0 P 0 0 ;0=19,1=2
P 2.7198425 1.591063 0 P 0 0 ;0=19,1=2
P 2.7224094 3.7860709 0 P 0 0 ;0=19,1=2
P 2.7244825 1.093063 0 P 0 0 ;0=19,1=2
P 2.7248425 3.521063 0 P 0 0 ;0=19,1=2
P 2.7248425 3.729063 0 P 0 0 ;0=19,1=2
P 2.7268425 2.293063 0 P 0 0 ;0=19,1=2
P 2.7322835 0.7952756 0 P 0 0 ;0=19,1=2
P 2.7401575 0.976378 0 P 0 0 ;0=19,1=2
P 2.74882 0.282312 0 P 0 0 ;0=19,1=2
P 2.7598425 0.7952756 0 P 0 0 ;0=19,1=2
P 2.7677165 0.976378 0 P 0 0 ;0=19,1=2
P 2.7748425 3.566063 0 P 0 0 ;0=19,1=2
P 2.7795276 0.2795276 0 P 0 0 ;0=19,1=2
P 2.7838425 2.429063 0 P 0 0 ;0=19,1=2
P 2.7838425 2.568063 0 P 0 0 ;0=19,1=2
P 2.7841625 1.094063 0 P 0 0 ;0=19,1=2
P 2.7992126 0.7952756 0 P 0 0 ;0=19,1=2
P 2.7992126 0.976378 0 P 0 0 ;0=19,1=2
P 2.7998425 3.616063 0 P 0 0 ;0=19,1=2
P 2.7999951 0.2519685 0 P 0 0 ;0=19,1=2
P 2.8038425 2.307063 0 P 0 0 ;0=19,1=2
P 2.8218425 2.601063 0 P 0 0 ;0=19,1=2
P 2.8219832 0.4078519 0 P 0 0 ;0=19,1=2
P 2.8267717 0.7952756 0 P 0 0 ;0=19,1=2
P 2.8267717 0.976378 0 P 0 0 ;0=19,1=2
P 2.8418425 2.263063 0 P 0 0 ;0=19,1=2
P 2.8428425 1.095063 0 P 0 0 ;0=19,1=2
P 2.8543307 0.4055118 0 P 0 0 ;0=19,1=2
P 2.8608425 3.787063 0 P 0 0 ;0=19,1=2
P 2.8622047 0.7952756 0 P 0 0 ;0=19,1=2
P 2.8718425 2.297063 0 P 0 0 ;0=19,1=2
P 2.8782843 0.2495967 0 P 0 0 ;0=19,1=2
P 2.8818425 2.566063 0 P 0 0 ;0=19,1=2
P 2.8888425 4.221063 0 P 0 0 ;0=19,1=2
P 2.8937008 0.7952756 0 P 0 0 ;0=19,1=2
P 2.8948425 1.561063 0 P 0 0 ;0=19,1=2
P 2.8948425 2.431063 0 P 0 0 ;0=19,1=2
P 2.9018425 1.095063 0 P 0 0 ;0=19,1=2
P 2.9054946 0.2795104 0 P 0 0 ;0=19,1=2
P 2.9198425 1.536063 0 P 0 0 ;0=19,1=2
P 2.9208425 2.428063 0 P 0 0 ;0=19,1=2
P 2.9338425 0.953063 0 P 0 0 ;0=19,1=2
P 2.9370079 0.2795276 0 P 0 0 ;0=19,1=2
P 2.9428425 2.286063 0 P 0 0 ;0=19,1=2
P 2.9488425 2.456063 0 P 0 0 ;0=19,1=2
P 2.9574751 0.2519685 0 P 0 0 ;0=19,1=2
P 2.9588425 2.621063 0 P 0 0 ;0=19,1=2
P 2.980457 0.4091539 0 P 0 0 ;0=19,1=2
P 2.9858425 2.287063 0 P 0 0 ;0=19,1=2
P 2.9933858 3.751063 0 P 0 0 ;0=19,1=2
P 3.0148425 3.831063 0 P 0 0 ;0=19,1=2
P 3.019685 0.4055118 0 P 0 0 ;0=19,1=2
P 3.0568817 1.811803 0 P 0 0 ;0=19,1=2
P 3.0688976 3.3956693 0 P 0 0 ;0=19,1=2
P 3.0974409 0.2519685 0 P 0 0 ;0=19,1=2
P 3.1830708 3.1358268 0 P 0 0 ;0=19,1=2
P 3.1889764 3.1870079 0 P 0 0 ;0=19,1=2
P 3.1972633 1.714063 0 P 0 0 ;0=19,1=2
P 3.1978425 2.970063 0 P 0 0 ;0=19,1=2
P 3.2198425 3.806063 0 P 0 0 ;0=19,1=2
P 3.2248425 1.6613472 0 P 0 0 ;0=19,1=2
P 3.2308425 3.235063 0 P 0 0 ;0=19,1=2
P 3.2398425 3.596063 0 P 0 0 ;0=19,1=2
P 3.2528425 1.661063 0 P 0 0 ;0=19,1=2
P 3.2636972 3.3039177 0 P 0 0 ;0=19,1=2
P 3.2698425 3.788063 0 P 0 0 ;0=19,1=2
P 3.2755905 3.1417323 0 P 0 0 ;0=19,1=2
P 3.277559 2.9635827 0 P 0 0 ;0=19,1=2
P 3.2988425 1.971063 0 P 0 0 ;0=19,1=2
P 3.3028425 3.344063 0 P 0 0 ;0=19,1=2
P 3.3291721 1.826063 0 P 0 0 ;0=19,1=2
P 3.3308425 3.301063 0 P 0 0 ;0=19,1=2
P 3.3428425 2.263063 0 P 0 0 ;0=19,1=2
P 3.3448425 2.996063 0 P 0 0 ;0=19,1=2
P 3.3588425 3.448063 0 P 0 0 ;0=19,1=2
P 3.3688425 3.050063 0 P 0 0 ;0=19,1=2
P 3.3708425 2.888063 0 P 0 0 ;0=19,1=2
P 3.3748425 3.273063 0 P 0 0 ;0=19,1=2
P 3.3798425 1.336063 0 P 0 0 ;0=19,1=2
P 3.3798425 1.386063 0 P 0 0 ;0=19,1=2
P 3.3928425 1.871063 0 P 0 0 ;0=19,1=2
P 3.3948425 3.447063 0 P 0 0 ;0=19,1=2
P 3.3958425 4.222063 0 P 0 0 ;0=19,1=2
P 3.4048425 1.363323 0 P 0 0 ;0=19,1=2
P 3.4068425 1.461063 0 P 0 0 ;0=19,1=2
P 3.4072822 1.411323 0 P 0 0 ;0=19,1=2
P 3.4108425 1.7136509 0 P 0 0 ;0=19,1=2
P 3.4138425 1.573063 0 P 0 0 ;0=19,1=2
P 3.4144661 1.805063 0 P 0 0 ;0=19,1=2
P 3.4248425 3.636063 0 P 0 0 ;0=19,1=2
P 3.4368425 3.457063 0 P 0 0 ;0=19,1=2
P 3.4392507 1.870938 0 P 0 0 ;0=19,1=2
P 3.4698425 3.456063 0 P 0 0 ;0=19,1=2
P 3.4918425 3.103063 0 P 0 0 ;0=19,1=2
P 3.4918425 3.297063 0 P 0 0 ;0=19,1=2
P 3.4988425 2.341063 0 P 0 0 ;0=19,1=2
P 3.5048425 4.086063 0 P 0 0 ;0=19,1=2
P 3.5298425 3.481063 0 P 0 0 ;0=19,1=2
P 3.5318425 3.660063 0 P 0 0 ;0=19,1=2
P 3.5398425 3.806063 0 P 0 0 ;0=19,1=2
P 3.542865 3.3190405 0 P 0 0 ;0=19,1=2
P 3.5498425 1.413063 0 P 0 0 ;0=19,1=2
P 3.5498425 1.441063 0 P 0 0 ;0=19,1=2
P 3.5548425 1.841063 0 P 0 0 ;0=19,1=2
P 3.5548425 1.891063 0 P 0 0 ;0=19,1=2
P 3.5548425 1.941063 0 P 0 0 ;0=19,1=2
P 3.5548425 1.991063 0 P 0 0 ;0=19,1=2
P 3.5718425 2.033063 0 P 0 0 ;0=19,1=2
P 3.5718425 2.058063 0 P 0 0 ;0=19,1=2
P 3.5898425 1.711063 0 P 0 0 ;0=19,1=2
P 3.5908425 1.662063 0 P 0 0 ;0=19,1=2
P 3.5948425 1.514063 0 P 0 0 ;0=19,1=2
P 3.6038425 0.682063 0 P 0 0 ;0=19,1=2
P 3.6228425 3.486063 0 P 0 0 ;0=19,1=2
P 3.6238425 2.587063 0 P 0 0 ;0=19,1=2
P 3.6428425 0.636063 0 P 0 0 ;0=19,1=2
P 3.6538425 3.293063 0 P 0 0 ;0=19,1=2
P 3.6998425 3.751063 0 P 0 0 ;0=19,1=2
P 3.6998425 3.836063 0 P 0 0 ;0=19,1=2
P 3.7178425 3.072063 0 P 0 0 ;0=19,1=2
P 3.7188425 1.713063 0 P 0 0 ;0=19,1=2
P 3.7198425 1.766063 0 P 0 0 ;0=19,1=2
P 3.7198425 1.921063 0 P 0 0 ;0=19,1=2
P 3.7198425 1.996063 0 P 0 0 ;0=19,1=2
P 3.7248425 1.675063 0 P 0 0 ;0=19,1=2
P 3.7328425 1.418063 0 P 0 0 ;0=19,1=2
P 3.7448425 3.261063 0 P 0 0 ;0=19,1=2
P 3.7448425 3.342063 0 P 0 0 ;0=19,1=2
P 3.7738632 1.6661021 0 P 0 0 ;0=19,1=2
P 3.7778425 4.023063 0 P 0 0 ;0=19,1=2
P 3.7998425 3.201063 0 P 0 0 ;0=19,1=2
P 3.8038425 1.691063 0 P 0 0 ;0=19,1=2
P 3.8048425 1.840063 0 P 0 0 ;0=19,1=2
P 3.8068425 3.235063 0 P 0 0 ;0=19,1=2
P 3.8298425 3.176063 0 P 0 0 ;0=19,1=2
P 3.8298425 3.806063 0 P 0 0 ;0=19,1=2
P 3.8308425 3.762063 0 P 0 0 ;0=19,1=2
P 3.8348425 1.481063 0 P 0 0 ;0=19,1=2
P 3.8548425 3.151063 0 P 0 0 ;0=19,1=2
P 3.8648425 1.511063 0 P 0 0 ;0=19,1=2
P 3.8808425 3.109063 0 P 0 0 ;0=19,1=2
P 3.8948425 1.566063 0 P 0 0 ;0=19,1=2
P 3.9248425 1.536063 0 P 0 0 ;0=19,1=2
P 3.9398425 3.121063 0 P 0 0 ;0=19,1=2
P 3.9448425 1.816063 0 P 0 0 ;0=19,1=2
P 3.9608425 2.724063 0 P 0 0 ;0=19,1=2
P 3.9688425 1.671063 0 P 0 0 ;0=19,1=2
P 3.9698425 1.552063 0 P 0 0 ;0=19,1=2
P 3.9948425 1.551063 0 P 0 0 ;0=19,1=2
P 3.9968425 1.711063 0 P 0 0 ;0=19,1=2
P 4.0348425 1.546063 0 P 0 0 ;0=19,1=2
P 4.0398425 2.406063 0 P 0 0 ;0=19,1=2
P 4.0398425 3.784063 0 P 0 0 ;0=19,1=2
P 4.0498425 3.665063 0 P 0 0 ;0=19,1=2
P 4.0648425 1.511063 0 P 0 0 ;0=19,1=2
P 4.0648425 1.796063 0 P 0 0 ;0=19,1=2
P 4.0648425 2.722063 0 P 0 0 ;0=19,1=2
P 4.0688425 3.135063 0 P 0 0 ;0=19,1=2
P 4.0858425 3.892063 0 P 0 0 ;0=19,1=2
P 4.1148425 3.135063 0 P 0 0 ;0=19,1=2
P 4.1203866 3.5941508 0 P 0 0 ;0=19,1=2
P 4.1318425 1.686063 0 P 0 0 ;0=19,1=2
P 4.1348425 1.651063 0 P 0 0 ;0=19,1=2
P 4.1348425 1.751063 0 P 0 0 ;0=19,1=2
P 4.1513063 1.6236232 0 P 0 0 ;0=19,1=2
P 4.1528425 3.135063 0 P 0 0 ;0=19,1=2
P 4.1798425 1.601063 0 P 0 0 ;0=19,1=2
P 4.1948425 3.884063 0 P 0 0 ;0=19,1=2
P 4.2088425 3.135063 0 P 0 0 ;0=19,1=2
P 4.2348425 2.725063 0 P 0 0 ;0=19,1=2
P 4.2548425 3.776063 0 P 0 0 ;0=19,1=2
P 4.2728425 3.135063 0 P 0 0 ;0=19,1=2
P 4.3338425 3.135063 0 P 0 0 ;0=19,1=2
P 4.3398425 2.725063 0 P 0 0 ;0=19,1=2
P 4.3878425 4.206063 0 P 0 0 ;0=19,1=2
P 4.4318425 3.135063 0 P 0 0 ;0=19,1=2
P 4.4778425 3.135063 0 P 0 0 ;0=19,1=2
P 4.5036614 2.7898819 0 P 0 0 ;0=19,1=2
P 4.7547119 4.1159324 0 P 0 0 ;0=19,1=2
P 4.7942913 2.8080709 0 P 0 0 ;0=19,1=2
P 4.9108425 4.203063 0 P 0 0 ;0=19,1=2
P 5.2670079 4.0888976 0 P 0 0 ;0=19,1=2
P 5.2748425 3.511063 0 P 0 0 ;0=19,1=2
P 5.5778425 2.214063 0 P 0 0 ;0=19,1=2
P 5.6348425 2.236063 0 P 0 0 ;0=19,1=2
P 5.6768425 3.546063 0 P 0 0 ;0=19,1=2
P 5.7338425 3.556063 0 P 0 0 ;0=19,1=2
P 5.9948425 3.552063 0 P 0 0 ;0=19,1=2
P 6.0048425 2.434063 0 P 0 0 ;0=19,1=2
P 6.0488425 2.171063 0 P 0 0 ;0=19,1=2
P 6.253937 2.9094488 0 P 0 0 ;0=19,1=2
P 6.2748425 2.391063 0 P 0 0 ;0=19,1=2
P 6.2824161 3.226063 0 P 0 0 ;0=19,1=2
P 6.2848425 2.501063 0 P 0 0 ;0=19,1=2
P 6.2948425 3.701063 0 P 0 0 ;0=19,1=2
P 6.3048425 3.121063 0 P 0 0 ;0=19,1=2
P 6.3094161 3.199063 0 P 0 0 ;0=19,1=2
P 6.3348425 3.266063 0 P 0 0 ;0=19,1=2
P 6.3398425 3.151063 0 P 0 0 ;0=19,1=2
P 6.3547483 3.3311384 0 P 0 0 ;0=19,1=2
P 6.3720472 2.9094488 0 P 0 0 ;0=19,1=2
P 6.3958425 2.111063 0 P 0 0 ;0=19,1=2
P 6.3968425 2.556063 0 P 0 0 ;0=19,1=2
P 6.3978425 2.501063 0 P 0 0 ;0=19,1=2
P 6.3978425 2.610063 0 P 0 0 ;0=19,1=2
P 6.3988425 2.453063 0 P 0 0 ;0=19,1=2
P 6.3988425 2.657063 0 P 0 0 ;0=19,1=2
P 6.4098425 3.371063 0 P 0 0 ;0=19,1=2
P 6.4248425 2.181063 0 P 0 0 ;0=19,1=2
P 6.4398425 3.191063 0 P 0 0 ;0=19,1=2
P 6.4448425 3.291063 0 P 0 0 ;0=19,1=2
P 6.4475772 3.396063 0 P 0 0 ;0=19,1=2
P 6.4568425 3.009063 0 P 0 0 ;0=19,1=2
P 6.4768425 3.231063 0 P 0 0 ;0=19,1=2
P 6.4798425 3.426063 0 P 0 0 ;0=19,1=2
P 6.5098425 3.456063 0 P 0 0 ;0=19,1=2
P 6.5488425 1.531063 0 P 0 0 ;0=19,1=2
P 6.6018425 1.777063 0 P 0 0 ;0=19,1=2
P 6.6028425 1.612063 0 P 0 0 ;0=19,1=2
P 6.6028425 1.672063 0 P 0 0 ;0=19,1=2
P 6.6028425 1.722063 0 P 0 0 ;0=19,1=2
P 6.6078425 2.176063 0 P 0 0 ;0=19,1=2
P 6.6268425 3.032063 0 P 0 0 ;0=19,1=2
P 6.6288425 1.372063 0 P 0 0 ;0=19,1=2
P 6.6476378 3.1299213 0 P 0 0 ;0=19,1=2
P 6.6488425 3.341063 0 P 0 0 ;0=19,1=2
P 6.6858425 1.828063 0 P 0 0 ;0=19,1=2
P 6.6998425 1.881063 0 P 0 0 ;0=19,1=2
P 6.8448425 1.661063 0 P 0 0 ;0=19,1=2
P 6.9498425 2.095063 0 P 0 0 ;0=19,1=2
P 6.9744094 1.9399606 0 P 0 0 ;0=19,1=2

### steps/pcb/layers/in1/features
#Layer_Physical_Order=3
#Layer_Color=16440176
#
#Feature symbol names
#
$0 r8
$1 r5
$2 r20
$3 r6
$4 r3.937
$5 r1
$6 r75
$7 r55
$8 r16

#
#Feature attribute names
#
@0 .geometry
@1 .pad_usage

#
#Feature attribute text strings
#
&0 Pad_Simple_X75.0000Y75.0000H50.0000C90.0000
&1 Pad_Simple_X55.0000Y55.0000H30.0000C70.0000
&2 VIA_RoundD16.0000H8.0000C48.0000

#
#Layer features
#
A 1.7712204 0.4310709 1.6275196 0.4310709 1.69937 0.4310709 4 P 0 N
A 2.3962788 2.7188785 2.4019357 2.7165354 2.4019357 2.7245354 0 P 0 N
A 2.4268055 0.2755913 2.4633018 0.2812475 2.4448819 0.2795276 1 P 0 N
A 2.4268055 0.2755914 2.4218883 0.2795276 2.4219199 0.2745276 1 P 0 N
A 2.4591027 0.3215522 2.4591028 0.3109457 2.4644061 0.316249 1 P 0 N
A 2.462398 0.2970437 2.462398 0.3076503 2.4570947 0.302347 1 P 0 N
A 2.4647316 0.2852354 2.4633016 0.2812476 2.46828 0.2817126 1 P 0 N
A 2.4697093 0.3215522 2.4591027 0.3215522 2.464406 0.3162489 1 P 0 N
A 2.4730045 0.3182572 2.483611 0.3182571 2.4783078 0.3235605 1 P 0 N
A 2.481143 0.3419383 2.4811431 0.3313318 2.4864464 0.3366351 1 P 0 N
A 2.483611 0.3182571 2.483611 0.3288637 2.4783077 0.3235604 1 P 0 N
A 2.4917496 0.3419383 2.481143 0.3419383 2.4864463 0.336635 1 P 0 N
A 2.4942177 0.3394704 2.5048242 0.3394703 2.499521 0.3447737 1 P 0 N
A 2.5048234 0.3606843 2.5048235 0.3500778 2.5101268 0.3553811 1 P 0 N
A 2.5048242 0.3394703 2.5048242 0.3500769 2.4995209 0.3447736 1 P 0 N
A 2.51543 0.3606843 2.5048234 0.3606843 2.5101267 0.355381 1 P 0 N
A 2.515431 0.3606833 2.5260376 0.3606833 2.5207343 0.3659866 1 P 0 N
A 2.5537186 0.3883645 2.555929 0.3937008 2.5483823 0.3937008 1 P 0 N
A 2.5633894 0.3838931 2.5669291 0.3909404 2.554478 0.3927817 1 P 0 N
A 2.5708465 0.8385633 2.555929 0.8025492 2.6068606 0.8025492 1 P 0 N
A 2.5772301 0.2979659 2.5967244 0.2751896 2.5787402 0.2795276 1 P 0 N
A 2.5772302 0.2979658 2.5811607 0.3004636 2.5768222 0.3029492 1 P 0 N
A 2.5786444 0.8308046 2.5669292 0.8025514 2.6069273 0.8025217 1 P 0 N
A 2.5787402 0.2795276 2.590997 0.2952757 2.5217118 0.3365568 1 P 0 N
A 2.5833241 0.3038795 2.5811607 0.3004636 2.6207554 0.27778 1 P 0 N
A 2.5833241 0.3038795 2.5840758 0.305536 2.5792227 0.3067394 1 P 0 N
A 2.589472 0.324767 2.587926 0.3207438 2.6049102 0.3165262 1 P 0 N
A 2.5894721 0.324767 2.5900612 0.3271215 2.5850611 0.3271216 1 P 0 N
A 2.590077 0.4048252 2.5900615 0.4044314 2.5950619 0.4044314 1 P 0 N
A 2.590997 0.2952757 2.5924267 0.2977757 2.5217118 0.3365568 1 P 0 N
A 2.6000644 0.2788024 2.5967439 0.2752696 2.6015907 0.274041 1 P 0 N
A 2.6010375 0.8687542 2.6303268 0.9394649 2.5303268 0.9394649 1 P 0 N
A 2.6023617 0.3765263 2.6098617 0.3690262 2.6098617 0.3765262 1 P 0 N
A 2.60464 0.2795276 2.6000644 0.2788025 2.60464 0.2647277 1 P 0 N
A 2.6049102 0.3240262 2.5976396 0.3183668 2.6049102 0.3165262 1 P 0 N
A 2.6075616 0.3540262 2.6075616 0.3390262 2.6075616 0.3465262 1 P 0 N
A 2.6085063 0.4571723 2.5900772 0.4048252 2.697819 0.3963118 1 P 0 N
A 2.6088541 0.8610146 2.6413267 0.9394103 2.5304584 0.9394103 1 P 0 N
A 2.6160907 0.3540262 2.6160907 0.3690262 2.6160907 0.3615262 1 P 0 N
A 2.6197278 0.3240262 2.6197278 0.3390262 2.6197278 0.3315262 1 P 0 N
A 2.625896 0.4802268 2.6085063 0.4571724 2.6994991 0.4066233 1 P 0 N
A 2.6266076 2.7165354 2.6322781 2.7188922 2.6266076 2.7245354 0 P 0 N
A 2.6303268 0.9562399 2.6220472 0.9762286 2.6020585 0.9562399 1 P 0 N
A 2.6337624 0.472537 2.6023621 0.3968183 2.7095689 0.3967302 1 P 0 N
A 2.6443446 0.4986753 2.6736339 0.569386 2.5736339 0.569386 1 P 0 N
A 2.6496063 0.9762283 2.6413269 0.95624 2.6695948 0.95624 1 P 0 N
A 2.6521612 0.4909357 2.6846338 0.5693314 2.5737655 0.5693314 1 P 0 N
A 2.6715808 2.7549212 2.6659503 2.7525644 2.671621 2.746921 0 P 0 N
A 2.6736339 0.7751375 2.6653543 0.7951262 2.6453656 0.7751375 1 P 0 N
A 2.6929134 0.7951259 2.684634 0.7751376 2.7129019 0.7751376 1 P 0 N
A 2.7130379 0.3275528 2.7374167 0.2674147 2.7995431 0.3276098 1 P 0 N
A 2.7339149 0.3181179 2.7339149 0.3031179 2.7339149 0.3106179 1 P 0 N
A 2.7339267 0.3481179 2.7339267 0.3331179 2.7339267 0.3406179 1 P 0 N
A 2.7374436 0.2673869 2.7661079 0.2755913 2.7495712 0.2791913 1 P 0 N
A 2.7379035 0.38751 2.7130379 0.3275528 2.7978525 0.3275131 1 P 0 N
A 2.7405615 0.3481179 2.7480615 0.3556149 2.7405615 0.3556179 1 P 0 N
A 2.7480334 0.2850057 2.7488197 0.2823122 2.7530335 0.2850038 1 P 0 N
A 2.7480377 0.295615 2.7405377 0.3031179 2.7405377 0.2956179 1 P 0 N
A 2.748437 0.9408906 2.7624692 0.9070139 2.7963459 0.9408906 1 P 0 N
A 2.748437 0.95624 2.7401575 0.9762285 2.720169 0.95624 1 P 0 N
A 2.7495358 0.3835858 2.7480713 0.3800522 2.7530713 0.3800503 1 P 0 N
A 2.7505469 0.3181179 2.7505469 0.3331179 2.7505469 0.3256179 1 P 0 N
A 2.759437 0.940945 2.7702859 0.9147536 2.7964773 0.940945 1 P 0 N
A 2.7677165 0.9762283 2.7594371 0.95624 2.787705 0.95624 1 P 0 N
A 2.771025 0.2795276 2.7661078 0.2755914 2.7709934 0.2745276 1 P 0 N
A 2.7818567 0.8876264 2.8602814 0.8551418 2.8602814 0.9660511 1 P 0 N
A 2.7874016 0.4370081 2.8074921 0.4855108 2.7388989 0.4855108 1 P 0 N
A 2.7896083 0.8954311 2.860319 0.8661418 2.860319 0.9661418 1 P 0 N
A 2.7952139 0.429264 2.8184921 0.4854626 2.7390153 0.4854626 1 P 0 N
A 2.8074922 0.7751375 2.7992126 0.7951262 2.7792239 0.7751375 1 P 0 N
A 2.8267717 0.7951259 2.8184923 0.7751376 2.8467602 0.7751376 1 P 0 N
A 2.8858267 0.2761384 2.8859824 0.2749003 2.8908271 0.2761384 1 P 0 N
A 2.8859825 0.2749004 2.9235738 0.2755876 2.904697 0.2796828 1 P 0 N
A 2.8976378 0.2894382 2.8991023 0.2859027 2.9026378 0.2894382 1 P 0 N
A 2.9033267 0.3444387 2.9033267 0.3294387 2.9033267 0.3369387 1 P 0 N
A 2.9051377 0.3144387 2.8976377 0.3069387 2.9051377 0.3069387 1 P 0 N
A 2.9073889 0.8445797 2.8818899 0.8551417 2.8818899 0.8190807 1 P 0 N
A 2.9091203 0.3669387 2.9166203 0.3594387 2.9166203 0.3669387 1 P 0 N
A 2.9111366 0.4003551 2.8858265 0.3525952 2.9436686 0.3525286 1 P 0 N
A 2.9111917 0.4003926 2.9127084 0.4020274 2.9083767 0.4045254 1 P 0 N
A 2.9127082 0.4020274 2.9173228 0.4191344 2.8829772 0.4192232 1 P 0 N
A 2.9150082 0.3144387 2.9150082 0.3294387 2.9150082 0.3219387 1 P 0 N
A 2.915133 0.8523918 2.8819379 0.8661417 2.8819379 0.8191967 1 P 0 N
A 2.9166213 0.3444387 2.9166213 0.3594387 2.9166213 0.3519387 1 P 0 N
A 2.9173229 0.820597 2.907389 0.8445797 2.883406 0.820597 1 P 0 N
A 2.9268527 0.4009545 2.928323 0.4044959 2.9233229 0.4044959 1 P 0 N
A 2.9283229 0.8346456 2.925101 0.842424 2.9173226 0.8346456 1 P 0 N
A 2.9284918 0.2795276 2.9235738 0.2755877 2.9284602 0.2745276 1 P 0 N
L -0.0001175 0.177913 0.5908825 0.177913 5 P 0
L -0.0004331 0.1781182 0.5901181 0.1781182 4 P 0
L 0.5901181 0.1781182 0.5901181 0.5029213 4 P 0
L 0.5901181 0.5029213 1.312559 0.5029213 4 P 0
L 0.5908825 0.177913 0.5908825 0.502913 5 P 0
L 0.8602362 1.3228347 0.8602362 2.0984252 0 P 0
L 0.8602362 1.3228347 0.996063 1.1870079 0 P 0
L 0.8602362 2.0984252 0.997847 2.236036 0 P 0
L 0.988189 1.7175197 2.5882992 1.7175197 0 P 0
L 0.9968357 2.256036 1.7322579 2.256036 0 P 0
L 0.997847 2.236036 2.4998155 2.236036 0 P 0
L 1.0048425 0.906063 1.2966929 0.906063 0 P 0
L 1.0088425 1.430063 1.0105288 1.430063 0 P 0
L 1.0098425 1.956063 1.0208425 1.967063 0 P 0
L 1.0105288 1.430063 1.0175288 1.437063 0 P 0
L 1.0175288 1.437063 2.4468425 1.437063 0 P 0
L 1.0208425 1.967063 2.4098425 1.967063 0 P 0
L 1.0208425 2.481063 1.1878425 2.314063 0 P 0
L 1.1878425 2.314063 2.4098425 2.314063 0 P 0
L 1.2948425 4.256063 1.3623867 4.256063 2 P 0
L 1.2966929 0.906063 1.3956693 0.8070866 0 P 0
L 1.312559 0.313945 1.312559 0.5029213 4 P 0
L 1.312559 0.313945 1.6275197 0.313945 4 P 0
L 1.3623867 4.256063 1.4137253 4.2047244 2 P 0
L 1.3937008 1.8169291 1.5178347 1.941063 0 P 0
L 1.3956693 0.8070866 1.769685 0.8070866 0 P 0
L 1.3996063 3.0757874 1.3996063 3.5225396 0 P 0
L 1.3996063 3.0757874 1.6348425 2.8405512 0 P 0
L 1.3996063 3.5225396 1.4005905 3.5235238 0 P 0
L 1.4005905 3.5235238 1.4005905 3.9716287 0 P 0
L 1.4005905 3.9716287 1.4084645 3.9795027 0 P 0
L 1.4084645 3.9795027 1.4084645 3.980315 0 P 0
L 1.4137253 4.2047244 1.4967344 4.2047244 2 P 0
L 1.4408425 3.557063 2.4238425 3.557063 0 P 0
L 1.4598425 3.147063 2.4354488 3.147063 0 P 0
L 1.4967344 4.2047244 1.5764588 4.2844488 2 P 0
L 1.5178347 1.941063 2.3848425 1.941063 0 P 0
L 1.5498425 3.621063 1.8709014 3.621063 0 P 0
L 1.5679134 1.2854331 1.5721654 1.2811811 0 P 0
L 1.5698819 4.1712599 1.6050788 4.136063 0 P 0
L 1.5721654 1.2811811 2.1899606 1.2811811 0 P 0
L 1.5748425 3.596063 1.5938425 3.577063 0 P 0
L 1.5764588 4.2844488 1.9094487 4.2844488 2 P 0
L 1.5938425 3.577063 2.117274 3.577063 0 P 0
L 1.6050788 4.136063 1.9863658 4.136063 0 P 0
L 1.6275197 0.313945 1.6275197 0.4310709 4 P 0
L 1.6348425 2.8405512 2.2175197 2.8405512 0 P 0
L 1.7322579 2.256036 1.7392309 2.249063 0 P 0
L 1.7392309 2.249063 2.4724882 2.249063 0 P 0
L 1.7548425 3.661063 1.7556536 3.6618741 0 P 0
L 1.7556536 3.6618741 2.6790314 3.6618741 0 P 0
L 1.769685 0.8070866 1.8686614 0.906063 0 P 0
L 1.7798425 4.156063 1.9651181 4.156063 0 P 0
L 1.7982283 1.3041339 1.8101574 1.316063 0 P 0
L 1.8101574 1.316063 2.0131267 1.316063 0 P 0
L 1.8227825 1.674003 1.8824983 1.674003 0 P 0
L 1.8498425 3.701063 6.2948425 3.701063 2 P 0
L 1.8686614 0.906063 2.4528425 0.906063 0 P 0
L 1.8709014 3.621063 1.8957125 3.6458741 0 P 0
L 1.8799377 1.811803 3.0568817 1.811803 0 P 0
L 1.8824983 1.674003 1.8835583 1.675063 0 P 0
L 1.8835583 1.675063 1.8855583 1.673063 0 P 0
L 1.8848425 3.601063 2.1159014 3.601063 0 P 0
L 1.8855583 1.673063 3.2029322 1.673063 0 P 0
L 1.8938425 1.693063 3.2045475 1.693063 0 P 0
L 1.8957125 3.6458741 2.6521765 3.6458741 0 P 0
L 1.9038425 4.018063 1.904189 4.0177165 0 P 0
L 1.904189 4.0177165 2.3533464 4.0177165 0 P 0
L 1.9094487 4.2844488 1.941929 4.3169291 2 P 0
L 1.941929 4.3169291 2.1525591 4.3169291 2 P 0
L 1.9651181 4.156063 2.0187008 4.2096457 0 P 0
L 1.9863658 4.136063 2.0023658 4.152063 0 P 0
L 2.0023658 4.152063 2.0433071 4.152063 0 P 0
L 2.0048425 1.336063 3.3798425 1.336063 0 P 0
L 2.0131267 1.316063 2.0161267 1.319063 0 P 0
L 2.0161267 1.319063 2.4998425 1.319063 0 P 0
L 2.0187008 4.2096457 2.0679106 4.2096457 0 P 0
L 2.0288425 1.361663 2.0294425 1.361063 0 P 0
L 2.0294425 1.361063 3.4025825 1.361063 0 P 0
L 2.0598425 1.386063 3.3798425 1.386063 0 P 0
L 2.0679106 4.2096457 2.1214933 4.156063 0 P 0
L 2.0838425 1.411663 2.0840125 1.411493 3 P 0
L 2.0840125 1.411493 3.4071122 1.411493 3 P 0
L 2.1159014 3.601063 2.1299014 3.587063 0 P 0
L 2.117274 3.577063 2.123274 3.571063 0 P 0
L 2.1214933 4.156063 3.9700965 4.156063 0 P 0
L 2.123274 3.571063 2.6119246 3.571063 0 P 0
L 2.1299014 3.587063 2.2578002 3.587063 0 P 0
L 2.1525591 4.3169291 2.1864252 4.283063 2 P 0
L 2.1864252 4.283063 2.5708425 4.283063 2 P 0
L 2.1899606 1.2811811 2.2068425 1.298063 0 P 0
L 2.2058425 3.200063 2.3855583 3.200063 0 P 0
L 2.2175197 2.8405512 2.3620079 2.696063 0 P 0
L 2.2348425 3.506063 2.5259014 3.506063 0 P 0
L 2.2578002 3.587063 2.3006113 3.6298741 0 P 0
L 2.2598425 3.261063 2.4055845 3.261063 0 P 0
L 2.2748425 1.506063 3.5448425 1.506063 0 P 0
L 2.2998425 1.916063 3.3344993 1.916063 0 P 0
L 2.3006113 3.6298741 2.5433214 3.6298741 0 P 0
L 2.3308425 2.215063 5.5778425 2.215063 0 P 0
L 2.3620079 2.696063 2.4948425 2.696063 0 P 0
L 2.3848425 1.941063 3.3321267 1.941063 0 P 0
L 2.3855583 3.200063 2.4115583 3.174063 0 P 0
L 2.394685 2.7204724 2.3962788 2.7188785 0 P 0
L 2.4019357 2.7165354 2.6266076 2.7165354 0 P 0
L 2.4055845 3.261063 2.4111751 3.2666536 0 P 0
L 2.4111751 3.2666536 2.6936282 3.2666536 0 P 0
L 2.4115583 3.174063 2.4281267 3.174063 0 P 0
L 2.4133858 0.2795276 2.4218882 0.2795276 1 P 0
L 2.4140551 3.1998504 2.4162199 3.1998504 0 P 0
L 2.4162199 3.1998504 2.4291017 3.2127322 0 P 0
L 2.4187174 3.1185066 2.4283989 3.1185066 0 P 0
L 2.4218882 0.2795276 2.4218883 0.2795276 1 P 0
L 2.4238425 3.557063 2.4348425 3.546063 0 P 0
L 2.4281267 3.174063 2.4541267 3.200063 0 P 0
L 2.4283989 3.1185066 2.5774173 2.9694882 0 P 0
L 2.4291017 3.2127322 2.4385117 3.2127322 0 P 0
L 2.4291925 2.621063 2.9588425 2.621063 0 P 0
L 2.4354488 3.147063 2.4606299 3.1722441 0 P 0
L 2.4385117 3.2127322 2.4608425 3.235063 0 P 0
L 2.4448819 0.2795276 2.4606299 0.2952756 1 P 0
L 2.4528425 0.906063 2.4788425 0.932063 0 P 0
L 2.4541267 3.200063 2.5774008 3.200063 0 P 0
L 2.4591027 0.3109456 2.462398 0.3076503 1 P 0
L 2.4606299 0.2952756 2.462398 0.2970437 1 P 0
L 2.4606299 3.1722441 2.462374 3.1722441 0 P 0
L 2.4608425 3.235063 2.6804223 3.235063 0 P 0
L 2.4633015 0.2812475 2.4633017 0.2812476 1 P 0
L 2.4647316 0.2852354 2.5633894 0.3838931 1 P 0
L 2.4697093 0.3215522 2.4730044 0.3182571 1 P 0
L 2.4724882 2.249063 2.4940945 2.2706693 0 P 0
L 2.4788425 0.932063 2.4788425 0.937063 0 P 0
L 2.481143 0.3313317 2.483611 0.3288637 1 P 0
L 2.4917496 0.3419383 2.4942176 0.3394703 1 P 0
L 2.4940945 2.2706693 2.5295275 2.2706693 0 P 0
L 2.4948425 2.661063 4.1147946 2.661063 0 P 0
L 2.4948425 2.696063 2.5098425 2.681063 0 P 0
L 2.4998155 2.236036 2.4998425 2.236063 0 P 0
L 2.4998425 1.319063 2.5028425 1.316063 0 P 0
L 2.4998425 2.236063 5.6348425 2.236063 0 P 0
L 2.5048234 0.3500777 2.5048242 0.3500769 1 P 0
L 2.5098425 2.681063 4.2129048 2.681063 0 P 0
L 2.51543 0.3606843 2.515431 0.3606833 1 P 0
L 2.5154309 0.3606832 2.515431 0.3606833 1 P 0
L 2.5258425 2.463063 2.5985583 2.463063 0 P 0
L 2.5259014 3.506063 2.5699014 3.462063 0 P 0
L 2.5260376 0.3606833 2.5435917 0.3782374 1 P 0
L 2.5295275 2.2706693 2.5492125 2.2509843 0 P 0
L 2.5433214 3.6298741 2.5571325 3.616063 0 P 0
L 2.5435917 0.3782374 2.5537187 0.3883644 1 P 0
L 2.5492125 2.2509843 2.6082678 2.2509843 0 P 0
L 2.5498425 1.755063 2.6121267 1.755063 0 P 0
L 2.555929 0.3937008 2.5559291 0.3937008 1 P 0
L 2.5559291 0.3937008 2.5559291 0.8025492 1 P 0
L 2.5571325 3.616063 2.7998425 3.616063 0 P 0
L 2.5669291 0.3909404 2.5669292 0.8025514 1 P 0
L 2.5699014 3.462063 3.0371764 3.462063 0 P 0
L 2.5708466 0.8385633 2.6010375 0.8687542 1 P 0
L 2.5758425 2.412063 2.5801721 2.412063 0 P 0
L 2.5772301 0.2979658 2.5772302 0.2979657 1 P 0
L 2.5774008 3.200063 2.5912433 3.1862205 0 P 0
L 2.5774173 2.9694882 3.0965519 2.9694882 0 P 0
L 2.5786443 0.8308047 2.5786444 0.8308046 1 P 0
L 2.5786443 0.8308047 2.6088541 0.8610145 1 P 0
L 2.5798425 1.790063 2.6351267 1.790063 0 P 0
L 2.5801721 2.412063 2.5861721 2.406063 0 P 0
L 2.5840758 0.305536 2.587926 0.3207438 1 P 0
L 2.5861721 2.406063 4.0398425 2.406063 0 P 0
L 2.5882992 1.7175197 2.6048425 1.734063 0 P 0
L 2.5900611 0.3271215 2.5900615 0.4044314 1 P 0
L 2.590077 0.4048252 2.5900772 0.4048252 1 P 0
L 2.5908425 3.288063 2.5930073 3.288063 0 P 0
L 2.5912433 3.1862205 2.5918425 3.1862205 0 P 0
L 2.5924267 0.2977757 2.5976396 0.3183668 1 P 0
L 2.5930073 3.288063 2.5980073 3.293063 0 P 0
L 2.5967244 0.2751896 2.5967439 0.2752696 1 P 0
L 2.5976395 0.3183668 2.5976396 0.3183668 1 P 0
L 2.5980073 3.293063 3.2528425 3.293063 0 P 0
L 2.5985583 2.463063 2.6165583 2.481063 0 P 0
L 2.6000644 0.2788024 2.6000644 0.2788025 1 P 0
L 2.6023617 0.3765263 2.6023619 0.3872638 1 P 0
L 2.6023619 0.3872638 2.602362 0.3897637 1 P 0
L 2.602362 0.3897637 2.602362 0.3897638 1 P 0
L 2.602362 0.3897637 2.6023622 0.3968183 1 P 0
L 2.60464 0.2795276 2.6102362 0.2795276 1 P 0
L 2.6048425 1.734063 3.5789014 1.734063 0 P 0
L 2.6049102 0.3240262 2.6197278 0.3240262 1 P 0
L 2.6075616 0.3390262 2.6197278 0.3390262 1 P 0
L 2.6075616 0.3540262 2.6160907 0.3540262 1 P 0
L 2.6082678 2.2509843 2.6298158 2.2725323 0 P 0
L 2.6085063 0.4571723 2.6085063 0.4571724 1 P 0
L 2.6098617 0.3690262 2.6160907 0.3690262 1 P 0
L 2.6119246 3.571063 2.6369246 3.596063 0 P 0
L 2.6121267 1.755063 2.6171267 1.750063 0 P 0
L 2.6165583 2.481063 2.9238425 2.481063 0 P 0
L 2.6171267 1.750063 3.4838639 1.750063 0 P 0
L 2.6220472 0.9762286 2.6220472 0.976378 1 P 0
L 2.6258961 0.4802268 2.6443446 0.4986753 1 P 0
L 2.6268425 1.770063 2.6290073 1.770063 0 P 0
L 2.6290073 1.770063 2.6330073 1.766063 0 P 0
L 2.6298158 2.2725323 2.6443118 2.2725323 0 P 0
L 2.6303268 0.9394649 2.6303268 0.9562399 1 P 0
L 2.6322781 2.7188922 2.6659503 2.7525644 0 P 0
L 2.6330073 1.766063 3.4758425 1.766063 0 P 0
L 2.6337624 0.472537 2.6337625 0.4725369 1 P 0
L 2.6337625 0.4725369 2.6521612 0.4909356 1 P 0
L 2.6351267 1.790063 2.6461267 1.779063 0 P 0
L 2.6369246 3.596063 3.2398425 3.596063 0 P 0
L 2.6413268 0.9394103 2.6413268 0.95624 1 P 0
L 2.6438425 1.616063 3.4696294 1.616063 0 P 0
L 2.6443118 2.2725323 2.6458425 2.274063 0 P 0
L 2.6461267 1.779063 3.4658425 1.779063 0 P 0
L 2.6496063 0.9762283 2.6496063 0.9762285 1 P 0
L 2.6496063 0.9762285 2.6496063 0.976378 1 P 0
L 2.6521765 3.6458741 2.6619876 3.636063 0 P 0
L 2.6619876 3.636063 3.4248425 3.636063 0 P 0
L 2.6653543 0.7951262 2.6653543 0.7952756 1 P 0
L 2.6668425 1.640063 2.6678425 1.641063 0 P 0
L 2.6678425 1.641063 3.7827652 1.641063 0 P 0
L 2.6715808 2.7549211 2.6716209 2.7549213 0 P 0
L 2.6716209 2.7549213 3.089567 2.7549213 0 P 0
L 2.6736339 0.569386 2.6736339 0.7751375 1 P 0
L 2.6790314 3.6618741 2.6798425 3.661063 0 P 0
L 2.6804223 3.235063 2.7029223 3.257563 0 P 0
L 2.6846339 0.5693314 2.6846339 0.7751376 1 P 0
L 2.6929134 0.7951259 2.6929134 0.7952756 1 P 0
L 2.6936282 3.2666536 2.7000376 3.273063 0 P 0
L 2.6948425 1.481063 3.5437836 1.481063 0 P 0
L 2.7000376 3.273063 3.3748425 3.273063 0 P 0
L 2.7029223 3.257563 2.9746059 3.257563 0 P 0
L 2.7198425 1.591063 3.0823425 1.591063 0 P 0
L 2.7339149 0.3031179 2.7405377 0.3031179 1 P 0
L 2.7339149 0.3181179 2.7505469 0.3181179 1 P 0
L 2.7339267 0.3331179 2.7505469 0.3331179 1 P 0
L 2.7339267 0.3481179 2.7405615 0.3481179 1 P 0
L 2.7374166 0.2674146 2.7374436 0.2673869 1 P 0
L 2.7379035 0.38751 2.7874016 0.4370081 1 P 0
L 2.7401575 0.9762285 2.7401575 0.976378 1 P 0
L 2.7480334 0.2850057 2.7480335 0.2850057 1 P 0
L 2.7480335 0.2850057 2.7480353 0.2893674 1 P 0
L 2.7480353 0.2893674 2.7480362 0.2918674 1 P 0
L 2.7480362 0.2918674 2.7480377 0.295615 1 P 0
L 2.7480376 0.295615 2.7480377 0.295615 1 P 0
L 2.7480614 0.3556149 2.7480615 0.3556149 1 P 0
L 2.7480615 0.3556149 2.7480703 0.3775521 1 P 0
L 2.7480703 0.3775521 2.7480712 0.3800521 1 P 0
L 2.7480712 0.380052 2.7480713 0.3800522 1 P 0
L 2.748437 0.9408906 2.748437 0.95624 1 P 0
L 2.7488196 0.2823122 2.74882 0.282312 1 P 0
L 2.7495358 0.3835858 2.7952139 0.4292639 1 P 0
L 2.759437 0.940945 2.759437 0.95624 1 P 0
L 2.7624692 0.9070139 2.7818567 0.8876264 1 P 0
L 2.7677165 0.9762283 2.7677165 0.976378 1 P 0
L 2.7702859 0.9147535 2.7896083 0.8954311 1 P 0
L 2.771025 0.2795276 2.7795276 0.2795276 1 P 0
L 2.7992126 0.7951262 2.7992126 0.7952756 1 P 0
L 2.8038425 2.307063 2.8378425 2.341063 0 P 0
L 2.8074922 0.4855108 2.8074922 0.7751375 1 P 0
L 2.8184922 0.4854626 2.8184922 0.7751376 1 P 0
L 2.8218425 2.601063 3.5665583 2.601063 0 P 0
L 2.8267717 0.7951259 2.8267717 0.7952756 1 P 0
L 2.8378425 2.341063 3.4988425 2.341063 0 P 0
L 2.8418425 2.263063 3.3428425 2.263063 0 P 0
L 2.8602814 0.8551418 2.8818899 0.8551418 1 P 0
L 2.860319 0.8661418 2.8819379 0.8661418 1 P 0
L 2.8818899 0.8551417 2.8818899 0.8551418 1 P 0
L 2.8858266 0.3525952 2.8858267 0.3525504 1 P 0
L 2.8858267 0.2761384 2.8858267 0.3525504 1 P 0
L 2.8948425 1.561063 3.3278424 1.561063 0 P 0
L 2.8976377 0.2919382 2.8976377 0.3069387 1 P 0
L 2.8976377 0.2919382 2.8976378 0.2894382 1 P 0
L 2.8991022 0.2859026 2.8991023 0.2859027 1 P 0
L 2.8991023 0.2859027 2.9054946 0.2795104 1 P 0
L 2.9033267 0.3294387 2.9150082 0.3294387 1 P 0
L 2.9033267 0.3444387 2.9166213 0.3444387 1 P 0
L 2.9051377 0.3144387 2.9150082 0.3144387 1 P 0
L 2.9091203 0.3669387 2.9091203 0.3811515 1 P 0
L 2.9091203 0.3811515 2.9105847 0.384687 1 P 0
L 2.9105847 0.384687 2.9239307 0.3980326 1 P 0
L 2.9111366 0.4003551 2.9111917 0.4003926 1 P 0
L 2.9127082 0.4020274 2.9127084 0.4020274 1 P 0
L 2.9151331 0.8523919 2.925101 0.842424 1 P 0
L 2.9166203 0.3594387 2.9166213 0.3594387 1 P 0
L 2.9173227 0.4191344 2.9173229 0.4192037 1 P 0
L 2.9173229 0.4192037 2.9173229 0.820597 1 P 0
L 2.9198425 1.536063 3.8737836 1.536063 0 P 0
L 2.9235737 0.2755877 2.9235738 0.2755876 1 P 0
L 2.9238425 2.481063 2.9488425 2.456063 0 P 0
L 2.9239307 0.3980326 2.9264307 0.4005326 1 P 0
L 2.9264307 0.4005325 2.9268527 0.4009545 1 P 0
L 2.9283229 0.4044959 2.9283229 0.8346456 1 P 0
L 2.9284918 0.2795276 2.9370079 0.2795276 1 P 0
L 2.9746059 3.257563 2.9971059 3.235063 0 P 0
L 2.9933858 3.751063 3.6998425 3.751063 0 P 0
L 2.9971059 3.235063 3.2308425 3.235063 0 P 0
L 3.0148425 3.831063 3.0148425 3.8313767 0 P 0
L 3.0148425 3.8313767 3.0195288 3.836063 0 P 0
L 3.0195288 3.836063 3.6998425 3.836063 0 P 0
L 3.0371764 3.462063 3.0561764 3.481063 0 P 0
L 3.0561764 3.481063 3.5298425 3.481063 0 P 0
L 3.0823425 1.591063 3.0913425 1.600063 0 P 0
L 3.089567 2.7549213 3.2322834 2.8976377 0 P 0
L 3.0913425 1.600063 3.6993192 1.600063 0 P 0
L 3.0965519 2.9694882 3.0971267 2.970063 0 P 0
L 3.0971267 2.970063 3.1978425 2.970063 0 P 0
L 3.1830708 3.1358268 3.2106299 3.1358268 0 P 0
L 3.1889764 3.1870079 3.2322834 3.1870079 0 P 0
L 3.2029322 1.673063 3.2112164 1.6813472 0 P 0
L 3.2045475 1.693063 3.2058317 1.6943472 0 P 0
L 3.2058317 1.6943472 3.3121311 1.6943472 0 P 0
L 3.2106299 3.1358268 3.2627952 3.1879921 0 P 0
L 3.2112164 1.6813472 3.3067464 1.6813472 0 P 0
L 3.2322834 2.8976377 3.2322834 3.0984252 0 P 0
L 3.2322834 3.0984252 3.2755905 3.1417323 0 P 0
L 3.2322834 3.1870079 3.2608267 3.2155512 0 P 0
L 3.2528425 3.293063 3.2636972 3.3039177 0 P 0
L 3.2608267 3.2155512 3.468504 3.2155512 0 P 0
L 3.2627952 3.1879921 3.2972441 3.1879921 0 P 0
L 3.2755905 2.984252 3.2755905 3.019685 0 P 0
L 3.2755905 2.984252 3.2762598 2.9835827 0 P 0
L 3.2755905 3.019685 3.3316929 3.0757874 0 P 0
L 3.2762598 2.9648819 3.2762598 2.9835827 0 P 0
L 3.2762598 2.9648819 3.277559 2.9635827 0 P 0
L 3.277559 2.9635827 3.351548 2.8895937 0 P 0
L 3.2972441 3.1879921 3.3316929 3.1535433 0 P 0
L 3.3028425 3.344063 3.6125583 3.344063 0 P 0
L 3.3067464 1.6813472 3.3074427 1.6806509 0 P 0
L 3.3074427 1.6806509 3.4296266 1.6806509 0 P 0
L 3.3121311 1.6943472 3.3128274 1.6936509 0 P 0
L 3.3128274 1.6936509 3.4191267 1.6936509 0 P 0
L 3.3278424 1.561063 3.3368424 1.552063 0 P 0
L 3.3316929 3.0757874 3.3316929 3.1535433 0 P 0
L 3.3321267 1.941063 3.3571267 1.916063 0 P 0
L 3.3344993 1.916063 3.3504993 1.900063 0 P 0
L 3.3368424 1.552063 3.7698425 1.552063 0 P 0
L 3.3504993 1.900063 3.4440668 1.900063 0 P 0
L 3.351548 2.8895937 3.3693118 2.8895937 0 P 0
L 3.3571267 1.916063 3.5697836 1.916063 0 P 0
L 3.3666857 3.270563 3.367655 3.2715323 0 P 0
L 3.367655 3.2715323 3.3733118 3.2715323 0 P 0
L 3.3693118 2.8895937 3.3708425 2.888063 0 P 0
L 3.3733118 3.2715323 3.3748425 3.273063 0 P 0
L 3.3948425 3.447063 3.4413149 3.4005906 0 P 0
L 3.4025825 1.361063 3.4048425 1.363323 0 P 0
L 3.4071122 1.411493 3.4072822 1.411323 3 P 0
L 3.4191267 1.6936509 3.4365388 1.711063 0 P 0
L 3.4296266 1.6806509 3.4310387 1.682063 0 P 0
L 3.4310387 1.682063 3.5991267 1.682063 0 P 0
L 3.4365388 1.711063 3.5898425 1.711063 0 P 0
L 3.4368425 3.457063 3.4578425 3.436063 0 P 0
L 3.4413149 3.4005906 4.9268701 3.4005906 0 P 0
L 3.4440668 1.900063 3.4530668 1.891063 0 P 0
L 3.4530668 1.891063 3.5548425 1.891063 0 P 0
L 3.4578425 3.436063 6.4698425 3.436063 0 P 0
L 3.4658425 1.779063 3.4868425 1.800063 0 P 0
L 3.468504 3.2155512 3.6870079 2.9970473 0 P 0
L 3.4696294 1.616063 3.4771896 1.6236232 0 P 0
L 3.4698425 3.456063 6.5098425 3.456063 0 P 0
L 3.4758425 1.766063 3.4938425 1.784063 0 P 0
L 3.4771896 1.6236232 4.1513063 1.6236232 0 P 0
L 3.4838639 1.750063 3.4998639 1.766063 0 P 0
L 3.4868425 1.800063 3.6358639 1.800063 0 P 0
L 3.4938425 1.784063 3.7039014 1.784063 0 P 0
L 3.4998639 1.766063 3.7198425 1.766063 0 P 0
L 3.5048425 4.086063 3.5076771 4.0888976 0 P 0
L 3.5076771 4.0888976 5.2670079 4.0888976 0 P 0
L 3.542865 3.3190405 6.3426504 3.3190405 0 P 0
L 3.5437836 1.481063 3.5847836 1.440063 0 P 0
L 3.5448425 1.506063 3.5948425 1.456063 0 P 0
L 3.5665583 2.601063 3.5715583 2.606063 0 P 0
L 3.5697836 1.916063 3.5887836 1.897063 0 P 0
L 3.5715583 2.606063 3.6048425 2.606063 0 P 0
L 3.5789014 1.734063 3.5799014 1.735063 0 P 0
L 3.5799014 1.735063 4.1169015 1.735063 0 P 0
L 3.5847836 1.440063 3.9938425 1.440063 0 P 0
L 3.5887836 1.897063 3.7478425 1.897063 0 P 0
L 3.5948425 1.456063 3.9228425 1.456063 0 P 0
L 3.5991267 1.682063 3.6061267 1.675063 0 P 0
L 3.6048425 2.606063 3.6238425 2.587063 0 P 0
L 3.6061267 1.675063 3.7248425 1.675063 0 P 0
L 3.6125583 3.344063 3.6395583 3.371063 0 P 0
L 3.6358639 1.800063 3.6518639 1.816063 0 P 0
L 3.6395583 3.371063 6.4098425 3.371063 0 P 0
L 3.6518639 1.816063 3.9448425 1.816063 0 P 0
L 3.6538425 3.293063 3.6553732 3.2945937 0 P 0
L 3.6553732 3.2945937 3.66103 3.2945937 0 P 0
L 3.66103 3.2945937 3.6624993 3.296063 0 P 0
L 3.6624993 3.296063 6.4333481 3.296063 0 P 0
L 3.6870079 2.9970473 4.6053149 2.9970473 0 P 0
L 3.6993192 1.600063 3.7053192 1.606063 0 P 0
L 3.7039014 1.784063 3.7099015 1.7900631 0 P 0
L 3.7053192 1.606063 3.9529609 1.606063 0 P 0
L 3.7099015 1.7900631 3.9937072 1.7900631 0 P 0
L 3.7448425 3.261063 3.7470073 3.261063 0 P 0
L 3.7470073 3.261063 3.7507081 3.2647638 0 P 0
L 3.7478425 1.897063 3.8048425 1.840063 0 P 0
L 3.7507081 3.2647638 5.0495433 3.2647638 0 P 0
L 3.7698425 1.552063 3.8078425 1.590063 0 P 0
L 3.7827652 1.641063 3.7927652 1.651063 0 P 0
L 3.7927652 1.651063 4.1348425 1.651063 0 P 0
L 3.7998425 3.201063 3.8008425 3.200063 0 P 0
L 3.8008425 3.200063 6.3084161 3.200063 0 P 0
L 3.8068425 3.235063 6.2690865 3.235063 0 P 0
L 3.8078425 1.590063 3.9047836 1.590063 0 P 0
L 3.8298425 3.176063 6.2748425 3.176063 0 P 0
L 3.8548425 3.151063 3.8570073 3.151063 0 P 0
L 3.8570073 3.151063 3.8610072 3.1550629 0 P 0
L 3.8610072 3.1550629 4.0605582 3.1550629 0 P 0
L 3.8737836 1.536063 3.8977836 1.512063 0 P 0
L 3.8977836 1.512063 3.9581267 1.512063 0 P 0
L 3.9047836 1.590063 3.9308425 1.5640041 0 P 0
L 3.9228425 1.456063 3.9398425 1.473063 0 P 0
L 3.9308425 1.5640041 3.9519014 1.5640041 0 P 0
L 3.9398425 1.473063 3.9618425 1.473063 0 P 0
L 3.9398425 3.121063 3.9420073 3.121063 0 P 0
L 3.9420073 3.121063 3.9480072 3.1150631 0 P 0
L 3.9480072 3.1150631 4.0125669 3.1150631 0 P 0
L 3.9519014 1.5640041 3.9638425 1.552063 0 P 0
L 3.9529609 1.606063 3.9594007 1.5996232 0 P 0
L 3.9581267 1.512063 3.9898425 1.5437788 0 P 0
L 3.9594007 1.5996232 4.1784027 1.5996232 0 P 0
L 3.9618425 1.473063 4.0348425 1.546063 0 P 0
L 3.9638425 1.552063 3.9698425 1.552063 0 P 0
L 3.9700965 4.156063 4.0102271 4.1159324 0 P 0
L 3.9898425 1.5437788 3.9898425 1.5438982 0 P 0
L 3.9898425 1.5438982 3.9948425 1.5488982 0 P 0
L 3.9937072 1.7900631 3.9997071 1.796063 0 P 0
L 3.9938425 1.440063 4.0648425 1.511063 0 P 0
L 3.9948425 1.5488982 3.9948425 1.551063 0 P 0
L 3.9997071 1.796063 4.0648425 1.796063 0 P 0
L 4.0102271 4.1159324 4.7547119 4.1159324 0 P 0
L 4.0125669 3.1150631 4.012567 3.115063 0 P 0
L 4.012567 3.115063 6.2966777 3.115063 0 P 0
L 4.0605582 3.1550629 4.0605583 3.155063 0 P 0
L 4.0605583 3.155063 6.3336777 3.155063 0 P 0
L 4.1147946 2.661063 4.1805146 2.595343 0 P 0
L 4.1169015 1.735063 4.1329015 1.751063 0 P 0
L 4.1329015 1.751063 4.1348425 1.751063 0 P 0
L 4.1784027 1.5996232 4.1798425 1.601063 0 P 0
L 4.2129048 2.681063 4.2986248 2.595343 0 P 0
L 4.6053149 2.9970473 4.7942913 2.8080709 0 P 0
L 4.9268701 3.4005906 4.9273425 3.401063 0 P 0
L 4.9273425 3.401063 6.4404124 3.401063 0 P 0
L 5.0495433 3.2647638 5.0508425 3.266063 0 P 0
L 5.0508425 3.266063 6.3348425 3.266063 0 P 0
L 6.2690865 3.235063 6.2780865 3.226063 0 P 0
L 6.2748425 3.176063 6.2758425 3.175063 0 P 0
L 6.2758425 3.175063 6.3617929 3.175063 0 P 0
L 6.2780865 3.226063 6.2824161 3.226063 0 P 0
L 6.2966777 3.115063 6.3026777 3.121063 0 P 0
L 6.3026777 3.121063 6.3048425 3.121063 0 P 0
L 6.3084161 3.200063 6.3094161 3.199063 0 P 0
L 6.3336777 3.155063 6.3376777 3.151063 0 P 0
L 6.3376777 3.151063 6.3398425 3.151063 0 P 0
L 6.3426504 3.3190405 6.3547483 3.3311384 0 P 0
L 6.3617929 3.175063 6.3777929 3.191063 0 P 0
L 6.3777929 3.191063 6.4398425 3.191063 0 P 0
L 6.4333481 3.296063 6.4383481 3.291063 0 P 0
L 6.4383481 3.291063 6.4448425 3.291063 0 P 0
L 6.4404124 3.401063 6.4454124 3.396063 0 P 0
L 6.4454124 3.396063 6.4475772 3.396063 0 P 0
L 6.4698425 3.436063 6.4798425 3.426063 0 P 0
P 2.0433071 4.157874 7 P 0 0 ;0=1,1=0
P 4.1805146 2.595343 6 P 0 0 ;0=0,1=0
P 4.2986248 2.595343 6 P 0 0 ;0=0,1=0
P 0.988189 1.7175197 8 P 0 0 ;0=2,1=1
P 0.996063 1.1870079 8 P 0 0 ;0=2,1=1
P 0.9968357 2.256036 8 P 0 0 ;0=2,1=1
P 1.0048425 0.906063 8 P 0 0 ;0=2,1=1
P 1.0088425 1.430063 8 P 0 0 ;0=2,1=1
P 1.0098425 1.956063 8 P 0 0 ;0=2,1=1
P 1.0208425 2.481063 8 P 0 0 ;0=2,1=1
P 1.2948425 4.256063 8 P 0 0 ;0=2,1=1
P 1.3937008 1.8169291 8 P 0 0 ;0=2,1=1
P 1.4084645 3.980315 8 P 0 0 ;0=2,1=1
P 1.4408425 3.557063 8 P 0 0 ;0=2,1=1
P 1.4598425 3.147063 8 P 0 0 ;0=2,1=1
P 1.5498425 3.621063 8 P 0 0 ;0=2,1=1
P 1.5679134 1.2854331 8 P 0 0 ;0=2,1=1
P 1.5698819 4.1712599 8 P 0 0 ;0=2,1=1
P 1.5748425 3.596063 8 P 0 0 ;0=2,1=1
P 1.7548425 3.661063 8 P 0 0 ;0=2,1=1
P 1.7798425 4.156063 8 P 0 0 ;0=2,1=1
P 1.7982283 1.3041339 8 P 0 0 ;0=2,1=1
P 1.8227825 1.674003 8 P 0 0 ;0=2,1=1
P 1.8498425 3.701063 8 P 0 0 ;0=2,1=1
P 1.8799377 1.811803 8 P 0 0 ;0=2,1=1
P 1.8848425 3.601063 8 P 0 0 ;0=2,1=1
P 1.8938425 1.693063 8 P 0 0 ;0=2,1=1
P 1.9038425 4.018063 8 P 0 0 ;0=2,1=1
P 2.0048425 1.336063 8 P 0 0 ;0=2,1=1
P 2.0288425 1.361663 8 P 0 0 ;0=2,1=1
P 2.0598425 1.386063 8 P 0 0 ;0=2,1=1
P 2.0838425 1.411663 8 P 0 0 ;0=2,1=1
P 2.2058425 3.200063 8 P 0 0 ;0=2,1=1
P 2.2068425 1.298063 8 P 0 0 ;0=2,1=1
P 2.2348425 3.506063 8 P 0 0 ;0=2,1=1
P 2.2598425 3.261063 8 P 0 0 ;0=2,1=1
P 2.2748425 1.506063 8 P 0 0 ;0=2,1=1
P 2.2998425 1.916063 8 P 0 0 ;0=2,1=1
P 2.3308425 2.215063 8 P 0 0 ;0=2,1=1
P 2.3533464 4.0177165 8 P 0 0 ;0=2,1=1
P 2.3848425 1.941063 8 P 0 0 ;0=2,1=1
P 2.394685 2.7204724 8 P 0 0 ;0=2,1=1
P 2.4098425 1.967063 8 P 0 0 ;0=2,1=1
P 2.4098425 2.314063 8 P 0 0 ;0=2,1=1
P 2.4133858 0.2795276 8 P 0 0 ;0=2,1=1
P 2.4140551 3.1998504 8 P 0 0 ;0=2,1=1
P 2.4187174 3.1185066 8 P 0 0 ;0=2,1=1
P 2.4291925 2.621063 8 P 0 0 ;0=2,1=1
P 2.4348425 3.546063 8 P 0 0 ;0=2,1=1
P 2.4448819 0.2795276 8 P 0 0 ;0=2,1=1
P 2.4468425 1.437063 8 P 0 0 ;0=2,1=1
P 2.462374 3.1722441 8 P 0 0 ;0=2,1=1
P 2.4788425 0.937063 8 P 0 0 ;0=2,1=1
P 2.4948425 2.661063 8 P 0 0 ;0=2,1=1
P 2.4948425 2.696063 8 P 0 0 ;0=2,1=1
P 2.4998425 2.236063 8 P 0 0 ;0=2,1=1
P 2.5028425 1.316063 8 P 0 0 ;0=2,1=1
P 2.5258425 2.463063 8 P 0 0 ;0=2,1=1
P 2.5498425 1.755063 8 P 0 0 ;0=2,1=1
P 2.5708425 4.283063 8 P 0 0 ;0=2,1=1
P 2.5758425 2.412063 8 P 0 0 ;0=2,1=1
P 2.5787402 0.2795276 8 P 0 0 ;0=2,1=1
P 2.5798425 1.790063 8 P 0 0 ;0=2,1=1
P 2.5908425 3.288063 8 P 0 0 ;0=2,1=1
P 2.5918425 3.1862205 8 P 0 0 ;0=2,1=1
P 2.6048425 1.734063 8 P 0 0 ;0=2,1=1
P 2.6102362 0.2795276 8 P 0 0 ;0=2,1=1
P 2.6220472 0.976378 8 P 0 0 ;0=2,1=1
P 2.6268425 1.770063 8 P 0 0 ;0=2,1=1
P 2.6438425 1.616063 8 P 0 0 ;0=2,1=1
P 2.6458425 2.274063 8 P 0 0 ;0=2,1=1
P 2.6496063 0.976378 8 P 0 0 ;0=2,1=1
P 2.6653543 0.7952756 8 P 0 0 ;0=2,1=1
P 2.6668425 1.640063 8 P 0 0 ;0=2,1=1
P 2.6798425 3.661063 8 P 0 0 ;0=2,1=1
P 2.6929134 0.7952756 8 P 0 0 ;0=2,1=1
P 2.6948425 1.481063 8 P 0 0 ;0=2,1=1
P 2.7198425 1.591063 8 P 0 0 ;0=2,1=1
P 2.7401575 0.976378 8 P 0 0 ;0=2,1=1
P 2.74882 0.282312 8 P 0 0 ;0=2,1=1
P 2.7677165 0.976378 8 P 0 0 ;0=2,1=1
P 2.7795276 0.2795276 8 P 0 0 ;0=2,1=1
P 2.7992126 0.7952756 8 P 0 0 ;0=2,1=1
P 2.7998425 3.616063 8 P 0 0 ;0=2,1=1
P 2.8038425 2.307063 8 P 0 0 ;0=2,1=1
P 2.8218425 2.601063 8 P 0 0 ;0=2,1=1
P 2.8267717 0.7952756 8 P 0 0 ;0=2,1=1
P 2.8418425 2.263063 8 P 0 0 ;0=2,1=1
P 2.8948425 1.561063 8 P 0 0 ;0=2,1=1
P 2.9054946 0.2795104 8 P 0 0 ;0=2,1=1
P 2.9198425 1.536063 8 P 0 0 ;0=2,1=1
P 2.9370079 0.2795276 8 P 0 0 ;0=2,1=1
P 2.9488425 2.456063 8 P 0 0 ;0=2,1=1
P 2.9588425 2.621063 8 P 0 0 ;0=2,1=1
P 2.9933858 3.751063 8 P 0 0 ;0=2,1=1
P 3.0148425 3.831063 8 P 0 0 ;0=2,1=1
P 3.0568817 1.811803 8 P 0 0 ;0=2,1=1
P 3.1830708 3.1358268 8 P 0 0 ;0=2,1=1
P 3.1889764 3.1870079 8 P 0 0 ;0=2,1=1
P 3.1978425 2.970063 8 P 0 0 ;0=2,1=1
P 3.2308425 3.235063 8 P 0 0 ;0=2,1=1
P 3.2398425 3.596063 8 P 0 0 ;0=2,1=1
P 3.2636972 3.3039177 8 P 0 0 ;0=2,1=1
P 3.2755905 3.1417323 8 P 0 0 ;0=2,1=1
P 3.277559 2.9635827 8 P 0 0 ;0=2,1=1
P 3.3028425 3.344063 8 P 0 0 ;0=2,1=1
P 3.3428425 2.263063 8 P 0 0 ;0=2,1=1
P 3.3708425 2.888063 8 P 0 0 ;0=2,1=1
P 3.3748425 3.273063 8 P 0 0 ;0=2,1=1
P 3.3798425 1.336063 8 P 0 0 ;0=2,1=1
P 3.3798425 1.386063 8 P 0 0 ;0=2,1=1
P 3.3948425 3.447063 8 P 0 0 ;0=2,1=1
P 3.4048425 1.363323 8 P 0 0 ;0=2,1=1
P 3.4072822 1.411323 8 P 0 0 ;0=2,1=1
P 3.4248425 3.636063 8 P 0 0 ;0=2,1=1
P 3.4368425 3.457063 8 P 0 0 ;0=2,1=1
P 3.4698425 3.456063 8 P 0 0 ;0=2,1=1
P 3.4988425 2.341063 8 P 0 0 ;0=2,1=1
P 3.5048425 4.086063 8 P 0 0 ;0=2,1=1
P 3.5298425 3.481063 8 P 0 0 ;0=2,1=1
P 3.542865 3.3190405 8 P 0 0 ;0=2,1=1
P 3.5548425 1.891063 8 P 0 0 ;0=2,1=1
P 3.5898425 1.711063 8 P 0 0 ;0=2,1=1
P 3.6238425 2.587063 8 P 0 0 ;0=2,1=1
P 3.6538425 3.293063 8 P 0 0 ;0=2,1=1
P 3.6998425 3.751063 8 P 0 0 ;0=2,1=1
P 3.6998425 3.836063 8 P 0 0 ;0=2,1=1
P 3.7198425 1.766063 8 P 0 0 ;0=2,1=1
P 3.7248425 1.675063 8 P 0 0 ;0=2,1=1
P 3.7448425 3.261063 8 P 0 0 ;0=2,1=1
P 3.7998425 3.201063 8 P 0 0 ;0=2,1=1
P 3.8048425 1.840063 8 P 0 0 ;0=2,1=1
P 3.8068425 3.235063 8 P 0 0 ;0=2,1=1
P 3.8298425 3.176063 8 P 0 0 ;0=2,1=1
P 3.8548425 3.151063 8 P 0 0 ;0=2,1=1
P 3.9398425 3.121063 8 P 0 0 ;0=2,1=1
P 3.9448425 1.816063 8 P 0 0 ;0=2,1=1
P 3.9698425 1.552063 8 P 0 0 ;0=2,1=1
P 3.9948425 1.551063 8 P 0 0 ;0=2,1=1
P 4.0348425 1.546063 8 P 0 0 ;0=2,1=1
P 4.0398425 2.406063 8 P 0 0 ;0=2,1=1
P 4.0648425 1.511063 8 P 0 0 ;0=2,1=1
P 4.0648425 1.796063 8 P 0 0 ;0=2,1=1
P 4.1348425 1.651063 8 P 0 0 ;0=2,1=1
P 4.1348425 1.751063 8 P 0 0 ;0=2,1=1
P 4.1513063 1.6236232 8 P 0 0 ;0=2,1=1
P 4.1798425 1.601063 8 P 0 0 ;0=2,1=1
P 4.7547119 4.1159324 8 P 0 0 ;0=2,1=1
P 4.7942913 2.8080709 8 P 0 0 ;0=2,1=1
P 5.2670079 4.0888976 8 P 0 0 ;0=2,1=1
P 5.5778425 2.214063 8 P 0 0 ;0=2,1=1
P 5.6348425 2.236063 8 P 0 0 ;0=2,1=1
P 6.2824161 3.226063 8 P 0 0 ;0=2,1=1
P 6.2948425 3.701063 8 P 0 0 ;0=2,1=1
P 6.3048425 3.121063 8 P 0 0 ;0=2,1=1
P 6.3094161 3.199063 8 P 0 0 ;0=2,1=1
P 6.3348425 3.266063 8 P 0 0 ;0=2,1=1
P 6.3398425 3.151063 8 P 0 0 ;0=2,1=1
P 6.3547483 3.3311384 8 P 0 0 ;0=2,1=1
P 6.4098425 3.371063 8 P 0 0 ;0=2,1=1
P 6.4398425 3.191063 8 P 0 0 ;0=2,1=1
P 6.4448425 3.291063 8 P 0 0 ;0=2,1=1
P 6.4475772 3.396063 8 P 0 0 ;0=2,1=1
P 6.4798425 3.426063 8 P 0 0 ;0=2,1=1
P 6.5098425 3.456063 8 P 0 0 ;0=2,1=1

### steps/pcb/layers/in2/features
#Layer_Physical_Order=4
#Layer_Color=6736896
#
#Feature symbol names
#
$0 r8
$1 r5
$2 r20
$3 r6
$4 r3.937
$5 r1
$6 r61.0236
$7 r75
$8 s55
$9 r16

#
#Feature attribute names
#
@0 .geometry
@1 .pad_usage

#
#Feature attribute text strings
#
&0 Pad_Simple_X61.0236Y61.0236H41.3386C81.3386
&1 Pad_Simple_X75.0000Y75.0000H50.0000C90.0000
&2 Pad_Simple_X55.0000Y55.0000H30.0000C70.0000
&3 VIA_RoundD16.0000H8.0000C48.0000

#
#Layer features
#
A 1.7712204 0.4310709 1.6275196 0.4310709 1.69937 0.4310709 4 P 0 N
A 2.2942913 3.9019358 2.2966345 3.8962788 2.3022913 3.9019358 0 P 0 N
A 2.3503937 0.4055118 2.351997 0.4048477 2.351997 0.4071151 1 P 0 N
A 2.3631142 0.4033832 2.3595786 0.4048477 2.3595786 0.3998476 1 P 0 N
A 2.3645787 0.3975695 2.367654 0.3901451 2.3750784 0.3975695 1 P 0 N
A 2.3645787 0.3998476 2.3631142 0.4033832 2.3595786 0.3998476 1 P 0 N
A 2.3755787 0.3998477 2.3770431 0.3963123 2.3805785 0.3998477 1 P 0 N
A 2.3770432 0.403383 2.3755788 0.3998477 2.3805785 0.3998477 1 P 0 N
A 2.380579 0.4048477 2.3770431 0.4033831 2.380579 0.3998472 1 P 0 N
A 2.3881605 0.4048477 2.3897638 0.4055118 2.3881605 0.4071151 1 P 0 N
A 2.3896338 0.3681652 2.4495895 0.3433308 2.4495895 0.4281209 1 P 0 N
A 2.3973016 0.3760536 2.4094488 0.3662328 2.4497454 0.4284974 1 P 0 N
A 2.4094488 0.3662328 2.4119488 0.3646842 2.4497454 0.4284974 1 P 0 N
A 2.4190699 0.3627335 2.4285515 0.369967 2.4210515 0.369967 1 P 0 N
A 2.4251968 0.4367471 2.4717322 0.3902121 2.4717321 0.4367474 1 P 0 N
A 2.4426969 0.4831502 2.4426969 0.4681502 2.4426969 0.4756502 1 P 0 N
A 2.4435515 0.3617492 2.44907 0.3545157 2.4510515 0.3617492 1 P 0 N
A 2.4435515 0.372224 2.4285515 0.372224 2.4360515 0.372224 1 P 0 N
A 2.4448819 0.5056502 2.4523819 0.4981502 2.4523819 0.5056502 1 P 0 N
A 2.444882 0.4237558 2.4467999 0.4196224 2.4501986 0.423711 1 P 0 N
A 2.4523819 0.4531502 2.4448819 0.4456502 2.4523819 0.4456502 1 P 0 N
A 2.4531483 0.4142057 2.4531191 0.4142307 2.4498846 0.4104173 1 P 0 N
A 2.4531646 0.4141917 2.4696367 0.4109015 2.4643476 0.4273002 1 P 0 N
A 2.4567253 0.4831502 2.4567253 0.4981502 2.4567253 0.4906502 1 P 0 N
A 2.4588273 0.4531502 2.4588273 0.4681502 2.4588273 0.4606502 1 P 0 N
A 2.4663545 0.7301341 2.4251968 0.6308028 2.5657178 0.6307707 1 P 0 N
A 2.4741712 0.7223944 2.4448819 0.6516837 2.5448819 0.6516837 1 P 0 N
A 2.4965115 0.3902123 2.511811 0.4055118 2.4965115 0.4055118 1 P 0 N
A 2.5281855 2.6187369 2.5258424 2.61308 2.5338425 2.61308 0 P 0 N
A 2.5354811 0.3433308 2.543177 0.3465186 2.5354811 0.3542145 1 P 0 N
A 2.5521855 2.6151778 2.5498424 2.6095209 2.5578425 2.6095209 0 P 0 N
A 2.5774155 0.3963132 2.6067048 0.4670239 2.5067048 0.4670239 1 P 0 N
A 2.5798424 3.6097971 2.5774717 3.6154416 2.5718422 3.6097571 0 P 0 N
A 2.5852321 0.3885736 2.6177047 0.4669693 2.5068364 0.4669693 1 P 0 N
A 2.6067048 0.7751375 2.5984252 0.7951262 2.5784365 0.7751375 1 P 0 N
A 2.6259843 0.7951259 2.6177049 0.7751376 2.6459728 0.7751376 1 P 0 N
A 2.6649797 2.7555307 2.6673229 2.7611877 2.6593228 2.7611877 0 P 0 N
A 2.6715037 0.3993623 2.735091 0.3923416 2.7076684 0.4354416 1 P 0 N
A 2.6841536 0.9479333 2.6893818 0.9605552 2.6715317 0.9605552 1 P 0 N
A 2.6846648 2.7476567 2.687008 2.7533137 2.6790079 2.7533137 0 P 0 N
A 2.6893819 0.9605552 2.6841537 0.9731772 2.6715317 0.9605552 1 P 0 N
A 2.6935428 0.9417659 2.7003819 0.9582771 2.6770316 0.9582771 1 P 0 N
A 2.7047243 0.4055116 2.7340575 0.4061129 2.7190989 0.4200595 1 P 0 N
A 2.707221 0.974788 2.7003819 0.9582771 2.7237319 0.9582771 1 P 0 N
A 2.7310449 0.5184503 2.7310449 0.5034503 2.7310449 0.5109503 1 P 0 N
A 2.7322151 0.4884503 2.7322151 0.4734503 2.7322151 0.4809503 1 P 0 N
A 2.733062 0.4584503 2.733062 0.4434503 2.733062 0.4509503 1 P 0 N
A 2.733063 0.5184503 2.740563 0.5259503 2.733063 0.5259503 1 P 0 N
A 2.7340575 0.4061129 2.7353582 0.4076537 2.7190989 0.4200595 1 P 0 N
A 2.734063 0.4584503 2.734063 0.4734503 2.734063 0.4659503 1 P 0 N
A 2.734063 0.4884503 2.734063 0.5034503 2.734063 0.4959503 1 P 0 N
A 2.735091 0.3923416 2.7515629 0.4223505 2.7159911 0.4223507 1 P 0 N
A 2.7353742 0.4076749 2.736048 0.4086129 2.7147607 0.423194 1 P 0 N
A 2.740563 0.4359503 2.733063 0.4434503 2.733063 0.4359503 1 P 0 N
A 2.740563 0.7751376 2.7322835 0.7951261 2.712295 0.7751376 1 P 0 N
A 2.7598425 0.7951259 2.7515631 0.7751376 2.779831 0.7751376 1 P 0 N
A 2.8033685 0.4075234 2.8096946 0.3934558 2.8251276 0.4088521 1 P 0 N
A 2.8074922 0.9582771 2.8006531 0.974788 2.7841422 0.9582771 1 P 0 N
A 2.8074922 0.9582771 2.8143313 0.9417659 2.8308425 0.9582771 1 P 0 N
A 2.8097215 0.3934295 2.8405136 0.393003 2.8253402 0.4092878 1 P 0 N
A 2.8119314 0.430042 2.8033666 0.4075566 2.8331009 0.4091045 1 P 0 N
A 2.8184922 0.9605552 2.8237204 0.9479332 2.8363424 0.9605552 1 P 0 N
A 2.8237204 0.9731771 2.8184923 0.9605552 2.8363424 0.9605552 1 P 0 N
A 2.8405136 0.393003 2.8421142 0.3966697 2.8371141 0.3966697 1 P 0 N
A 2.8438426 0.4016785 2.8421142 0.3975056 2.8480156 0.3975056 1 P 0 N
A 2.8474989 0.4369234 2.8368923 0.4369235 2.8421956 0.4316201 1 P 0 N
A 2.8480156 0.4034071 2.8438426 0.4016786 2.8480156 0.3975056 1 P 0 N
A 2.8492495 0.4034071 2.8543307 0.4055118 2.8492495 0.410593 1 P 0 N
A 2.8515207 0.4329018 2.8621272 0.4329017 2.856824 0.4382051 1 P 0 N
A 2.8561371 0.460105 2.8561372 0.4494985 2.8614405 0.4548018 1 P 0 N
A 2.8621272 0.4329017 2.8621272 0.4435083 2.8568239 0.438205 1 P 0 N
A 2.8667437 0.460105 2.8561371 0.460105 2.8614404 0.4548017 1 P 0 N
A 2.8709826 0.4890923 2.8724529 0.4926337 2.8674528 0.4926337 1 P 0 N
A 2.8724528 0.7705345 2.8622047 0.7952756 2.8374636 0.7705345 1 P 0 N
A 2.872734 0.4541149 2.8833405 0.4541148 2.8780373 0.4594182 1 P 0 N
A 2.8793188 0.4793498 2.8793188 0.4687431 2.8846221 0.4740465 1 P 0 N
A 2.8819883 0.482019 2.8819663 0.4819972 2.8855022 0.4784614 1 P 0 N
A 2.8819883 0.482019 2.8834529 0.4855546 2.8784529 0.4855546 1 P 0 N
A 2.8833405 0.4541148 2.8833405 0.4647214 2.8780372 0.4594181 1 P 0 N
A 2.8937008 0.7952755 2.8834529 0.7705347 2.9184417 0.7705347 1 P 0 N
A 2.9251969 0.789479 2.8959076 0.8601896 2.8251969 0.789479 1 P 0 N
A 2.925197 0.4700228 2.9534811 0.3998375 3.0259409 0.46983 1 P 0 N
A 2.9361969 0.8087645 2.9173228 0.8543308 2.8717563 0.8087645 1 P 0 N
A 2.9380196 0.4933436 2.9450738 0.4883909 2.9450738 0.4958909 1 P 0 N
A 2.9452235 0.4733909 2.9452235 0.4583909 2.9452235 0.4658909 1 P 0 N
A 2.953481 0.3998374 2.9536063 0.3997118 2.957083 0.4033057 1 P 0 N
A 2.9539854 0.399345 2.9544564 0.3990509 2.982837 0.4450253 1 P 0 N
A 2.9544564 0.3990509 2.9740968 0.3917082 2.982837 0.4450253 1 P 0 N
A 2.9551168 0.4733909 2.9551168 0.4883909 2.9551168 0.4808909 1 P 0 N
A 2.9667398 0.4433909 2.9596857 0.4333435 2.9667398 0.4358909 1 P 0 N
A 2.9667408 0.4433909 2.9667408 0.4583909 2.9667408 0.4508909 1 P 0 N
A 2.9748134 0.3915357 2.9740968 0.3917083 2.973288 0.3867737 1 P 0 N
A 2.9748134 0.3915357 2.9837232 0.3909445 2.980457 0.4091539 1 P 0 N
A 2.975631 0.4123601 2.979314 0.4098601 3.0155239 0.4671675 1 P 0 N
A 2.979314 0.4098601 2.9804568 0.4091538 3.0155239 0.4671675 1 P 0 N
A 2.9844564 0.3910209 3.0196848 0.4055115 2.982837 0.4450253 1 P 0 N
A 2.9844564 0.391021 2.9837232 0.3909446 2.9846063 0.3860228 1 P 0 N
L -0.0001175 0.177913 0.5908825 0.177913 5 P 0
L -0.0004331 0.1781182 0.5901181 0.1781182 4 P 0
L 0.5901181 0.1781182 0.5901181 0.5029213 4 P 0
L 0.5901181 0.5029213 1.312559 0.5029213 4 P 0
L 0.5908825 0.177913 0.5908825 0.502913 5 P 0
L 0.9901575 0.6870079 1.2175197 0.6870079 0 P 0
L 1.2175197 0.6870079 1.363189 0.8326772 0 P 0
L 1.312559 0.313945 1.312559 0.5029213 4 P 0
L 1.312559 0.313945 1.6275197 0.313945 4 P 0
L 1.3454724 4.1751969 1.3454724 4.2667323 0 P 0
L 1.3454724 4.2667323 1.3937007 4.3149606 0 P 0
L 1.363189 0.8326772 1.363189 1.7864173 0 P 0
L 1.363189 1.7864173 1.3937008 1.8169291 0 P 0
L 1.3808425 3.617063 1.3808425 4.202063 0 P 0
L 1.3808425 3.617063 1.4408425 3.557063 0 P 0
L 1.3808425 4.202063 1.4388425 4.260063 0 P 0
L 1.3937007 4.3149606 1.5866142 4.3149606 0 P 0
L 1.4598425 3.147063 1.4598425 3.4637795 0 P 0
L 1.4598425 3.4637795 1.4783464 3.4822834 0 P 0
L 1.4783464 3.4822834 1.4783464 3.8928483 0 P 0
L 1.4783464 3.8928483 1.6318897 4.0463916 0 P 0
L 1.5498424 2.4652788 1.5498424 3.6210629 0 P 0
L 1.5498424 2.4652788 1.5498425 2.4652787 0 P 0
L 1.5498424 3.6210629 1.5498425 3.621063 0 P 0
L 1.5498425 2.4078367 1.5498425 2.4652787 0 P 0
L 1.5498425 2.4078367 1.5682025 2.3894767 0 P 0
L 1.5682025 2.067703 1.5682025 2.3894767 0 P 0
L 1.5748425 2.4202363 1.5748425 3.596063 0 P 0
L 1.5748425 2.4202363 1.6198425 2.3752363 0 P 0
L 1.5866142 4.3149606 1.625 4.2765748 0 P 0
L 1.6198425 2.121063 1.6198425 2.3752363 0 P 0
L 1.625 4.2765748 1.8818897 4.2765748 0 P 0
L 1.6275197 0.313945 1.6275197 0.4310709 4 P 0
L 1.6318897 4.0463916 1.6318897 4.1998032 0 P 0
L 1.6318897 4.1998032 1.6811023 4.2490158 0 P 0
L 1.6811023 4.2490158 1.8366141 4.2490158 0 P 0
L 1.7198425 1.536063 1.7798425 1.596063 0 P 0
L 1.7548425 2.126063 1.7548425 3.661063 0 P 0
L 1.7798425 1.596063 1.7798425 4.156063 0 P 0
L 1.8366141 4.2490158 1.9251968 4.1604331 0 P 0
L 1.8498425 0.271063 1.8498425 3.701063 2 P 0
L 1.8818897 4.2765748 1.9517716 4.2066929 0 P 0
L 1.8848425 2.071063 1.8848425 3.601063 0 P 0
L 1.9251968 4.160433 1.9251968 4.1604331 0 P 0
L 1.9251968 4.160433 1.9793306 4.1062992 0 P 0
L 1.9517716 4.2066929 2.1437008 4.2066929 0 P 0
L 1.9793306 4.1062992 2.143558 4.1062992 0 P 0
L 2.0048425 1.336063 2.0048425 3.816063 0 P 0
L 2.0288425 1.361663 2.0298425 1.362663 0 P 0
L 2.0298425 1.362663 2.0298425 3.836063 0 P 0
L 2.0433071 4.257874 2.1633858 4.257874 0 P 0
L 2.0598425 1.386063 2.0598425 3.871063 0 P 0
L 2.0838425 1.411663 2.0843425 1.412163 3 P 0
L 2.0843425 1.412163 2.0843425 3.895563 3 P 0
L 2.0843425 3.895563 2.0848425 3.896063 3 P 0
L 2.143558 4.1062992 2.1460663 4.1037909 0 P 0
L 2.1437008 4.2066929 2.2058425 4.1445512 0 P 0
L 2.1633858 4.257874 2.2942913 4.1269685 0 P 0
L 2.2058425 1.299063 2.2058425 2.4089566 0 P 0
L 2.2058425 1.299063 2.2068425 1.298063 0 P 0
L 2.2058425 2.4089566 2.2259625 2.4290766 0 P 0
L 2.2058425 2.4681094 2.2058425 3.200063 0 P 0
L 2.2058425 2.4681094 2.2259625 2.4479894 0 P 0
L 2.2058425 3.200063 2.2058425 4.1445512 0 P 0
L 2.2259625 2.4290766 2.2259625 2.4479894 0 P 0
L 2.2298425 2.586063 2.2298425 3.4988982 0 P 0
L 2.2298425 3.4988982 2.2348425 3.5038982 0 P 0
L 2.2348425 3.5038982 2.2348425 3.506063 0 P 0
L 2.2523425 2.613563 2.2598425 2.621063 0 P 0
L 2.253937 3.8474409 2.253937 4.0866142 0 P 0
L 2.253937 3.8474409 2.4793307 3.6220472 0 P 0
L 2.2548425 3.536063 2.2998425 3.491063 0 P 0
L 2.2598425 2.621063 2.2598425 3.261063 0 P 0
L 2.2720325 2.2891572 2.2720325 2.463873 0 P 0
L 2.2720325 2.2891572 2.2748425 2.2863472 0 P 0
L 2.2748425 1.506063 2.2748425 2.2863472 0 P 0
L 2.2942913 3.9019358 2.2942913 4.1269685 0 P 0
L 2.2966345 3.8962788 2.5774718 3.6154415 0 P 0
L 2.2998424 1.916063 2.2998425 3.491063 0 P 0
L 2.3415354 2.4470859 2.3415354 3.4305911 0 P 0
L 2.3415354 2.4470859 2.3898425 2.3987788 0 P 0
L 2.3415354 3.4305911 2.3898425 3.4788982 0 P 0
L 2.351997 0.4048477 2.3595786 0.4048477 1 P 0
L 2.3622047 2.6880508 2.3622047 3.2989023 0 P 0
L 2.3622047 2.6880508 2.4291925 2.621063 0 P 0
L 2.3622047 3.2989023 2.4594558 3.3961534 0 P 0
L 2.3645787 0.3975695 2.3645787 0.3998476 1 P 0
L 2.367654 0.3901451 2.3896338 0.3681653 1 P 0
L 2.3755787 0.3998477 2.3755788 0.3998477 1 P 0
L 2.3770431 0.3963123 2.3973017 0.3760537 1 P 0
L 2.380579 0.4048477 2.3881605 0.4048477 1 P 0
L 2.3848425 1.941063 2.3848425 1.9432278 0 P 0
L 2.3848425 1.9432278 2.3898425 1.9482278 0 P 0
L 2.3858268 3.019685 2.3858268 3.2982284 0 P 0
L 2.3858268 3.019685 2.3864999 3.0190119 0 P 0
L 2.3858268 3.2982284 2.4793307 3.3917323 0 P 0
L 2.3864999 2.7694056 2.3864999 3.0190119 0 P 0
L 2.3864999 2.7694056 2.4948425 2.661063 0 P 0
L 2.3898425 1.9482278 2.3898425 2.3987788 0 P 0
L 2.3898425 3.4788982 2.3898425 3.481063 0 P 0
L 2.4098425 1.967063 2.4098425 2.283063 0 P 0
L 2.4119488 0.3646842 2.41907 0.3627335 1 P 0
L 2.4190699 0.3627334 2.41907 0.3627335 1 P 0
L 2.4251968 0.6308028 2.4251969 0.4367472 1 P 0
L 2.4285515 0.369967 2.4285515 0.372224 1 P 0
L 2.4348425 3.546063 2.4594558 3.5214497 0 P 0
L 2.4426969 0.4681502 2.4588273 0.4681502 1 P 0
L 2.4426969 0.4831502 2.4567253 0.4831502 1 P 0
L 2.4435515 0.3617492 2.4435515 0.372224 1 P 0
L 2.4448819 0.4237558 2.4448819 0.4281497 1 P 0
L 2.4448819 0.4281497 2.4448819 0.4456502 1 P 0
L 2.4448819 0.5056502 2.4448819 0.5620079 1 P 0
L 2.4448819 0.5620079 2.4448819 0.6516837 1 P 0
L 2.4467998 0.4196223 2.4531191 0.4142306 1 P 0
L 2.4468425 1.437063 2.4468425 2.2758982 0 P 0
L 2.4468425 2.2758982 2.4508425 2.2798982 0 P 0
L 2.44907 0.3545156 2.4490701 0.3545157 1 P 0
L 2.4490701 0.3545157 2.4497454 0.3543307 1 P 0
L 2.4495895 0.3433308 2.5354811 0.3433308 1 P 0
L 2.4497454 0.3543307 2.4606299 0.3543308 1 P 0
L 2.4508425 2.2798982 2.4508425 2.282063 0 P 0
L 2.4523819 0.4531502 2.4588273 0.4531502 1 P 0
L 2.4523819 0.4981502 2.4567253 0.4981502 1 P 0
L 2.4531483 0.4142057 2.4531647 0.4141918 1 P 0
L 2.4594558 3.3961534 2.4594558 3.5214497 0 P 0
L 2.4606299 0.3543308 2.468552 0.3543308 1 P 0
L 2.462374 3.1722441 2.6535433 2.9810748 0 P 0
L 2.4663546 0.7301341 2.466393 0.7301725 1 P 0
L 2.466393 0.7301725 2.4763779 0.7401574 1 P 0
L 2.468552 0.3543308 2.5354331 0.3543308 1 P 0
L 2.4696367 0.4109016 2.469871 0.4109766 1 P 0
L 2.469871 0.4109766 2.4698827 0.4109883 1 P 0
L 2.4717322 0.3902122 2.4782363 0.3902122 1 P 0
L 2.4741712 0.7223944 2.4841561 0.7323793 1 P 0
L 2.4758425 2.291063 2.4788425 2.288063 0 P 0
L 2.4763779 0.7401574 2.6841537 0.9479332 1 P 0
L 2.4782363 0.3902122 2.478281 0.3902123 1 P 0
L 2.478281 0.3902123 2.4965115 0.3902123 1 P 0
L 2.4788425 0.937063 2.4788425 2.288063 0 P 0
L 2.4793307 3.3917323 2.4793307 3.6220472 0 P 0
L 2.4841561 0.7323793 2.6935428 0.941766 1 P 0
L 2.5028425 1.316063 2.5028425 2.2107788 0 P 0
L 2.5028425 2.2107788 2.5198425 2.2277788 0 P 0
L 2.5058425 2.4427789 2.5058425 2.6200157 0 P 0
L 2.5058425 2.4427789 2.5198425 2.4287789 0 P 0
L 2.5058425 2.6200157 2.6535433 2.7677165 0 P 0
L 2.5198425 2.2277788 2.5198425 2.4287789 0 P 0
L 2.5258424 2.61308 2.5258425 2.61308 0 P 0
L 2.5258425 2.463063 2.5258425 2.61308 0 P 0
L 2.5278425 3.2949922 2.5278425 3.434063 0 P 0
L 2.5278425 3.2949922 2.6673228 3.1555119 0 P 0
L 2.5278425 3.434063 2.5798425 3.486063 0 P 0
L 2.5281855 2.6187369 2.6649797 2.7555307 0 P 0
L 2.5354331 0.3543308 2.5774155 0.3963132 1 P 0
L 2.5431771 0.3465185 2.5852321 0.3885735 1 P 0
L 2.5498424 2.6095209 2.5498425 2.6095209 0 P 0
L 2.5498425 1.755063 2.5498425 2.6095209 0 P 0
L 2.5521855 2.6151778 2.6846648 2.7476567 0 P 0
L 2.5798423 3.6097971 2.5798425 3.6097572 0 P 0
L 2.5798425 1.790063 2.5798425 2.281063 0 P 0
L 2.5798425 3.486063 2.5798425 3.6097572 0 P 0
L 2.5984252 0.7951262 2.5984252 0.7952756 1 P 0
L 2.6048425 1.734063 2.6048425 2.4313767 0 P 0
L 2.6067048 0.4670239 2.6067048 0.7751375 1 P 0
L 2.6177048 0.4669693 2.6177048 0.7751376 1 P 0
L 2.6248425 1.7777198 2.6248425 2.461063 0 P 0
L 2.6248425 1.7777198 2.6253118 1.7772505 0 P 0
L 2.6253118 1.7715937 2.6253118 1.7772505 0 P 0
L 2.6253118 1.7715937 2.6268425 1.770063 0 P 0
L 2.6259843 0.7951259 2.6259843 0.7951261 1 P 0
L 2.6259843 0.7951261 2.6259843 0.7952756 1 P 0
L 2.6259843 0.7951261 2.6259844 0.795126 1 P 0
L 2.6348425 3.406063 2.6870079 3.3538976 0 P 0
L 2.6387795 2.5305119 2.6387795 2.6673228 0 P 0
L 2.6387795 2.5305119 2.6653543 2.5039371 0 P 0
L 2.6387795 2.6673228 2.6929134 2.7214567 0 P 0
L 2.6438425 1.616063 2.6438425 1.711063 0 P 0
L 2.6438425 1.711063 2.6488425 1.716063 0 P 0
L 2.6458425 2.274063 2.6458425 2.3791103 0 P 0
L 2.6458425 2.274063 2.6473732 2.2725323 0 P 0
L 2.6458425 2.3791103 2.6653543 2.3986221 0 P 0
L 2.6473732 2.2668755 2.6473732 2.2725323 0 P 0
L 2.6473732 2.2668755 2.6488425 2.2654062 0 P 0
L 2.6488425 1.716063 2.6488425 2.2654062 0 P 0
L 2.6535433 2.7677165 2.6535433 2.9810748 0 P 0
L 2.6653543 0.4055118 2.6715037 0.3993623 1 P 0
L 2.6653543 2.3986221 2.6653543 2.5039371 0 P 0
L 2.6658425 1.641063 2.6658425 2.291063 0 P 0
L 2.6658425 1.641063 2.6668425 1.640063 0 P 0
L 2.6673228 2.7611877 2.6673228 3.1555119 0 P 0
L 2.6715036 0.3993622 2.6715037 0.3993623 1 P 0
L 2.6811024 0.9762285 2.6811024 0.976378 1 P 0
L 2.6811024 0.9762285 2.6841537 0.9731772 1 P 0
L 2.6870079 2.7533137 2.6870079 3.3538976 0 P 0
L 2.6893818 0.9605552 2.6893819 0.9605552 1 P 0
L 2.6948425 1.481063 2.6948425 2.2843767 0 P 0
L 2.6948425 2.2843767 2.7028425 2.2923767 0 P 0
L 2.7028425 2.2923767 2.7028425 2.293063 0 P 0
L 2.7047243 0.4055116 2.7047244 0.4055118 1 P 0
L 2.707221 0.9747881 2.7086614 0.9762285 1 P 0
L 2.7086614 0.9762285 2.7086614 0.976378 1 P 0
L 2.7198425 1.591063 2.7198425 1.5927493 0 P 0
L 2.7198425 1.5927493 2.7268425 1.5997493 0 P 0
L 2.7268425 1.5997493 2.7268425 2.293063 0 P 0
L 2.7310449 0.5034503 2.734063 0.5034503 1 P 0
L 2.7310449 0.5184503 2.733063 0.5184503 1 P 0
L 2.7322151 0.4734503 2.734063 0.4734503 1 P 0
L 2.7322151 0.4884503 2.734063 0.4884503 1 P 0
L 2.7322835 0.7951261 2.7322835 0.7952756 1 P 0
L 2.733062 0.4434503 2.733063 0.4434503 1 P 0
L 2.733062 0.4584503 2.734063 0.4584503 1 P 0
L 2.7353582 0.4076537 2.7353742 0.4076749 1 P 0
L 2.736048 0.4086129 2.740563 0.423194 1 P 0
L 2.740563 0.423194 2.740563 0.4359503 1 P 0
L 2.740563 0.5259503 2.740563 0.5434508 1 P 0
L 2.740563 0.5434508 2.740563 0.7751376 1 P 0
L 2.7515629 0.4223505 2.751563 0.4223953 1 P 0
L 2.751563 0.4223953 2.751563 0.7751376 1 P 0
L 2.7598425 0.7951259 2.7598425 0.7951261 1 P 0
L 2.7598425 0.7951261 2.7598425 0.7952756 1 P 0
L 2.7992126 0.9762286 2.7992126 0.976378 1 P 0
L 2.7992126 0.9762286 2.8006531 0.9747881 1 P 0
L 2.8033665 0.4075566 2.8033685 0.4075234 1 P 0
L 2.8096947 0.3934559 2.8097215 0.3934295 1 P 0
L 2.8119314 0.430042 2.8119537 0.4300643 1 P 0
L 2.8119537 0.4300643 2.8709826 0.4890923 1 P 0
L 2.8143313 0.941766 2.8959076 0.8601897 1 P 0
L 2.8163193 0.4121203 2.8166357 0.4113091 1 P 0
L 2.8163193 0.4121203 2.8174418 0.4174731 1 P 0
L 2.8166357 0.4113091 2.8185055 0.4065166 1 P 0
L 2.8174418 0.4174731 2.8368923 0.4369235 1 P 0
L 2.8185055 0.4065166 2.8197456 0.4077567 1 P 0
L 2.8197456 0.4077567 2.8216839 0.4077567 1 P 0
L 2.8216839 0.4077567 2.8217791 0.4078519 1 P 0
L 2.8217791 0.4078519 2.8219832 0.4078519 1 P 0
L 2.8237204 0.9479332 2.9173228 0.8543308 1 P 0
L 2.8237204 0.9731772 2.8267717 0.9762285 1 P 0
L 2.8267717 0.9762285 2.8267717 0.976378 1 P 0
L 2.8421141 0.3966697 2.8421141 0.3975056 1 P 0
L 2.8474989 0.4369234 2.8515206 0.4329017 1 P 0
L 2.8480156 0.4034071 2.8492495 0.4034071 1 P 0
L 2.8561371 0.4494984 2.8621272 0.4435083 1 P 0
L 2.8667437 0.460105 2.8727339 0.4541148 1 P 0
L 2.8724528 0.4926337 2.8724528 0.7705345 1 P 0
L 2.8793188 0.4687431 2.8833405 0.4647214 1 P 0
L 2.8793188 0.4793498 2.8793191 0.4793501 1 P 0
L 2.8793191 0.4793501 2.8810868 0.4811178 1 P 0
L 2.8810868 0.4811178 2.8810869 0.4811179 1 P 0
L 2.8810868 0.4811178 2.8819663 0.4819972 1 P 0
L 2.8834528 0.5091763 2.8834528 0.7705347 1 P 0
L 2.8834529 0.4855546 2.8834529 0.5091763 1 P 0
L 2.8937008 0.7952756 2.8937009 0.7952755 1 P 0
L 2.8948425 1.561063 2.8948425 2.431063 0 P 0
L 2.9198425 1.536063 2.9208425 1.537063 0 P 0
L 2.9208425 1.537063 2.9208425 2.428063 0 P 0
L 2.9251969 0.4700228 2.9251969 0.789479 1 P 0
L 2.9361969 0.4983914 2.9361969 0.8087645 1 P 0
L 2.9361969 0.4983914 2.9370996 0.4958914 1 P 0
L 2.9370996 0.4958914 2.9380196 0.4933437 1 P 0
L 2.9380195 0.4933436 2.9380196 0.4933437 1 P 0
L 2.9428425 2.286063 2.9555625 2.286063 0 P 0
L 2.9450738 0.4883909 2.9551168 0.4883909 1 P 0
L 2.9452235 0.4583909 2.9667408 0.4583909 1 P 0
L 2.9452235 0.4733909 2.9551168 0.4733909 1 P 0
L 2.9534809 0.3998373 2.953481 0.3998374 1 P 0
L 2.9536062 0.3997117 2.9539854 0.399345 1 P 0
L 2.9555625 2.286063 2.9677025 2.298203 0 P 0
L 2.9596856 0.4333435 2.9596857 0.4333436 1 P 0
L 2.9596857 0.4333436 2.9629045 0.4244298 1 P 0
L 2.9629045 0.4244298 2.975631 0.4123601 1 P 0
L 2.9667398 0.4433909 2.9667408 0.4433909 1 P 0
L 2.9677025 2.298203 2.9677025 2.4479894 0 P 0
L 2.9677025 2.4479894 2.9798425 2.4601294 0 P 0
L 2.9798425 2.4601294 2.9798425 2.971631 0 P 0
L 2.9798425 2.971631 2.9933858 2.9851743 0 P 0
L 2.9804567 0.4091537 2.980457 0.4091539 1 P 0
L 2.9837232 0.3909445 2.9837232 0.3909446 1 P 0
L 2.9844564 0.3910208 2.9844564 0.3910209 1 P 0
L 2.9858425 2.287063 3.0133625 2.314583 0 P 0
L 2.9933858 2.9851743 2.9933858 3.751063 0 P 0
L 2.9988425 2.6183076 2.9988425 2.9722463 0 P 0
L 2.9988425 2.6183076 3.0133625 2.6037876 0 P 0
L 2.9988425 2.9722463 3.0218425 2.9952463 0 P 0
L 3.0133625 2.314583 3.0133625 2.6037876 0 P 0
L 3.0148425 3.8288982 3.0148425 3.831063 0 P 0
L 3.0148425 3.8288982 3.0218425 3.8218982 0 P 0
L 3.0218425 2.9952463 3.0218425 3.8218982 0 P 0
L 3.0568817 1.811803 3.0568817 2.2261731 0 P 0
L 3.0568817 2.2261731 3.0728346 2.242126 0 P 0
L 3.0649606 3.3996063 3.0688976 3.3956693 0 P 0
L 3.0688976 3.3956693 3.0728346 3.3917323 0 P 0
L 3.0728346 2.242126 3.0728346 3.3917323 0 P 0
L 3.1972633 1.714063 3.1972633 2.9694838 0 P 0
L 3.1972633 2.9694838 3.1978425 2.970063 0 P 0
L 3.2248425 1.6613472 3.2248425 3.229063 0 P 0
L 3.2248425 3.229063 3.2308425 3.235063 0 P 0
L 3.2528425 1.661063 3.2528425 3.293063 0 P 0
L 3.2528425 3.293063 3.2636972 3.3039177 0 P 0
L 3.2988425 1.971063 3.2988425 1.9732278 0 P 0
L 3.2988425 1.9732278 3.3028425 1.9772278 0 P 0
L 3.3028425 1.9772278 3.3028425 3.344063 0 P 0
L 3.3248425 1.941063 3.3291721 1.9367334 0 P 0
L 3.3248425 1.941063 3.3948425 2.011063 0 P 0
L 3.3291721 1.826063 3.3291721 1.9367334 0 P 0
L 3.3428425 2.263063 3.3448425 2.265063 0 P 0
L 3.3448425 2.265063 3.3448425 2.996063 0 P 0
L 3.3448425 2.996063 3.3448425 3.2867788 0 P 0
L 3.3448425 3.2867788 3.3588425 3.3007788 0 P 0
L 3.3588425 3.3007788 3.3588425 3.448063 0 P 0
L 3.3688425 3.050063 3.3688425 3.2648982 0 P 0
L 3.3688425 3.2648982 3.3748425 3.2708982 0 P 0
L 3.3748425 3.2708982 3.3748425 3.273063 0 P 0
L 3.3928425 1.871063 3.3928425 1.949063 0 P 0
L 3.3928425 1.949063 3.4398425 1.996063 0 P 0
L 3.3948425 2.011063 3.3948425 3.447063 0 P 0
L 3.4368425 1.999063 3.4368425 3.457063 0 P 0
L 3.4368425 1.999063 3.4398425 1.996063 0 P 0
L 3.4389125 1.875133 3.4392507 1.8747948 0 P 0
L 3.4389125 1.875133 3.4698425 1.906063 0 P 0
L 3.4392507 1.870938 3.4392507 1.8747948 0 P 0
L 3.4698425 1.906063 3.4698425 3.456063 0 P 0
L 3.4918425 3.297063 3.4928425 3.296063 0 P 0
L 3.4928425 2.357063 3.4928425 3.296063 0 P 0
L 3.4928425 2.357063 3.5018425 2.348063 0 P 0
L 3.4978425 2.344063 3.4998425 2.342063 0 P 0
L 3.4978425 2.344063 3.5018425 2.348063 0 P 0
L 3.4988425 2.341063 3.4998425 2.342063 0 P 0
L 3.5048425 4.086063 3.5198425 4.071063 0 P 0
L 3.5098425 3.3237788 3.5098425 3.7669208 0 P 0
L 3.5098425 3.3237788 3.523622 3.3099993 0 P 0
L 3.5098425 3.7669208 3.5198425 3.7769208 0 P 0
L 3.5198425 3.7769208 3.5198425 4.071063 0 P 0
L 3.523622 1.4672835 3.523622 3.3099993 0 P 0
L 3.523622 1.4672835 3.5498425 1.441063 0 P 0
L 3.542865 2.4157965 3.542865 3.3190405 0 P 0
L 3.542865 2.4157965 3.6048425 2.353819 0 P 0
L 3.5898425 1.711063 3.6138425 1.735063 0 P 0
L 3.6048425 2.0900041 3.6048425 2.353819 0 P 0
L 3.6048425 2.0900041 3.6138425 2.0810041 0 P 0
L 3.6138425 1.735063 3.6138425 2.0810041 0 P 0
L 3.6228425 2.588063 3.6228425 3.486063 0 P 0
L 3.6228425 2.588063 3.6238425 2.587063 0 P 0
L 3.6538425 3.293063 3.6958661 3.2510394 0 P 0
L 3.6958661 1.7000394 3.6958661 3.2510394 0 P 0
L 3.6958661 1.7000394 3.7208425 1.675063 0 P 0
L 3.7208425 1.675063 3.7248425 1.675063 0 P 0
L 3.7448425 1.711063 3.7448425 3.261063 0 P 0
L 3.7448425 1.711063 3.7748425 1.681063 0 P 0
L 3.7698425 1.726063 3.7698425 3.215063 0 P 0
L 3.7698425 1.726063 3.8038425 1.692063 0 P 0
L 3.7698425 3.215063 3.7898425 3.235063 0 P 0
L 3.7738632 1.6661021 3.7748425 1.6670814 0 P 0
L 3.7748425 1.6670814 3.7748425 1.681063 0 P 0
L 3.7898425 3.235063 3.8068425 3.235063 0 P 0
L 3.7998425 2.3563981 3.7998425 3.201063 0 P 0
L 3.7998425 2.3563981 3.8348425 2.3213981 0 P 0
L 3.8038425 1.691063 3.8038425 1.692063 0 P 0
L 3.8243425 2.3618981 3.8243425 2.8680238 0 P 0
L 3.8243425 2.3618981 3.8648425 2.3213981 0 P 0
L 3.8243425 2.8680238 3.8298425 2.8735238 0 P 0
L 3.8298425 2.8735238 3.8298425 3.176063 0 P 0
L 3.8348425 1.481063 3.8348425 2.3213981 0 P 0
L 3.8403425 2.3685255 3.8403425 2.8613964 0 P 0
L 3.8403425 2.3685255 3.8948425 2.3140255 0 P 0
L 3.8403425 2.8613964 3.8548425 2.8758964 0 P 0
L 3.8548425 2.8758964 3.8548425 3.151063 0 P 0
L 3.8648425 1.511063 3.8648425 2.3213981 0 P 0
L 3.8948425 1.566063 3.8948425 2.3140255 0 P 0
L 3.9208425 1.6851984 3.9208425 3.102063 0 P 0
L 3.9208425 1.6851984 3.9248425 1.6811984 0 P 0
L 3.9208425 3.102063 3.9398425 3.121063 0 P 0
L 3.9248425 1.536063 3.9248425 1.6811984 0 P 0
L 4.0398425 2.406063 4.0624044 2.4286249 0 P 0
L 4.0624044 2.4286249 4.0624044 2.595343 0 P 0
L 4.3277559 2.3074803 4.5348425 2.1003937 0 P 0
L 4.5348425 2.1003937 5.6348425 2.1003937 0 P 0
L 5.5778425 2.214063 5.5781524 2.2143729 0 P 0
L 5.5778425 2.214063 5.5800073 2.214063 0 P 0
L 5.5781524 0.8906186 5.6348425 0.9473087 0 P 0
L 5.5781524 2.2143729 5.5781524 2.4890438 0 P 0
L 5.5800073 2.214063 5.5844482 2.2185039 0 P 0
L 5.5844482 2.2185039 5.5866142 2.2185039 0 P 0
L 5.6348425 0.9473087 5.6348425 2.1003937 0 P 0
L 5.6348425 2.1003937 5.6348425 2.236063 0 P 0
P 1.4576771 4.253937 8 P 0 0 ;0=2,1=0
P 2.0433071 4.257874 8 P 0 0 ;0=2,1=0
P 4.0624044 2.595343 7 P 0 0 ;0=1,1=0
P 4.3277559 2.3074803 6 P 0 0 ;0=0,1=0
P 5.5781524 0.8906186 7 P 0 0 ;0=1,1=0
P 5.5781524 2.4890438 7 P 0 0 ;0=1,1=0
P 0.9901575 0.6870079 9 P 0 0 ;0=3,1=1
P 1.3454724 4.1751969 9 P 0 0 ;0=3,1=1
P 1.3937008 1.8169291 9 P 0 0 ;0=3,1=1
P 1.4408425 3.557063 9 P 0 0 ;0=3,1=1
P 1.4598425 3.147063 9 P 0 0 ;0=3,1=1
P 1.5498425 3.621063 9 P 0 0 ;0=3,1=1
P 1.5682025 2.067703 9 P 0 0 ;0=3,1=1
P 1.5748425 3.596063 9 P 0 0 ;0=3,1=1
P 1.6198425 2.121063 9 P 0 0 ;0=3,1=1
P 1.7198425 1.536063 9 P 0 0 ;0=3,1=1
P 1.7548425 2.126063 9 P 0 0 ;0=3,1=1
P 1.7548425 3.661063 9 P 0 0 ;0=3,1=1
P 1.7798425 4.156063 9 P 0 0 ;0=3,1=1
P 1.8326771 0.2874016 9 P 0 0 ;0=3,1=1
P 1.8498425 3.701063 9 P 0 0 ;0=3,1=1
P 1.8523622 0.2559055 9 P 0 0 ;0=3,1=1
P 1.8523622 0.2874016 9 P 0 0 ;0=3,1=1
P 1.8848425 2.071063 9 P 0 0 ;0=3,1=1
P 1.8848425 3.601063 9 P 0 0 ;0=3,1=1
P 2.0048425 1.336063 9 P 0 0 ;0=3,1=1
P 2.0048425 3.816063 9 P 0 0 ;0=3,1=1
P 2.0288425 1.361663 9 P 0 0 ;0=3,1=1
P 2.0298425 3.836063 9 P 0 0 ;0=3,1=1
P 2.0598425 1.386063 9 P 0 0 ;0=3,1=1
P 2.0598425 3.871063 9 P 0 0 ;0=3,1=1
P 2.0838425 1.411663 9 P 0 0 ;0=3,1=1
P 2.0848425 3.896063 9 P 0 0 ;0=3,1=1
P 2.1460663 4.1037909 9 P 0 0 ;0=3,1=1
P 2.2058425 3.200063 9 P 0 0 ;0=3,1=1
P 2.2068425 1.298063 9 P 0 0 ;0=3,1=1
P 2.2317425 2.584163 9 P 0 0 ;0=3,1=1
P 2.2348425 3.506063 9 P 0 0 ;0=3,1=1
P 2.2523425 2.613563 9 P 0 0 ;0=3,1=1
P 2.253937 4.0866142 9 P 0 0 ;0=3,1=1
P 2.2548425 3.536063 9 P 0 0 ;0=3,1=1
P 2.2598425 3.261063 9 P 0 0 ;0=3,1=1
P 2.2720325 2.463873 9 P 0 0 ;0=3,1=1
P 2.2748425 1.506063 9 P 0 0 ;0=3,1=1
P 2.2998425 1.916063 9 P 0 0 ;0=3,1=1
P 2.3503937 0.4055118 9 P 0 0 ;0=3,1=1
P 2.3848425 1.941063 9 P 0 0 ;0=3,1=1
P 2.3897638 0.4055118 9 P 0 0 ;0=3,1=1
P 2.3898425 3.481063 9 P 0 0 ;0=3,1=1
P 2.4098425 1.967063 9 P 0 0 ;0=3,1=1
P 2.4098425 2.283063 9 P 0 0 ;0=3,1=1
P 2.4291925 2.621063 9 P 0 0 ;0=3,1=1
P 2.4348425 3.546063 9 P 0 0 ;0=3,1=1
P 2.4468425 1.437063 9 P 0 0 ;0=3,1=1
P 2.4508425 2.282063 9 P 0 0 ;0=3,1=1
P 2.462374 3.1722441 9 P 0 0 ;0=3,1=1
P 2.4698827 0.4109883 9 P 0 0 ;0=3,1=1
P 2.4758425 2.291063 9 P 0 0 ;0=3,1=1
P 2.4788425 0.937063 9 P 0 0 ;0=3,1=1
P 2.4948425 2.661063 9 P 0 0 ;0=3,1=1
P 2.5028425 1.316063 9 P 0 0 ;0=3,1=1
P 2.511811 0.4055118 9 P 0 0 ;0=3,1=1
P 2.5258425 2.463063 9 P 0 0 ;0=3,1=1
P 2.5498425 1.755063 9 P 0 0 ;0=3,1=1
P 2.5798425 1.790063 9 P 0 0 ;0=3,1=1
P 2.5798425 2.281063 9 P 0 0 ;0=3,1=1
P 2.5798425 3.486063 9 P 0 0 ;0=3,1=1
P 2.5984252 0.7952756 9 P 0 0 ;0=3,1=1
P 2.5998425 2.436063 9 P 0 0 ;0=3,1=1
P 2.6048425 1.734063 9 P 0 0 ;0=3,1=1
P 2.6248425 2.461063 9 P 0 0 ;0=3,1=1
P 2.6259843 0.7952756 9 P 0 0 ;0=3,1=1
P 2.6268425 1.770063 9 P 0 0 ;0=3,1=1
P 2.6348425 3.406063 9 P 0 0 ;0=3,1=1
P 2.6438425 1.616063 9 P 0 0 ;0=3,1=1
P 2.6458425 2.274063 9 P 0 0 ;0=3,1=1
P 2.6653543 0.4055118 9 P 0 0 ;0=3,1=1
P 2.6658425 2.291063 9 P 0 0 ;0=3,1=1
P 2.6668425 1.640063 9 P 0 0 ;0=3,1=1
P 2.6811024 0.976378 9 P 0 0 ;0=3,1=1
P 2.6929134 2.7214567 9 P 0 0 ;0=3,1=1
P 2.6948425 1.481063 9 P 0 0 ;0=3,1=1
P 2.7028425 2.289063 9 P 0 0 ;0=3,1=1
P 2.7047244 0.4055118 9 P 0 0 ;0=3,1=1
P 2.7086614 0.976378 9 P 0 0 ;0=3,1=1
P 2.7198425 1.591063 9 P 0 0 ;0=3,1=1
P 2.7268425 2.293063 9 P 0 0 ;0=3,1=1
P 2.7322835 0.7952756 9 P 0 0 ;0=3,1=1
P 2.7598425 0.7952756 9 P 0 0 ;0=3,1=1
P 2.7992126 0.976378 9 P 0 0 ;0=3,1=1
P 2.8219832 0.4078519 9 P 0 0 ;0=3,1=1
P 2.8267717 0.976378 9 P 0 0 ;0=3,1=1
P 2.8543307 0.4055118 9 P 0 0 ;0=3,1=1
P 2.8622047 0.7952756 9 P 0 0 ;0=3,1=1
P 2.8937008 0.7952756 9 P 0 0 ;0=3,1=1
P 2.8948425 1.561063 9 P 0 0 ;0=3,1=1
P 2.8948425 2.431063 9 P 0 0 ;0=3,1=1
P 2.9198425 1.536063 9 P 0 0 ;0=3,1=1
P 2.9208425 2.428063 9 P 0 0 ;0=3,1=1
P 2.9428425 2.286063 9 P 0 0 ;0=3,1=1
P 2.980457 0.4091539 9 P 0 0 ;0=3,1=1
P 2.9858425 2.287063 9 P 0 0 ;0=3,1=1
P 2.9933858 3.751063 9 P 0 0 ;0=3,1=1
P 3.0148425 3.831063 9 P 0 0 ;0=3,1=1
P 3.019685 0.4055118 9 P 0 0 ;0=3,1=1
P 3.0568817 1.811803 9 P 0 0 ;0=3,1=1
P 3.0688976 3.3956693 9 P 0 0 ;0=3,1=1
P 3.1972633 1.714063 9 P 0 0 ;0=3,1=1
P 3.1978425 2.970063 9 P 0 0 ;0=3,1=1
P 3.2248425 1.6613472 9 P 0 0 ;0=3,1=1
P 3.2308425 3.235063 9 P 0 0 ;0=3,1=1
P 3.2528425 1.661063 9 P 0 0 ;0=3,1=1
P 3.2636972 3.3039177 9 P 0 0 ;0=3,1=1
P 3.2988425 1.971063 9 P 0 0 ;0=3,1=1
P 3.3028425 3.344063 9 P 0 0 ;0=3,1=1
P 3.3291721 1.826063 9 P 0 0 ;0=3,1=1
P 3.3428425 2.263063 9 P 0 0 ;0=3,1=1
P 3.3448425 2.996063 9 P 0 0 ;0=3,1=1
P 3.3588425 3.448063 9 P 0 0 ;0=3,1=1
P 3.3688425 3.050063 9 P 0 0 ;0=3,1=1
P 3.3748425 3.273063 9 P 0 0 ;0=3,1=1
P 3.3928425 1.871063 9 P 0 0 ;0=3,1=1
P 3.3948425 3.447063 9 P 0 0 ;0=3,1=1
P 3.4368425 3.457063 9 P 0 0 ;0=3,1=1
P 3.4392507 1.870938 9 P 0 0 ;0=3,1=1
P 3.4698425 3.456063 9 P 0 0 ;0=3,1=1
P 3.4918425 3.103063 9 P 0 0 ;0=3,1=1
P 3.4918425 3.297063 9 P 0 0 ;0=3,1=1
P 3.4988425 2.341063 9 P 0 0 ;0=3,1=1
P 3.5048425 4.086063 9 P 0 0 ;0=3,1=1
P 3.542865 3.3190405 9 P 0 0 ;0=3,1=1
P 3.5498425 1.441063 9 P 0 0 ;0=3,1=1
P 3.5898425 1.711063 9 P 0 0 ;0=3,1=1
P 3.6228425 3.486063 9 P 0 0 ;0=3,1=1
P 3.6238425 2.587063 9 P 0 0 ;0=3,1=1
P 3.6538425 3.293063 9 P 0 0 ;0=3,1=1
P 3.7248425 1.675063 9 P 0 0 ;0=3,1=1
P 3.7448425 3.261063 9 P 0 0 ;0=3,1=1
P 3.7738632 1.6661021 9 P 0 0 ;0=3,1=1
P 3.7998425 3.201063 9 P 0 0 ;0=3,1=1
P 3.8038425 1.691063 9 P 0 0 ;0=3,1=1
P 3.8068425 3.235063 9 P 0 0 ;0=3,1=1
P 3.8298425 3.176063 9 P 0 0 ;0=3,1=1
P 3.8348425 1.481063 9 P 0 0 ;0=3,1=1
P 3.8548425 3.151063 9 P 0 0 ;0=3,1=1
P 3.8648425 1.511063 9 P 0 0 ;0=3,1=1
P 3.8948425 1.566063 9 P 0 0 ;0=3,1=1
P 3.9248425 1.536063 9 P 0 0 ;0=3,1=1
P 3.9398425 3.121063 9 P 0 0 ;0=3,1=1
P 4.0398425 2.406063 9 P 0 0 ;0=3,1=1
P 5.5778425 2.214063 9 P 0 0 ;0=3,1=1
P 5.6348425 2.236063 9 P 0 0 ;0=3,1=1

### steps/pcb/layers/sgnd/features
#Layer_Physical_Order=2
#Layer_Color=36540
#
#Feature symbol names
#
$0 r3.937
$1 r1
$2 r61.0236
$3 r75
$4 oval88.5827x177.1654
$5 oval177.1654x88.5827
$6 r120
$7 r98.4252
$8 r16
$9 r200

#
#Feature attribute names
#
@0 .geometry
@1 .pad_usage

#
#Feature attribute text strings
#
&0 Pad_Simple_X61.0236Y61.0236H41.3386C81.3386
&1 Pad_Simple_X75.0000Y75.0000H50.0000C90.0000
&2 Pad_Simple_X88.5827Y177.1654H39.3701C79.3701
&3 Pad_Simple_X177.1654Y88.5827H39.3701C79.3701
&4 Pad_Simple_X120.0000Y120.0000H68.0000C108.0000
&5 Pad_Simple_X98.4252Y98.4252H70.8661C110.8661
&6 VIA_RoundD16.0000H8.0000C48.0000
&7 VIA_RoundD200.0000H125.9843C165.9843

#
#Layer features
#
A 1.7712204 0.4310709 1.6275196 0.4310709 1.69937 0.4310709 0 P 0 N
L -0.0001175 0.177913 0.5908825 0.177913 1 P 0
L -0.0004331 0.1781182 0.5901181 0.1781182 0 P 0
L 0.5901181 0.1781182 0.5901181 0.5029213 0 P 0
L 0.5901181 0.5029213 1.312559 0.5029213 0 P 0
L 0.5908825 0.177913 0.5908825 0.502913 1 P 0
L 1.312559 0.313945 1.312559 0.5029213 0 P 0
L 1.312559 0.313945 1.6275197 0.313945 0 P 0
L 1.6275197 0.313945 1.6275197 0.4310709 0 P 0
P 0.0998425 0.806063 6 P 0 0 ;0=4,1=0
P 0.0998425 1.006063 6 P 0 0 ;0=4,1=0
P 0.0998425 1.331063 6 P 0 0 ;0=4,1=0
P 0.0998425 1.531063 6 P 0 0 ;0=4,1=0
P 0.0998425 1.856063 6 P 0 0 ;0=4,1=0
P 0.0998425 2.056063 6 P 0 0 ;0=4,1=0
P 0.0998425 2.381063 6 P 0 0 ;0=4,1=0
P 0.0998425 2.581063 6 P 0 0 ;0=4,1=0
P 0.2998425 0.806063 6 P 0 0 ;0=4,1=0
P 0.2998425 1.006063 6 P 0 0 ;0=4,1=0
P 0.2998425 1.331063 6 P 0 0 ;0=4,1=0
P 0.2998425 1.531063 6 P 0 0 ;0=4,1=0
P 0.2998425 1.856063 6 P 0 0 ;0=4,1=0
P 0.2998425 2.056063 6 P 0 0 ;0=4,1=0
P 0.2998425 2.381063 6 P 0 0 ;0=4,1=0
P 0.2998425 2.581063 6 P 0 0 ;0=4,1=0
P 3.9797272 2.4890438 3 P 0 0 ;0=1,1=0
P 5.1277559 2.3074803 2 P 0 0 ;0=0,1=0
P 5.5781524 1.6898312 3 P 0 0 ;0=1,1=0
P 5.9348031 3.9379527 4 P 0 0 ;0=2,1=0
P 6.1198425 4.056063 5 P 0 0 ;0=3,1=0
P 6.5694882 3.5895276 7 P 0 0 ;0=5,1=0
P 6.7348425 3.5895276 7 P 0 0 ;0=5,1=0
P 6.9001969 3.5895276 7 P 0 0 ;0=5,1=0
S P 0
OB 7.0787396 0.5090628 I
OS 3.1148425 0.509063
OS 3.1148425 0.2253937
OS 2.2948425 0.2253937
OS 2.2948425 0.314063
OS 2.2628425 0.346063
OS 2.2348425 0.346063
OS 2.2028425 0.314063
OS 2.2028425 0.2253937
OS 1.7818425 0.2253937
OS 1.7818425 0.3412095
OS 1.7844359 0.342556
OS 1.7868425 0.3431698
OS 1.7915996 0.3399913
OS 1.7978425 0.3387495
OS 1.8040854 0.3399913
OS 1.8093779 0.3435276
OS 1.8129142 0.3488201
OS 1.814156 0.355063
OS 1.8129142 0.3613059
OS 1.8093779 0.3665984
OS 1.8040854 0.3701347
OS 1.7978425 0.3713765
OS 1.7915996 0.3701347
OS 1.7868425 0.3669562
OS 1.7844359 0.36757
OS 1.7818425 0.3689165
OS 1.7818425 0.469063
OS 1.7358425 0.515063
OS 1.6638425 0.515063
OS 1.6188425 0.470063
OS 1.6188425 0.3129921
OS 1.3218425 0.3129921
OS 1.3218425 0.512063
OS 0.5818425 0.512063
OS 0.5818425 0.188063
OS 0.0078425 0.188063
OS 0.0078425 4.354063
OS 0.019921 4.3661415
OS 7.0787401 4.3661417
OS 7.0787396 0.5090628
OE
OB 2.5708425 4.2993765 H
OS 2.5645996 4.2981347
OS 2.5593071 4.2945984
OS 2.5557708 4.2893059
OS 2.554529 4.283063
OS 2.5557708 4.2768201
OS 2.5593071 4.2715276
OS 2.5645996 4.2679913
OS 2.5708425 4.2667495
OS 2.5770854 4.2679913
OS 2.5823779 4.2715276
OS 2.5859142 4.2768201
OS 2.587156 4.283063
OS 2.5859142 4.2893059
OS 2.5823779 4.2945984
OS 2.5770854 4.2981347
OS 2.5708425 4.2993765
OE
OB 1.2948425 4.2723765 H
OS 1.2885996 4.2711347
OS 1.2833071 4.2675984
OS 1.2797708 4.2623059
OS 1.278529 4.256063
OS 1.2797708 4.2498201
OS 1.2833071 4.2445276
OS 1.2885996 4.2409913
OS 1.2948425 4.2397495
OS 1.3010854 4.2409913
OS 1.3063779 4.2445276
OS 1.3099142 4.2498201
OS 1.311156 4.256063
OS 1.3099142 4.2623059
OS 1.3063779 4.2675984
OS 1.3010854 4.2711347
OS 1.2948425 4.2723765
OE
OB 2.0788071 4.293374 H
OS 2.0078071 4.293374
OS 2.0078071 4.222374
OS 2.0788071 4.222374
OS 2.0788071 4.293374
OE
OB 1.4931771 4.289437 H
OS 1.4221771 4.289437
OS 1.4221771 4.218437
OS 1.4931771 4.218437
OS 1.4931771 4.289437
OE
OB 1.5578425 4.2453765 H
OS 1.5515996 4.2441347
OS 1.5463071 4.2405984
OS 1.5427708 4.2353059
OS 1.541529 4.229063
OS 1.5427708 4.2228201
OS 1.5463071 4.2175276
OS 1.5515996 4.2139913
OS 1.5578425 4.2127495
OS 1.5640854 4.2139913
OS 1.5693779 4.2175276
OS 1.5729142 4.2228201
OS 1.574156 4.229063
OS 1.5729142 4.2353059
OS 1.5693779 4.2405984
OS 1.5640854 4.2441347
OS 1.5578425 4.2453765
OE
OB 1.3454724 4.1915104 H
OS 1.3392295 4.1902686
OS 1.333937 4.1867323
OS 1.3304007 4.1814398
OS 1.3291589 4.1751969
OS 1.3304007 4.168954
OS 1.333937 4.1636615
OS 1.3392295 4.1601252
OS 1.3454724 4.1588834
OS 1.3517153 4.1601252
OS 1.3570078 4.1636615
OS 1.3605441 4.168954
OS 1.3617859 4.1751969
OS 1.3605441 4.1814398
OS 1.3570078 4.1867323
OS 1.3517153 4.1902686
OS 1.3454724 4.1915104
OE
OB 1.5698819 4.1875734 H
OS 1.563639 4.1863316
OS 1.5583465 4.1827953
OS 1.5548102 4.1775028
OS 1.5535684 4.1712599
OS 1.5548102 4.165017
OS 1.5583465 4.1597245
OS 1.563639 4.1561882
OS 1.5698819 4.1549464
OS 1.5761248 4.1561882
OS 1.5814173 4.1597245
OS 1.5849536 4.165017
OS 1.5861954 4.1712599
OS 1.5849536 4.1775028
OS 1.5814173 4.1827953
OS 1.5761248 4.1863316
OS 1.5698819 4.1875734
OE
OB 1.7798425 4.1723765 H
OS 1.7735996 4.1711347
OS 1.7683071 4.1675984
OS 1.7647708 4.1623059
OS 1.763529 4.156063
OS 1.7647708 4.1498201
OS 1.7683071 4.1445276
OS 1.7735996 4.1409913
OS 1.7798425 4.1397495
OS 1.7860854 4.1409913
OS 1.7913779 4.1445276
OS 1.7949142 4.1498201
OS 1.796156 4.156063
OS 1.7949142 4.1623059
OS 1.7913779 4.1675984
OS 1.7860854 4.1711347
OS 1.7798425 4.1723765
OE
OB 2.0433071 4.1936803 H
OS 2.0340397 4.1924602
OS 2.0254039 4.1888832
OS 2.0179882 4.1831929
OS 2.0122979 4.1757772
OS 2.0087209 4.1671414
OS 2.0075008 4.157874
OS 2.0087209 4.1486066
OS 2.0122979 4.1399708
OS 2.0179882 4.1325551
OS 2.0254039 4.1268648
OS 2.0340397 4.1232878
OS 2.0433071 4.1220677
OS 2.0525745 4.1232878
OS 2.0612103 4.1268648
OS 2.068626 4.1325551
OS 2.0743163 4.1399708
OS 2.0778933 4.1486066
OS 2.0791134 4.157874
OS 2.0778933 4.1671414
OS 2.0743163 4.1757772
OS 2.068626 4.1831929
OS 2.0612103 4.1888832
OS 2.0525745 4.1924602
OS 2.0433071 4.1936803
OE
OB 1.4576771 4.1897433 H
OS 1.4484097 4.1885232
OS 1.4397739 4.1849462
OS 1.4323582 4.1792559
OS 1.4266679 4.1718402
OS 1.4230909 4.1632044
OS 1.4218708 4.153937
OS 1.4230909 4.1446696
OS 1.4266679 4.1360338
OS 1.4323582 4.1286181
OS 1.4397739 4.1229278
OS 1.4484097 4.1193508
OS 1.4576771 4.1181307
OS 1.4669445 4.1193508
OS 1.4755803 4.1229278
OS 1.482996 4.1286181
OS 1.4886863 4.1360338
OS 1.4922633 4.1446696
OS 1.4934834 4.153937
OS 1.4922633 4.1632044
OS 1.4886863 4.1718402
OS 1.482996 4.1792559
OS 1.4755803 4.1849462
OS 1.4669445 4.1885232
OS 1.4576771 4.1897433
OE
OB 3.9580709 4.1520014 H
OS 3.9513575 4.1511176
OS 3.9451017 4.1485263
OS 3.9397297 4.1444042
OS 3.9356076 4.1390322
OS 3.9330163 4.1327764
OS 3.9321325 4.126063
OS 3.9330163 4.1193496
OS 3.9356076 4.1130938
OS 3.9397297 4.1077218
OS 3.9451017 4.1035997
OS 3.9513575 4.1010084
OS 3.9580709 4.1001246
OS 3.9647843 4.1010084
OS 3.9710401 4.1035997
OS 3.9764121 4.1077218
OS 3.9805342 4.1130938
OS 3.9831255 4.1193496
OS 3.9840093 4.126063
OS 3.9831255 4.1327764
OS 3.9805342 4.1390322
OS 3.9764121 4.1444042
OS 3.9710401 4.1485263
OS 3.9647843 4.1511176
OS 3.9580709 4.1520014
OE
OB 3.7848425 4.1520014 H
OS 3.7781291 4.1511176
OS 3.7718733 4.1485263
OS 3.7665013 4.1444042
OS 3.7623792 4.1390322
OS 3.7597879 4.1327764
OS 3.7589041 4.126063
OS 3.7597879 4.1193496
OS 3.7623792 4.1130938
OS 3.7665013 4.1077218
OS 3.7718733 4.1035997
OS 3.7781291 4.1010084
OS 3.7848425 4.1001246
OS 3.7915559 4.1010084
OS 3.7978117 4.1035997
OS 3.8031837 4.1077218
OS 3.8073058 4.1130938
OS 3.8098971 4.1193496
OS 3.8107809 4.126063
OS 3.8098971 4.1327764
OS 3.8073058 4.1390322
OS 3.8031837 4.1444042
OS 3.7978117 4.1485263
OS 3.7915559 4.1511176
OS 3.7848425 4.1520014
OE
OB 4.7547119 4.1322459 H
OS 4.748469 4.1310041
OS 4.7431765 4.1274678
OS 4.7396402 4.1221753
OS 4.7383984 4.1159324
OS 4.7396402 4.1096895
OS 4.7431765 4.104397
OS 4.748469 4.1008607
OS 4.7547119 4.0996189
OS 4.7609548 4.1008607
OS 4.7662473 4.104397
OS 4.7697836 4.1096895
OS 4.7710254 4.1159324
OS 4.7697836 4.1221753
OS 4.7662473 4.1274678
OS 4.7609548 4.1310041
OS 4.7547119 4.1322459
OE
OB 2.1460663 4.1201044 H
OS 2.1398234 4.1188626
OS 2.1345309 4.1153263
OS 2.1309946 4.1100338
OS 2.1297528 4.1037909
OS 2.1309946 4.097548
OS 2.1345309 4.0922555
OS 2.1398234 4.0887192
OS 2.1460663 4.0874774
OS 2.1523092 4.0887192
OS 2.1576017 4.0922555
OS 2.161138 4.097548
OS 2.1623798 4.1037909
OS 2.161138 4.1100338
OS 2.1576017 4.1153263
OS 2.1523092 4.1188626
OS 2.1460663 4.1201044
OE
OB 5.2670079 4.1052111 H
OS 5.260765 4.1039693
OS 5.2554725 4.100433
OS 5.2519362 4.0951405
OS 5.2506944 4.0888976
OS 5.2519362 4.0826547
OS 5.2554725 4.0773622
OS 5.260765 4.0738259
OS 5.2670079 4.0725841
OS 5.2732508 4.0738259
OS 5.2785433 4.0773622
OS 5.2820796 4.0826547
OS 5.2833214 4.0888976
OS 5.2820796 4.0951405
OS 5.2785433 4.100433
OS 5.2732508 4.1039693
OS 5.2670079 4.1052111
OE
OB 2.253937 4.1029277 H
OS 2.2476941 4.1016859
OS 2.2424016 4.0981496
OS 2.2388653 4.0928571
OS 2.2376235 4.0866142
OS 2.2388653 4.0803713
OS 2.2424016 4.0750788
OS 2.2476941 4.0715425
OS 2.253937 4.0703007
OS 2.2601799 4.0715425
OS 2.2654724 4.0750788
OS 2.2690087 4.0803713
OS 2.2702505 4.0866142
OS 2.2690087 4.0928571
OS 2.2654724 4.0981496
OS 2.2601799 4.1016859
OS 2.253937 4.1029277
OE
OB 3.5048425 4.1023765 H
OS 3.4985996 4.1011347
OS 3.4933071 4.0975984
OS 3.4897708 4.0923059
OS 3.488529 4.086063
OS 3.4897708 4.0798201
OS 3.4933071 4.0745276
OS 3.4985996 4.0709913
OS 3.5048425 4.0697495
OS 3.5110854 4.0709913
OS 3.5163779 4.0745276
OS 3.5199142 4.0798201
OS 3.521156 4.086063
OS 3.5199142 4.0923059
OS 3.5163779 4.0975984
OS 3.5110854 4.1011347
OS 3.5048425 4.1023765
OE
OB 3.2948425 4.1274482 H
OS 3.2841414 4.1260394
OS 3.2741696 4.1219089
OS 3.2656066 4.1153383
OS 3.259036 4.1067753
OS 3.2549055 4.0968035
OS 3.2534967 4.0861024
OS 3.2549055 4.0754013
OS 3.259036 4.0654295
OS 3.2656066 4.0568665
OS 3.2741696 4.0502959
OS 3.2841414 4.0461654
OS 3.2948425 4.0447566
OS 3.3055436 4.0461654
OS 3.3155154 4.0502959
OS 3.3240784 4.0568665
OS 3.330649 4.0654295
OS 3.3347795 4.0754013
OS 3.3361883 4.0861024
OS 3.3347795 4.0968035
OS 3.330649 4.1067753
OS 3.3240784 4.1153383
OS 3.3155154 4.1219089
OS 3.3055436 4.1260394
OS 3.2948425 4.1274482
OE
OB 2.9948425 4.1274482 H
OS 2.9841414 4.1260394
OS 2.9741696 4.1219089
OS 2.9656066 4.1153383
OS 2.959036 4.1067753
OS 2.9549055 4.0968035
OS 2.9534967 4.0861024
OS 2.9549055 4.0754013
OS 2.959036 4.0654295
OS 2.9656066 4.0568665
OS 2.9741696 4.0502959
OS 2.9841414 4.0461654
OS 2.9948425 4.0447566
OS 3.0055436 4.0461654
OS 3.0155154 4.0502959
OS 3.0240784 4.0568665
OS 3.030649 4.0654295
OS 3.0347795 4.0754013
OS 3.0361883 4.0861024
OS 3.0347795 4.0968035
OS 3.030649 4.1067753
OS 3.0240784 4.1153383
OS 3.0155154 4.1219089
OS 3.0055436 4.1260394
OS 2.9948425 4.1274482
OE
OB 6.9001969 4.1608442 H
OS 6.8870518 4.1595495
OS 6.8744118 4.1557152
OS 6.8627628 4.1494887
OS 6.8525523 4.1411092
OS 6.8441728 4.1308987
OS 6.8379463 4.1192497
OS 6.834112 4.1066097
OS 6.8328173 4.0934646
OS 6.834112 4.0803195
OS 6.8379463 4.0676795
OS 6.8441728 4.0560305
OS 6.8525523 4.04582
OS 6.8627628 4.0374405
OS 6.8744118 4.031214
OS 6.8870518 4.0273797
OS 6.9001969 4.026085
OS 6.913342 4.0273797
OS 6.925982 4.031214
OS 6.937631 4.0374405
OS 6.9478415 4.04582
OS 6.956221 4.0560305
OS 6.9624475 4.0676795
OS 6.9662818 4.0803195
OS 6.9675765 4.0934646
OS 6.9662818 4.1066097
OS 6.9624475 4.1192497
OS 6.956221 4.1308987
OS 6.9478415 4.1411092
OS 6.937631 4.1494887
OS 6.925982 4.1557152
OS 6.913342 4.1595495
OS 6.9001969 4.1608442
OE
OB 6.5694882 4.1608442 H
OS 6.5563431 4.1595495
OS 6.5437031 4.1557152
OS 6.5320541 4.1494887
OS 6.5218436 4.1411092
OS 6.5134641 4.1308987
OS 6.5072376 4.1192497
OS 6.5034033 4.1066097
OS 6.5021086 4.0934646
OS 6.5034033 4.0803195
OS 6.5072376 4.0676795
OS 6.5134641 4.0560305
OS 6.5218436 4.04582
OS 6.5320541 4.0374405
OS 6.5437031 4.031214
OS 6.5563431 4.0273797
OS 6.5694882 4.026085
OS 6.5826333 4.0273797
OS 6.5952733 4.031214
OS 6.6069223 4.0374405
OS 6.6171328 4.04582
OS 6.6255123 4.0560305
OS 6.6317388 4.0676795
OS 6.6355731 4.0803195
OS 6.6368678 4.0934646
OS 6.6355731 4.1066097
OS 6.6317388 4.1192497
OS 6.6255123 4.1308987
OS 6.6171328 4.1411092
OS 6.6069223 4.1494887
OS 6.5952733 4.1557152
OS 6.5826333 4.1595495
OS 6.5694882 4.1608442
OE
OB 2.0433071 4.0936803 H
OS 2.0340397 4.0924602
OS 2.0254039 4.0888832
OS 2.0179882 4.0831929
OS 2.0122979 4.0757772
OS 2.0087209 4.0671414
OS 2.0075008 4.057874
OS 2.0087209 4.0486066
OS 2.0122979 4.0399708
OS 2.0179882 4.0325551
OS 2.0254039 4.0268648
OS 2.0340397 4.0232878
OS 2.0433071 4.0220677
OS 2.0525745 4.0232878
OS 2.0612103 4.0268648
OS 2.068626 4.0325551
OS 2.0743163 4.0399708
OS 2.0778933 4.0486066
OS 2.0791134 4.057874
OS 2.0778933 4.0671414
OS 2.0743163 4.0757772
OS 2.068626 4.0831929
OS 2.0612103 4.0888832
OS 2.0525745 4.0924602
OS 2.0433071 4.0936803
OE
OB 0.285433 4.2854743 H
OS 0.2645629 4.2838318
OS 0.2442066 4.2789447
OS 0.2248655 4.2709333
OS 0.2070158 4.259995
OS 0.191097 4.246399
OS 0.177501 4.2304802
OS 0.1665627 4.2126305
OS 0.1585513 4.1932894
OS 0.1536642 4.1729331
OS 0.1520217 4.152063
OS 0.1536642 4.1311929
OS 0.1585513 4.1108366
OS 0.1665627 4.0914955
OS 0.177501 4.0736458
OS 0.191097 4.057727
OS 0.2070158 4.044131
OS 0.2248655 4.0331927
OS 0.2442066 4.0251813
OS 0.2645629 4.0202942
OS 0.285433 4.0186517
OS 0.3063031 4.0202942
OS 0.3266594 4.0251813
OS 0.3460005 4.0331927
OS 0.3638502 4.044131
OS 0.379769 4.057727
OS 0.393365 4.0736458
OS 0.4043033 4.0914955
OS 0.4123147 4.1108366
OS 0.4172018 4.1311929
OS 0.4188443 4.152063
OS 0.4172018 4.1729331
OS 0.4123147 4.1932894
OS 0.4043033 4.2126305
OS 0.393365 4.2304802
OS 0.379769 4.246399
OS 0.3638502 4.259995
OS 0.3460005 4.2709333
OS 0.3266594 4.2789447
OS 0.3063031 4.2838318
OS 0.285433 4.2854743
OE
OB 1.4576771 4.0897433 H
OS 1.4484097 4.0885232
OS 1.4397739 4.0849462
OS 1.4323582 4.0792559
OS 1.4266679 4.0718402
OS 1.4230909 4.0632044
OS 1.4218708 4.053937
OS 1.4230909 4.0446696
OS 1.4266679 4.0360338
OS 1.4323582 4.0286181
OS 1.4397739 4.0229278
OS 1.4484097 4.0193508
OS 1.4576771 4.0181307
OS 1.4669445 4.0193508
OS 1.4755803 4.0229278
OS 1.482996 4.0286181
OS 1.4886863 4.0360338
OS 1.4922633 4.0446696
OS 1.4934834 4.053937
OS 1.4922633 4.0632044
OS 1.4886863 4.0718402
OS 1.482996 4.0792559
OS 1.4755803 4.0849462
OS 1.4669445 4.0885232
OS 1.4576771 4.0897433
OE
OB 1.9038425 4.0343765 H
OS 1.8975996 4.0331347
OS 1.8923071 4.0295984
OS 1.8887708 4.0243059
OS 1.887529 4.018063
OS 1.8887708 4.0118201
OS 1.8923071 4.0065276
OS 1.8975996 4.0029913
OS 1.9038425 4.0017495
OS 1.9100854 4.0029913
OS 1.9153779 4.0065276
OS 1.9189142 4.0118201
OS 1.920156 4.018063
OS 1.9189142 4.0243059
OS 1.9153779 4.0295984
OS 1.9100854 4.0331347
OS 1.9038425 4.0343765
OE
OB 2.3533464 4.03403 H
OS 2.3471035 4.0327882
OS 2.341811 4.0292519
OS 2.3382747 4.0239594
OS 2.3370329 4.0177165
OS 2.3382747 4.0114736
OS 2.341811 4.0061811
OS 2.3471035 4.0026448
OS 2.3533464 4.001403
OS 2.3595893 4.0026448
OS 2.3648818 4.0061811
OS 2.3684181 4.0114736
OS 2.3696599 4.0177165
OS 2.3684181 4.0239594
OS 2.3648818 4.0292519
OS 2.3595893 4.0327882
OS 2.3533464 4.03403
OE
OB 5.7234252 4.0832969 H
OS 5.7084897 4.0813306
OS 5.6945721 4.0755657
OS 5.6826207 4.0663951
OS 5.6734501 4.0544438
OS 5.6676852 4.0405261
OS 5.6657189 4.0255906
OS 5.6676852 4.0106551
OS 5.6734501 3.9967374
OS 5.6826207 3.9847861
OS 5.6945721 3.9756155
OS 5.7084897 3.9698506
OS 5.7234252 3.9678843
OS 5.7383607 3.9698506
OS 5.7522783 3.9756155
OS 5.7642297 3.9847861
OS 5.7734003 3.9967374
OS 5.7791652 4.0106551
OS 5.7811315 4.0255906
OS 5.7791652 4.0405261
OS 5.7734003 4.0544438
OS 5.7642297 4.0663951
OS 5.7522783 4.0755657
OS 5.7383607 4.0813306
OS 5.7234252 4.0832969
OE
OB 1.4084645 3.9966285 H
OS 1.4022216 3.9953867
OS 1.3969291 3.9918504
OS 1.3933928 3.9865579
OS 1.392151 3.980315
OS 1.3933928 3.9740721
OS 1.3969291 3.9687796
OS 1.4022216 3.9652433
OS 1.4084645 3.9640015
OS 1.4147074 3.9652433
OS 1.4199999 3.9687796
OS 1.4235362 3.9740721
OS 1.424778 3.980315
OS 1.4235362 3.9865579
OS 1.4199999 3.9918504
OS 1.4147074 3.9953867
OS 1.4084645 3.9966285
OE
OB 2.0848425 3.9123765 H
OS 2.0785996 3.9111347
OS 2.0733071 3.9075984
OS 2.0697708 3.9023059
OS 2.068529 3.896063
OS 2.0697708 3.8898201
OS 2.0699331 3.8895773
OS 2.0663282 3.8859724
OS 2.0660854 3.8861347
OS 2.0598425 3.8873765
OS 2.0535996 3.8861347
OS 2.0483071 3.8825984
OS 2.0447708 3.8773059
OS 2.043529 3.871063
OS 2.0447708 3.8648201
OS 2.0483071 3.8595276
OS 2.0535996 3.8559913
OS 2.0598425 3.8547495
OS 2.0660854 3.8559913
OS 2.0713779 3.8595276
OS 2.0749142 3.8648201
OS 2.076156 3.871063
OS 2.0749142 3.8773059
OS 2.0747519 3.8775487
OS 2.0783568 3.8811536
OS 2.0785996 3.8809913
OS 2.0848425 3.8797495
OS 2.0910854 3.8809913
OS 2.0963779 3.8845276
OS 2.0999142 3.8898201
OS 2.101156 3.896063
OS 2.0999142 3.9023059
OS 2.0963779 3.9075984
OS 2.0910854 3.9111347
OS 2.0848425 3.9123765
OE
OB 2.0298425 3.8523765 H
OS 2.0235996 3.8511347
OS 2.0183071 3.8475984
OS 2.0147708 3.8423059
OS 2.013529 3.836063
OS 2.0136749 3.8353296
OS 2.0130932 3.8343873
OS 2.0093423 3.8314814
OS 2.0048425 3.8323765
OS 1.9985996 3.8311347
OS 1.9933071 3.8275984
OS 1.9897708 3.8223059
OS 1.988529 3.816063
OS 1.9897708 3.8098201
OS 1.9933071 3.8045276
OS 1.9985996 3.8009913
OS 2.0048425 3.7997495
OS 2.0110854 3.8009913
OS 2.0163779 3.8045276
OS 2.0199142 3.8098201
OS 2.021156 3.816063
OS 2.0210101 3.8167964
OS 2.0215918 3.8177387
OS 2.0253427 3.8206446
OS 2.0298425 3.8197495
OS 2.0360854 3.8209913
OS 2.0413779 3.8245276
OS 2.0449142 3.8298201
OS 2.046156 3.836063
OS 2.0449142 3.8423059
OS 2.0413779 3.8475984
OS 2.0360854 3.8511347
OS 2.0298425 3.8523765
OE
OB 3.6998425 3.8523765 H
OS 3.6935996 3.8511347
OS 3.6883071 3.8475984
OS 3.6847708 3.8423059
OS 3.683529 3.836063
OS 3.6847708 3.8298201
OS 3.6883071 3.8245276
OS 3.6935996 3.8209913
OS 3.6998425 3.8197495
OS 3.7060854 3.8209913
OS 3.7113779 3.8245276
OS 3.7149142 3.8298201
OS 3.716156 3.836063
OS 3.7149142 3.8423059
OS 3.7113779 3.8475984
OS 3.7060854 3.8511347
OS 3.6998425 3.8523765
OE
OB 3.0148425 3.8473765 H
OS 3.0085996 3.8461347
OS 3.0033071 3.8425984
OS 2.9997708 3.8373059
OS 2.998529 3.831063
OS 2.9997708 3.8248201
OS 3.0033071 3.8195276
OS 3.0085996 3.8159913
OS 3.0148425 3.8147495
OS 3.0210854 3.8159913
OS 3.0263779 3.8195276
OS 3.0299142 3.8248201
OS 3.031156 3.831063
OS 3.0299142 3.8373059
OS 3.0263779 3.8425984
OS 3.0210854 3.8461347
OS 3.0148425 3.8473765
OE
OB 3.8298425 3.8223765 H
OS 3.8235996 3.8211347
OS 3.8183071 3.8175984
OS 3.8147708 3.8123059
OS 3.813529 3.806063
OS 3.8147708 3.7998201
OS 3.8183071 3.7945276
OS 3.8235996 3.7909913
OS 3.8298425 3.7897495
OS 3.8360854 3.7909913
OS 3.8413779 3.7945276
OS 3.8449142 3.7998201
OS 3.846156 3.806063
OS 3.8449142 3.8123059
OS 3.8413779 3.8175984
OS 3.8360854 3.8211347
OS 3.8298425 3.8223765
OE
OB 3.5398425 3.8223765 H
OS 3.5335996 3.8211347
OS 3.5283071 3.8175984
OS 3.5247708 3.8123059
OS 3.523529 3.806063
OS 3.5247708 3.7998201
OS 3.5283071 3.7945276
OS 3.5335996 3.7909913
OS 3.5398425 3.7897495
OS 3.5460854 3.7909913
OS 3.5513779 3.7945276
OS 3.5549142 3.7998201
OS 3.556156 3.806063
OS 3.5549142 3.8123059
OS 3.5513779 3.8175984
OS 3.5460854 3.8211347
OS 3.5398425 3.8223765
OE
OB 3.2198425 3.8223765 H
OS 3.2135996 3.8211347
OS 3.2083071 3.8175984
OS 3.2047708 3.8123059
OS 3.203529 3.806063
OS 3.2047708 3.7998201
OS 3.2083071 3.7945276
OS 3.2135996 3.7909913
OS 3.2198425 3.7897495
OS 3.2260854 3.7909913
OS 3.2313779 3.7945276
OS 3.2349142 3.7998201
OS 3.236156 3.806063
OS 3.2349142 3.8123059
OS 3.2313779 3.8175984
OS 3.2260854 3.8211347
OS 3.2198425 3.8223765
OE
OB 5.7234252 3.9021945 H
OS 5.7084897 3.9002282
OS 5.6945721 3.8944633
OS 5.6826207 3.8852927
OS 5.6734501 3.8733414
OS 5.6676852 3.8594237
OS 5.6657189 3.8444882
OS 5.6676852 3.8295527
OS 5.6734501 3.815635
OS 5.6826207 3.8036837
OS 5.6945721 3.7945131
OS 5.7084897 3.7887482
OS 5.7234252 3.7867819
OS 5.7383607 3.7887482
OS 5.7522783 3.7945131
OS 5.7642297 3.8036837
OS 5.7734003 3.815635
OS 5.7791652 3.8295527
OS 5.7811315 3.8444882
OS 5.7791652 3.8594237
OS 5.7734003 3.8733414
OS 5.7642297 3.8852927
OS 5.7522783 3.8944633
OS 5.7383607 3.9002282
OS 5.7234252 3.9021945
OE
OB 2.7224094 3.8023844 H
OS 2.7161665 3.8011426
OS 2.710874 3.7976063
OS 2.7073377 3.7923138
OS 2.7060959 3.7860709
OS 2.7073377 3.779828
OS 2.710874 3.7745355
OS 2.7161665 3.7709992
OS 2.7224094 3.7697574
OS 2.7286523 3.7709992
OS 2.7339448 3.7745355
OS 2.7374811 3.779828
OS 2.7387229 3.7860709
OS 2.7374811 3.7923138
OS 2.7339448 3.7976063
OS 2.7286523 3.8011426
OS 2.7224094 3.8023844
OE
OB 6.1690551 3.8775488 H
OS 6.0706299 3.8775488
OS 6.0556944 3.8755825
OS 6.0417767 3.8698176
OS 6.0298254 3.860647
OS 6.0206548 3.8486956
OS 6.0148899 3.834778
OS 6.0129236 3.8198425
OS 6.0148899 3.804907
OS 6.0206548 3.7909894
OS 6.0298254 3.779038
OS 6.0417767 3.7698674
OS 6.0556944 3.7641025
OS 6.0706299 3.7621362
OS 6.1690551 3.7621362
OS 6.1839906 3.7641025
OS 6.1979083 3.7698674
OS 6.2098596 3.779038
OS 6.2190302 3.7909894
OS 6.2247951 3.804907
OS 6.2267614 3.8198425
OS 6.2247951 3.834778
OS 6.2190302 3.8486956
OS 6.2098596 3.860647
OS 6.1979083 3.8698176
OS 6.1839906 3.8755825
OS 6.1690551 3.8775488
OE
OB 4.2548425 3.7923765 H
OS 4.2485996 3.7911347
OS 4.2433071 3.7875984
OS 4.2397708 3.7823059
OS 4.238529 3.776063
OS 4.2397708 3.7698201
OS 4.2433071 3.7645276
OS 4.2485996 3.7609913
OS 4.2548425 3.7597495
OS 4.2610854 3.7609913
OS 4.2663779 3.7645276
OS 4.2699142 3.7698201
OS 4.271156 3.776063
OS 4.2699142 3.7823059
OS 4.2663779 3.7875984
OS 4.2610854 3.7911347
OS 4.2548425 3.7923765
OE
OB 6.9001969 3.8637693 H
OS 6.8852614 3.861803
OS 6.8713437 3.8560381
OS 6.8593924 3.8468675
OS 6.8502218 3.8349162
OS 6.8444569 3.8209985
OS 6.8424906 3.806063
OS 6.8444569 3.7911275
OS 6.8502218 3.7772098
OS 6.8593924 3.7652585
OS 6.8713437 3.7560879
OS 6.8852614 3.750323
OS 6.9001969 3.7483567
OS 6.9151324 3.750323
OS 6.9290501 3.7560879
OS 6.9410014 3.7652585
OS 6.950172 3.7772098
OS 6.9559369 3.7911275
OS 6.9579032 3.806063
OS 6.9559369 3.8209985
OS 6.950172 3.8349162
OS 6.9410014 3.8468675
OS 6.9290501 3.8560381
OS 6.9151324 3.861803
OS 6.9001969 3.8637693
OE
OB 6.7348425 3.8637693 H
OS 6.719907 3.861803
OS 6.7059893 3.8560381
OS 6.694038 3.8468675
OS 6.6848674 3.8349162
OS 6.6791025 3.8209985
OS 6.6771362 3.806063
OS 6.6791025 3.7911275
OS 6.6848674 3.7772098
OS 6.694038 3.7652585
OS 6.7059893 3.7560879
OS 6.719907 3.750323
OS 6.7348425 3.7483567
OS 6.749778 3.750323
OS 6.7636957 3.7560879
OS 6.775647 3.7652585
OS 6.7848176 3.7772098
OS 6.7905825 3.7911275
OS 6.7925488 3.806063
OS 6.7905825 3.8209985
OS 6.7848176 3.8349162
OS 6.775647 3.8468675
OS 6.7636957 3.8560381
OS 6.749778 3.861803
OS 6.7348425 3.8637693
OE
OB 6.5694882 3.8637693 H
OS 6.5545527 3.861803
OS 6.540635 3.8560381
OS 6.5286837 3.8468675
OS 6.5195131 3.8349161
OS 6.5137482 3.8209985
OS 6.5117819 3.806063
OS 6.5137482 3.7911275
OS 6.5195131 3.7772099
OS 6.5286837 3.7652585
OS 6.540635 3.7560879
OS 6.5545527 3.750323
OS 6.5694882 3.7483567
OS 6.5844237 3.750323
OS 6.5983414 3.7560879
OS 6.6102927 3.7652585
OS 6.6194633 3.7772099
OS 6.6252282 3.7911275
OS 6.6271945 3.806063
OS 6.6252282 3.8209985
OS 6.6194633 3.8349161
OS 6.6102927 3.8468675
OS 6.5983414 3.8560381
OS 6.5844237 3.861803
OS 6.5694882 3.8637693
OE
OB 3.6998425 3.7673765 H
OS 3.6935996 3.7661347
OS 3.6883071 3.7625984
OS 3.6847708 3.7573059
OS 3.683529 3.751063
OS 3.6847708 3.7448201
OS 3.6883071 3.7395276
OS 3.6935996 3.7359913
OS 3.6998425 3.7347495
OS 3.7060854 3.7359913
OS 3.7113779 3.7395276
OS 3.7149142 3.7448201
OS 3.716156 3.751063
OS 3.7149142 3.7573059
OS 3.7113779 3.7625984
OS 3.7060854 3.7661347
OS 3.6998425 3.7673765
OE
OB 2.9933858 3.7673765 H
OS 2.9871429 3.7661347
OS 2.9818504 3.7625984
OS 2.9783141 3.7573059
OS 2.9770723 3.751063
OS 2.9783141 3.7448201
OS 2.9818504 3.7395276
OS 2.9871429 3.7359913
OS 2.9933858 3.7347495
OS 2.9996287 3.7359913
OS 3.0049212 3.7395276
OS 3.0084575 3.7448201
OS 3.0096993 3.751063
OS 3.0084575 3.7573059
OS 3.0049212 3.7625984
OS 2.9996287 3.7661347
OS 2.9933858 3.7673765
OE
OB 6.2948425 3.7173765 H
OS 6.2885996 3.7161347
OS 6.2833071 3.7125984
OS 6.2797708 3.7073059
OS 6.278529 3.701063
OS 6.2797708 3.6948201
OS 6.2833071 3.6895276
OS 6.2885996 3.6859913
OS 6.2948425 3.6847495
OS 6.3010854 3.6859913
OS 6.3063779 3.6895276
OS 6.3099142 3.6948201
OS 6.311156 3.701063
OS 6.3099142 3.7073059
OS 6.3063779 3.7125984
OS 6.3010854 3.7161347
OS 6.2948425 3.7173765
OE
OB 1.8498425 3.7173765 H
OS 1.8435996 3.7161347
OS 1.8383071 3.7125984
OS 1.8347708 3.7073059
OS 1.833529 3.701063
OS 1.8347708 3.6948201
OS 1.8383071 3.6895276
OS 1.8435996 3.6859913
OS 1.8498425 3.6847495
OS 1.8560854 3.6859913
OS 1.8613779 3.6895276
OS 1.8649142 3.6948201
OS 1.866156 3.701063
OS 1.8649142 3.7073059
OS 1.8613779 3.7125984
OS 1.8560854 3.7161347
OS 1.8498425 3.7173765
OE
OB 4.0498425 3.6813765 H
OS 4.0435996 3.6801347
OS 4.0383071 3.6765984
OS 4.0347708 3.6713059
OS 4.033529 3.665063
OS 4.0347708 3.6588201
OS 4.0383071 3.6535276
OS 4.0435996 3.6499913
OS 4.0498425 3.6487495
OS 4.0560854 3.6499913
OS 4.0613779 3.6535276
OS 4.0649142 3.6588201
OS 4.066156 3.665063
OS 4.0649142 3.6713059
OS 4.0613779 3.6765984
OS 4.0560854 3.6801347
OS 4.0498425 3.6813765
OE
OB 2.6798425 3.6773765 H
OS 2.6735996 3.6761347
OS 2.6683071 3.6725984
OS 2.6647708 3.6673059
OS 2.663529 3.661063
OS 2.6647708 3.6548201
OS 2.6683071 3.6495276
OS 2.6735996 3.6459913
OS 2.6798425 3.6447495
OS 2.6860854 3.6459913
OS 2.6913779 3.6495276
OS 2.6949142 3.6548201
OS 2.696156 3.661063
OS 2.6949142 3.6673059
OS 2.6913779 3.6725984
OS 2.6860854 3.6761347
OS 2.6798425 3.6773765
OE
OB 1.7548425 3.6773765 H
OS 1.7485996 3.6761347
OS 1.7433071 3.6725984
OS 1.7397708 3.6673059
OS 1.738529 3.661063
OS 1.7397708 3.6548201
OS 1.7433071 3.6495276
OS 1.7485996 3.6459913
OS 1.7548425 3.6447495
OS 1.7610854 3.6459913
OS 1.7663779 3.6495276
OS 1.7699142 3.6548201
OS 1.771156 3.661063
OS 1.7699142 3.6673059
OS 1.7663779 3.6725984
OS 1.7610854 3.6761347
OS 1.7548425 3.6773765
OE
OB 3.4248425 3.6523765 H
OS 3.4185996 3.6511347
OS 3.4133071 3.6475984
OS 3.4097708 3.6423059
OS 3.408529 3.636063
OS 3.4097708 3.6298201
OS 3.4133071 3.6245276
OS 3.4185996 3.6209913
OS 3.4248425 3.6197495
OS 3.4310854 3.6209913
OS 3.4363779 3.6245276
OS 3.4399142 3.6298201
OS 3.441156 3.636063
OS 3.4399142 3.6423059
OS 3.4363779 3.6475984
OS 3.4310854 3.6511347
OS 3.4248425 3.6523765
OE
OB 2.7998425 3.6323765 H
OS 2.7935996 3.6311347
OS 2.7883071 3.6275984
OS 2.7847708 3.6223059
OS 2.783529 3.616063
OS 2.7847708 3.6098201
OS 2.7883071 3.6045276
OS 2.7935996 3.6009913
OS 2.7998425 3.5997495
OS 2.8060854 3.6009913
OS 2.8113779 3.6045276
OS 2.8149142 3.6098201
OS 2.816156 3.616063
OS 2.8149142 3.6223059
OS 2.8113779 3.6275984
OS 2.8060854 3.6311347
OS 2.7998425 3.6323765
OE
OB 2.1398425 3.6273765 H
OS 2.1335996 3.6261347
OS 2.1283071 3.6225984
OS 2.1247708 3.6173059
OS 2.123529 3.611063
OS 2.1247708 3.6048201
OS 2.1283071 3.5995276
OS 2.1335996 3.5959913
OS 2.1398425 3.5947495
OS 2.1460854 3.5959913
OS 2.1513779 3.5995276
OS 2.1549142 3.6048201
OS 2.156156 3.611063
OS 2.1549142 3.6173059
OS 2.1513779 3.6225984
OS 2.1460854 3.6261347
OS 2.1398425 3.6273765
OE
OB 1.8848425 3.6173765 H
OS 1.8785996 3.6161347
OS 1.8733071 3.6125984
OS 1.8697708 3.6073059
OS 1.868529 3.601063
OS 1.8697708 3.5948201
OS 1.8733071 3.5895276
OS 1.8785996 3.5859913
OS 1.8848425 3.5847495
OS 1.8910854 3.5859913
OS 1.8963779 3.5895276
OS 1.8999142 3.5948201
OS 1.901156 3.601063
OS 1.8999142 3.6073059
OS 1.8963779 3.6125984
OS 1.8910854 3.6161347
OS 1.8848425 3.6173765
OE
OB 3.2398425 3.6123765 H
OS 3.2335996 3.6111347
OS 3.2283071 3.6075984
OS 3.2247708 3.6023059
OS 3.223529 3.596063
OS 3.2247708 3.5898201
OS 3.2283071 3.5845276
OS 3.2335996 3.5809913
OS 3.2398425 3.5797495
OS 3.2460854 3.5809913
OS 3.2513779 3.5845276
OS 3.2549142 3.5898201
OS 3.256156 3.596063
OS 3.2549142 3.6023059
OS 3.2513779 3.6075984
OS 3.2460854 3.6111347
OS 3.2398425 3.6123765
OE
OB 1.5498425 3.6373765 H
OS 1.5435996 3.6361347
OS 1.5383071 3.6325984
OS 1.5347708 3.6273059
OS 1.533529 3.621063
OS 1.5347708 3.6148201
OS 1.5383071 3.6095276
OS 1.5435996 3.6059913
OS 1.5498425 3.6047495
OS 1.5560854 3.6059913
OS 1.5563282 3.6061536
OS 1.5599331 3.6025487
OS 1.5597708 3.6023059
OS 1.558529 3.596063
OS 1.5597708 3.5898201
OS 1.5633071 3.5845276
OS 1.5685996 3.5809913
OS 1.5748425 3.5797495
OS 1.5810854 3.5809913
OS 1.5863779 3.5845276
OS 1.5899142 3.5898201
OS 1.591156 3.596063
OS 1.5899142 3.6023059
OS 1.5863779 3.6075984
OS 1.5810854 3.6111347
OS 1.5748425 3.6123765
OS 1.5685996 3.6111347
OS 1.5683568 3.6109724
OS 1.5647519 3.6145773
OS 1.5649142 3.6148201
OS 1.566156 3.621063
OS 1.5649142 3.6273059
OS 1.5613779 3.6325984
OS 1.5560854 3.6361347
OS 1.5498425 3.6373765
OE
OB 2.4223425 3.6247884 H
OS 2.4133837 3.6230064
OS 2.4057888 3.6179317
OS 2.4007141 3.6103368
OS 2.3989321 3.601378
OS 2.4007141 3.5924192
OS 2.4057888 3.5848243
OS 2.4133837 3.5797496
OS 2.4223425 3.5779676
OS 2.4313013 3.5797496
OS 2.4388962 3.5848243
OS 2.4439709 3.5924192
OS 2.4457529 3.601378
OS 2.4439709 3.6103368
OS 2.4388962 3.6179317
OS 2.4313013 3.6230064
OS 2.4223425 3.6247884
OE
OB 2.7748425 3.5823765 H
OS 2.7685996 3.5811347
OS 2.7633071 3.5775984
OS 2.7597708 3.5723059
OS 2.758529 3.566063
OS 2.7597708 3.5598201
OS 2.7633071 3.5545276
OS 2.7685996 3.5509913
OS 2.7748425 3.5497495
OS 2.7810854 3.5509913
OS 2.7863779 3.5545276
OS 2.7899142 3.5598201
OS 2.791156 3.566063
OS 2.7899142 3.5723059
OS 2.7863779 3.5775984
OS 2.7810854 3.5811347
OS 2.7748425 3.5823765
OE
OB 1.4408425 3.5733765 H
OS 1.4345996 3.5721347
OS 1.4293071 3.5685984
OS 1.4257708 3.5633059
OS 1.424529 3.557063
OS 1.4257708 3.5508201
OS 1.4293071 3.5455276
OS 1.4345996 3.5419913
OS 1.4408425 3.5407495
OS 1.4470854 3.5419913
OS 1.4523779 3.5455276
OS 1.4559142 3.5508201
OS 1.457156 3.557063
OS 1.4559142 3.5633059
OS 1.4523779 3.5685984
OS 1.4470854 3.5721347
OS 1.4408425 3.5733765
OE
OB 5.9948425 3.5683765 H
OS 5.9885996 3.5671347
OS 5.9833071 3.5635984
OS 5.9797708 3.5583059
OS 5.978529 3.552063
OS 5.9797708 3.5458201
OS 5.9833071 3.5405276
OS 5.9885996 3.5369913
OS 5.9948425 3.5357495
OS 6.0010854 3.5369913
OS 6.0063779 3.5405276
OS 6.0099142 3.5458201
OS 6.011156 3.552063
OS 6.0099142 3.5583059
OS 6.0063779 3.5635984
OS 6.0010854 3.5671347
OS 5.9948425 3.5683765
OE
OB 2.4348425 3.5623765 H
OS 2.4285996 3.5611347
OS 2.4233071 3.5575984
OS 2.4197708 3.5523059
OS 2.418529 3.546063
OS 2.4197708 3.5398201
OS 2.4233071 3.5345276
OS 2.4285996 3.5309913
OS 2.4348425 3.5297495
OS 2.4410854 3.5309913
OS 2.4463779 3.5345276
OS 2.4499142 3.5398201
OS 2.451156 3.546063
OS 2.4499142 3.5523059
OS 2.4463779 3.5575984
OS 2.4410854 3.5611347
OS 2.4348425 3.5623765
OE
OB 2.2548425 3.5523765 H
OS 2.2485996 3.5511347
OS 2.2433071 3.5475984
OS 2.2397708 3.5423059
OS 2.238529 3.536063
OS 2.2397708 3.5298201
OS 2.2424883 3.5257531
OS 2.2396399 3.5214222
OS 2.2348425 3.5223765
OS 2.2285996 3.5211347
OS 2.2233071 3.5175984
OS 2.2197708 3.5123059
OS 2.218529 3.506063
OS 2.2197708 3.4998201
OS 2.2233071 3.4945276
OS 2.2285996 3.4909913
OS 2.2348425 3.4897495
OS 2.2410854 3.4909913
OS 2.2463779 3.4945276
OS 2.2499142 3.4998201
OS 2.251156 3.506063
OS 2.2499142 3.5123059
OS 2.2471967 3.5163729
OS 2.2500451 3.5207038
OS 2.2548425 3.5197495
OS 2.2610854 3.5209913
OS 2.2663779 3.5245276
OS 2.2699142 3.5298201
OS 2.271156 3.536063
OS 2.2699142 3.5423059
OS 2.2663779 3.5475984
OS 2.2610854 3.5511347
OS 2.2548425 3.5523765
OE
OB 5.2748425 3.5273765 H
OS 5.2685996 3.5261347
OS 5.2633071 3.5225984
OS 5.2597708 3.5173059
OS 5.258529 3.511063
OS 5.2597708 3.5048201
OS 5.2633071 3.4995276
OS 5.2685996 3.4959913
OS 5.2748425 3.4947495
OS 5.2810854 3.4959913
OS 5.2863779 3.4995276
OS 5.2899142 3.5048201
OS 5.291156 3.511063
OS 5.2899142 3.5173059
OS 5.2863779 3.5225984
OS 5.2810854 3.5261347
OS 5.2748425 3.5273765
OE
OB 3.6228425 3.5023765 H
OS 3.6165996 3.5011347
OS 3.6113071 3.4975984
OS 3.6077708 3.4923059
OS 3.606529 3.486063
OS 3.6077708 3.4798201
OS 3.6113071 3.4745276
OS 3.6165996 3.4709913
OS 3.6228425 3.4697495
OS 3.6290854 3.4709913
OS 3.6343779 3.4745276
OS 3.6379142 3.4798201
OS 3.639156 3.486063
OS 3.6379142 3.4923059
OS 3.6343779 3.4975984
OS 3.6290854 3.5011347
OS 3.6228425 3.5023765
OE
OB 2.5798425 3.5023765 H
OS 2.5735996 3.5011347
OS 2.5683071 3.4975984
OS 2.5647708 3.4923059
OS 2.563529 3.486063
OS 2.5647708 3.4798201
OS 2.5683071 3.4745276
OS 2.5735996 3.4709913
OS 2.5798425 3.4697495
OS 2.5860854 3.4709913
OS 2.5913779 3.4745276
OS 2.5949142 3.4798201
OS 2.596156 3.486063
OS 2.5949142 3.4923059
OS 2.5913779 3.4975984
OS 2.5860854 3.5011347
OS 2.5798425 3.5023765
OE
OB 3.5298425 3.4973765 H
OS 3.5235996 3.4961347
OS 3.5183071 3.4925984
OS 3.5147708 3.4873059
OS 3.513529 3.481063
OS 3.5147708 3.4748201
OS 3.5183071 3.4695276
OS 3.5235996 3.4659913
OS 3.5298425 3.4647495
OS 3.5360854 3.4659913
OS 3.5413779 3.4695276
OS 3.5449142 3.4748201
OS 3.546156 3.481063
OS 3.5449142 3.4873059
OS 3.5413779 3.4925984
OS 3.5360854 3.4961347
OS 3.5298425 3.4973765
OE
OB 2.3898425 3.4973765 H
OS 2.3835996 3.4961347
OS 2.3783071 3.4925984
OS 2.3747708 3.4873059
OS 2.373529 3.481063
OS 2.3747708 3.4748201
OS 2.3783071 3.4695276
OS 2.3835996 3.4659913
OS 2.3898425 3.4647495
OS 2.3960854 3.4659913
OS 2.4013779 3.4695276
OS 2.4049142 3.4748201
OS 2.406156 3.481063
OS 2.4049142 3.4873059
OS 2.4013779 3.4925984
OS 2.3960854 3.4961347
OS 2.3898425 3.4973765
OE
OB 6.5098425 3.4723765 H
OS 6.5035996 3.4711347
OS 6.4983071 3.4675984
OS 6.4947708 3.4623059
OS 6.493529 3.456063
OS 6.4947708 3.4498201
OS 6.4983071 3.4445276
OS 6.5035996 3.4409913
OS 6.5098425 3.4397495
OS 6.5160854 3.4409913
OS 6.5213779 3.4445276
OS 6.5249142 3.4498201
OS 6.526156 3.456063
OS 6.5249142 3.4623059
OS 6.5213779 3.4675984
OS 6.5160854 3.4711347
OS 6.5098425 3.4723765
OE
OB 3.4368425 3.4733765 H
OS 3.4305996 3.4721347
OS 3.4253071 3.4685984
OS 3.4217708 3.4633059
OS 3.420529 3.457063
OS 3.4217708 3.4508201
OS 3.4253071 3.4455276
OS 3.4305996 3.4419913
OS 3.4368425 3.4407495
OS 3.4430854 3.4419913
OS 3.4483779 3.4455276
OS 3.4502305 3.4483003
OS 3.4506142 3.4484287
OS 3.4560152 3.4479578
OS 3.4583071 3.4445276
OS 3.4635996 3.4409913
OS 3.4698425 3.4397495
OS 3.4760854 3.4409913
OS 3.4813779 3.4445276
OS 3.4849142 3.4498201
OS 3.486156 3.456063
OS 3.4849142 3.4623059
OS 3.4813779 3.4675984
OS 3.4760854 3.4711347
OS 3.4698425 3.4723765
OS 3.4635996 3.4711347
OS 3.4583071 3.4675984
OS 3.4564545 3.4648257
OS 3.4560708 3.4646973
OS 3.4506698 3.4651682
OS 3.4483779 3.4685984
OS 3.4430854 3.4721347
OS 3.4368425 3.4733765
OE
OB 3.3588425 3.4643765 H
OS 3.3525996 3.4631347
OS 3.3473071 3.4595984
OS 3.3437708 3.4543059
OS 3.342529 3.448063
OS 3.3437708 3.4418201
OS 3.3473071 3.4365276
OS 3.3525996 3.4329913
OS 3.3588425 3.4317495
OS 3.3650854 3.4329913
OS 3.3703779 3.4365276
OS 3.3739142 3.4418201
OS 3.3741941 3.443227
OS 3.379292 3.443227
OS 3.3797708 3.4408201
OS 3.3833071 3.4355276
OS 3.3885996 3.4319913
OS 3.3948425 3.4307495
OS 3.4010854 3.4319913
OS 3.4063779 3.4355276
OS 3.4099142 3.4408201
OS 3.411156 3.447063
OS 3.4099142 3.4533059
OS 3.4063779 3.4585984
OS 3.4010854 3.4621347
OS 3.3948425 3.4633765
OS 3.3885996 3.4621347
OS 3.3833071 3.4585984
OS 3.3797708 3.4533059
OS 3.3794909 3.451899
OS 3.374393 3.451899
OS 3.3739142 3.4543059
OS 3.3703779 3.4595984
OS 3.3650854 3.4631347
OS 3.3588425 3.4643765
OE
OB 2.4223425 3.4673081 H
OS 2.4133837 3.4655261
OS 2.4057888 3.4604514
OS 2.4007141 3.4528565
OS 2.3989321 3.4438977
OS 2.4007141 3.4349389
OS 2.4057888 3.427344
OS 2.4133837 3.4222693
OS 2.4223425 3.4204873
OS 2.4313013 3.4222693
OS 2.4388962 3.427344
OS 2.4439709 3.4349389
OS 2.4457529 3.4438977
OS 2.4439709 3.4528565
OS 2.4388962 3.4604514
OS 2.4313013 3.4655261
OS 2.4223425 3.4673081
OE
OB 6.4798425 3.4423765 H
OS 6.4735996 3.4411347
OS 6.4683071 3.4375984
OS 6.4647708 3.4323059
OS 6.463529 3.426063
OS 6.4647708 3.4198201
OS 6.4683071 3.4145276
OS 6.4735996 3.4109913
OS 6.4798425 3.4097495
OS 6.4860854 3.4109913
OS 6.4913779 3.4145276
OS 6.4949142 3.4198201
OS 6.496156 3.426063
OS 6.4949142 3.4323059
OS 6.4913779 3.4375984
OS 6.4860854 3.4411347
OS 6.4798425 3.4423765
OE
OB 2.6348425 3.4223765 H
OS 2.6285996 3.4211347
OS 2.6233071 3.4175984
OS 2.6197708 3.4123059
OS 2.618529 3.406063
OS 2.6197708 3.3998201
OS 2.6233071 3.3945276
OS 2.6285996 3.3909913
OS 2.6348425 3.3897495
OS 2.6410854 3.3909913
OS 2.6463779 3.3945276
OS 2.6499142 3.3998201
OS 2.651156 3.406063
OS 2.6499142 3.4123059
OS 2.6463779 3.4175984
OS 2.6410854 3.4211347
OS 2.6348425 3.4223765
OE
OB 6.4475772 3.4123765 H
OS 6.4413343 3.4111347
OS 6.4360418 3.4075984
OS 6.4325055 3.4023059
OS 6.4312637 3.396063
OS 6.4325055 3.3898201
OS 6.4360418 3.3845276
OS 6.4413343 3.3809913
OS 6.4475772 3.3797495
OS 6.4538201 3.3809913
OS 6.4591126 3.3845276
OS 6.4626489 3.3898201
OS 6.4638907 3.396063
OS 6.4626489 3.4023059
OS 6.4591126 3.4075984
OS 6.4538201 3.4111347
OS 6.4475772 3.4123765
OE
OB 3.0688976 3.4119828 H
OS 3.0626547 3.410741
OS 3.0573622 3.4072047
OS 3.0538259 3.4019122
OS 3.0525841 3.3956693
OS 3.0538259 3.3894264
OS 3.0573622 3.3841339
OS 3.0626547 3.3805976
OS 3.0688976 3.3793558
OS 3.0751405 3.3805976
OS 3.080433 3.3841339
OS 3.0839693 3.3894264
OS 3.0852111 3.3956693
OS 3.0839693 3.4019122
OS 3.080433 3.4072047
OS 3.0751405 3.410741
OS 3.0688976 3.4119828
OE
OB 6.4098425 3.3873765 H
OS 6.4035996 3.3861347
OS 6.3983071 3.3825984
OS 6.3947708 3.3773059
OS 6.393529 3.371063
OS 6.3947708 3.3648201
OS 6.3983071 3.3595276
OS 6.4035996 3.3559913
OS 6.4098425 3.3547495
OS 6.4160854 3.3559913
OS 6.4213779 3.3595276
OS 6.4249142 3.3648201
OS 6.426156 3.371063
OS 6.4249142 3.3773059
OS 6.4213779 3.3825984
OS 6.4160854 3.3861347
OS 6.4098425 3.3873765
OE
OB 3.3028425 3.3603765 H
OS 3.2965996 3.3591347
OS 3.2913071 3.3555984
OS 3.2877708 3.3503059
OS 3.286529 3.344063
OS 3.2877708 3.3378201
OS 3.2913071 3.3325276
OS 3.2965996 3.3289913
OS 3.3028425 3.3277495
OS 3.3090854 3.3289913
OS 3.3143779 3.3325276
OS 3.3179142 3.3378201
OS 3.319156 3.344063
OS 3.3179142 3.3503059
OS 3.3143779 3.3555984
OS 3.3090854 3.3591347
OS 3.3028425 3.3603765
OE
OB 6.3547483 3.3474519 H
OS 6.3485054 3.3462101
OS 6.3432129 3.3426738
OS 6.3396766 3.3373813
OS 6.3384348 3.3311384
OS 6.3396766 3.3248955
OS 6.3432129 3.319603
OS 6.3485054 3.3160667
OS 6.3547483 3.3148249
OS 6.3609912 3.3160667
OS 6.3662837 3.319603
OS 6.36982 3.3248955
OS 6.3710618 3.3311384
OS 6.36982 3.3373813
OS 6.3662837 3.3426738
OS 6.3609912 3.3462101
OS 6.3547483 3.3474519
OE
OB 3.542865 3.335354 H
OS 3.5366221 3.3341122
OS 3.5313296 3.3305759
OS 3.5277933 3.3252834
OS 3.5265515 3.3190405
OS 3.5277933 3.3127976
OS 3.5313296 3.3075051
OS 3.5366221 3.3039688
OS 3.542865 3.302727
OS 3.5491079 3.3039688
OS 3.5544004 3.3075051
OS 3.5579367 3.3127976
OS 3.5591785 3.3190405
OS 3.5579367 3.3252834
OS 3.5544004 3.3305759
OS 3.5491079 3.3341122
OS 3.542865 3.335354
OE
OB 3.2636972 3.3202312 H
OS 3.2574543 3.3189894
OS 3.2521618 3.3154531
OS 3.2486255 3.3101606
OS 3.2473837 3.3039177
OS 3.2486255 3.2976748
OS 3.2521618 3.2923823
OS 3.2574543 3.288846
OS 3.2636972 3.2876042
OS 3.2699401 3.288846
OS 3.2752326 3.2923823
OS 3.2787689 3.2976748
OS 3.2800107 3.3039177
OS 3.2787689 3.3101606
OS 3.2752326 3.3154531
OS 3.2699401 3.3189894
OS 3.2636972 3.3202312
OE
OB 3.4918425 3.3133765 H
OS 3.4855996 3.3121347
OS 3.4803071 3.3085984
OS 3.4767708 3.3033059
OS 3.475529 3.297063
OS 3.4767708 3.2908201
OS 3.4803071 3.2855276
OS 3.4855996 3.2819913
OS 3.4918425 3.2807495
OS 3.4980854 3.2819913
OS 3.5033779 3.2855276
OS 3.5069142 3.2908201
OS 3.508156 3.297063
OS 3.5069142 3.3033059
OS 3.5033779 3.3085984
OS 3.4980854 3.3121347
OS 3.4918425 3.3133765
OE
OB 3.6538425 3.3093765 H
OS 3.6475996 3.3081347
OS 3.6423071 3.3045984
OS 3.6387708 3.2993059
OS 3.637529 3.293063
OS 3.6387708 3.2868201
OS 3.6423071 3.2815276
OS 3.6475996 3.2779913
OS 3.6538425 3.2767495
OS 3.6600854 3.2779913
OS 3.6653779 3.2815276
OS 3.6689142 3.2868201
OS 3.670156 3.293063
OS 3.6689142 3.2993059
OS 3.6653779 3.3045984
OS 3.6600854 3.3081347
OS 3.6538425 3.3093765
OE
OB 6.4448425 3.3073765 H
OS 6.4385996 3.3061347
OS 6.4333071 3.3025984
OS 6.4297708 3.2973059
OS 6.428529 3.291063
OS 6.4297708 3.2848201
OS 6.4333071 3.2795276
OS 6.4385996 3.2759913
OS 6.4448425 3.2747495
OS 6.4510854 3.2759913
OS 6.4563779 3.2795276
OS 6.4599142 3.2848201
OS 6.461156 3.291063
OS 6.4599142 3.2973059
OS 6.4563779 3.3025984
OS 6.4510854 3.3061347
OS 6.4448425 3.3073765
OE
OB 2.5908425 3.3043765 H
OS 2.5845996 3.3031347
OS 2.5793071 3.2995984
OS 2.5757708 3.2943059
OS 2.574529 3.288063
OS 2.5757708 3.2818201
OS 2.5793071 3.2765276
OS 2.5845996 3.2729913
OS 2.5908425 3.2717495
OS 2.5970854 3.2729913
OS 2.6023779 3.2765276
OS 2.6059142 3.2818201
OS 2.607156 3.288063
OS 2.6059142 3.2943059
OS 2.6023779 3.2995984
OS 2.5970854 3.3031347
OS 2.5908425 3.3043765
OE
OB 3.3748425 3.2893765 H
OS 3.3685996 3.2881347
OS 3.3633071 3.2845984
OS 3.3597708 3.2793059
OS 3.358529 3.273063
OS 3.3597708 3.2668201
OS 3.3633071 3.2615276
OS 3.3685996 3.2579913
OS 3.3748425 3.2567495
OS 3.3810854 3.2579913
OS 3.3863779 3.2615276
OS 3.3899142 3.2668201
OS 3.391156 3.273063
OS 3.3899142 3.2793059
OS 3.3863779 3.2845984
OS 3.3810854 3.2881347
OS 3.3748425 3.2893765
OE
OB 6.3348425 3.2823765 H
OS 6.3285996 3.2811347
OS 6.3233071 3.2775984
OS 6.3197708 3.2723059
OS 6.318529 3.266063
OS 6.3197708 3.2598201
OS 6.3233071 3.2545276
OS 6.3285996 3.2509913
OS 6.3348425 3.2497495
OS 6.3410854 3.2509913
OS 6.3463779 3.2545276
OS 6.3499142 3.2598201
OS 6.351156 3.266063
OS 6.3499142 3.2723059
OS 6.3463779 3.2775984
OS 6.3410854 3.2811347
OS 6.3348425 3.2823765
OE
OB 3.7448425 3.2773765 H
OS 3.7385996 3.2761347
OS 3.7333071 3.2725984
OS 3.7297708 3.2673059
OS 3.728529 3.261063
OS 3.7297708 3.2548201
OS 3.7333071 3.2495276
OS 3.7385996 3.2459913
OS 3.7448425 3.2447495
OS 3.7510854 3.2459913
OS 3.7563779 3.2495276
OS 3.7599142 3.2548201
OS 3.761156 3.261063
OS 3.7599142 3.2673059
OS 3.7563779 3.2725984
OS 3.7510854 3.2761347
OS 3.7448425 3.2773765
OE
OB 2.2598425 3.2773765 H
OS 2.2535996 3.2761347
OS 2.2483071 3.2725984
OS 2.2447708 3.2673059
OS 2.243529 3.261063
OS 2.2447708 3.2548201
OS 2.2483071 3.2495276
OS 2.2535996 3.2459913
OS 2.2598425 3.2447495
OS 2.2660854 3.2459913
OS 2.2713779 3.2495276
OS 2.2749142 3.2548201
OS 2.276156 3.261063
OS 2.2749142 3.2673059
OS 2.2713779 3.2725984
OS 2.2660854 3.2761347
OS 2.2598425 3.2773765
OE
OB 3.2308425 3.2513765 H
OS 3.2245996 3.2501347
OS 3.2193071 3.2465984
OS 3.2157708 3.2413059
OS 3.214529 3.235063
OS 3.2157708 3.2288201
OS 3.2193071 3.2235276
OS 3.2245996 3.2199913
OS 3.2308425 3.2187495
OS 3.2370854 3.2199913
OS 3.2423779 3.2235276
OS 3.2459142 3.2288201
OS 3.247156 3.235063
OS 3.2459142 3.2413059
OS 3.2423779 3.2465984
OS 3.2370854 3.2501347
OS 3.2308425 3.2513765
OE
OB 6.2824161 3.2423765 H
OS 6.2761732 3.2411347
OS 6.2708807 3.2375984
OS 6.2673444 3.2323059
OS 6.2661026 3.226063
OS 6.2673444 3.2198201
OS 6.2708807 3.2145276
OS 6.2761732 3.2109913
OS 6.2824161 3.2097495
OS 6.288659 3.2109913
OS 6.2939515 3.2145276
OS 6.2974878 3.2198201
OS 6.2987296 3.226063
OS 6.2974878 3.2323059
OS 6.2939515 3.2375984
OS 6.288659 3.2411347
OS 6.2824161 3.2423765
OE
OB 3.8068425 3.2513765 H
OS 3.8005996 3.2501347
OS 3.7953071 3.2465984
OS 3.7917708 3.2413059
OS 3.790529 3.235063
OS 3.7917708 3.2288201
OS 3.7953071 3.2235276
OS 3.7975621 3.2220209
OS 3.7965063 3.2167129
OS 3.7935996 3.2161347
OS 3.7883071 3.2125984
OS 3.7847708 3.2073059
OS 3.783529 3.201063
OS 3.7847708 3.1948201
OS 3.7883071 3.1895276
OS 3.7935996 3.1859913
OS 3.7998425 3.1847495
OS 3.8060854 3.1859913
OS 3.8113779 3.1895276
OS 3.8149142 3.1948201
OS 3.816156 3.201063
OS 3.8149142 3.2073059
OS 3.8113779 3.2125984
OS 3.8091229 3.2141051
OS 3.8101787 3.2194131
OS 3.8130854 3.2199913
OS 3.8183779 3.2235276
OS 3.8219142 3.2288201
OS 3.823156 3.235063
OS 3.8219142 3.2413059
OS 3.8183779 3.2465984
OS 3.8130854 3.2501347
OS 3.8068425 3.2513765
OE
OB 2.2058425 3.2163765 H
OS 2.1995996 3.2151347
OS 2.1943071 3.2115984
OS 2.1907708 3.2063059
OS 2.189529 3.200063
OS 2.1907708 3.1938201
OS 2.1943071 3.1885276
OS 2.1995996 3.1849913
OS 2.2058425 3.1837495
OS 2.2120854 3.1849913
OS 2.2173779 3.1885276
OS 2.2209142 3.1938201
OS 2.222156 3.200063
OS 2.2209142 3.2063059
OS 2.2173779 3.2115984
OS 2.2120854 3.2151347
OS 2.2058425 3.2163765
OE
OB 2.4223425 3.2631033 H
OS 2.4133837 3.2613213
OS 2.4057888 3.2562466
OS 2.4007141 3.2486517
OS 2.3989321 3.2396929
OS 2.4007141 3.2307341
OS 2.4057888 3.2231392
OS 2.4098502 3.2204255
OS 2.4087944 3.2151175
OS 2.4078122 3.2149221
OS 2.4025197 3.2113858
OS 2.3989834 3.2060933
OS 2.3977416 3.1998504
OS 2.3989834 3.1936075
OS 2.4025197 3.188315
OS 2.4078122 3.1847787
OS 2.4140551 3.1835369
OS 2.420298 3.1847787
OS 2.4255905 3.188315
OS 2.4291268 3.1936075
OS 2.4303686 3.1998504
OS 2.4291268 3.2060933
OS 2.4255905 3.2113858
OS 2.4250776 3.2117285
OS 2.4261334 3.2170365
OS 2.4313013 3.2180645
OS 2.4388962 3.2231392
OS 2.4439709 3.2307341
OS 2.4457529 3.2396929
OS 2.4439709 3.2486517
OS 2.4388962 3.2562466
OS 2.4313013 3.2613213
OS 2.4223425 3.2631033
OE
OB 6.3094161 3.2153765 H
OS 6.3031732 3.2141347
OS 6.2978807 3.2105984
OS 6.2943444 3.2053059
OS 6.2931026 3.199063
OS 6.2943444 3.1928201
OS 6.2978807 3.1875276
OS 6.3031732 3.1839913
OS 6.3094161 3.1827495
OS 6.315659 3.1839913
OS 6.3209515 3.1875276
OS 6.3244878 3.1928201
OS 6.3257296 3.199063
OS 6.3244878 3.2053059
OS 6.3209515 3.2105984
OS 6.315659 3.2141347
OS 6.3094161 3.2153765
OE
OB 6.4398425 3.2073765 H
OS 6.4335996 3.2061347
OS 6.4283071 3.2025984
OS 6.4247708 3.1973059
OS 6.423529 3.191063
OS 6.4247708 3.1848201
OS 6.4283071 3.1795276
OS 6.4335996 3.1759913
OS 6.4398425 3.1747495
OS 6.4460854 3.1759913
OS 6.4513779 3.1795276
OS 6.4549142 3.1848201
OS 6.456156 3.191063
OS 6.4549142 3.1973059
OS 6.4513779 3.2025984
OS 6.4460854 3.2061347
OS 6.4398425 3.2073765
OE
OB 3.1889764 3.2033214 H
OS 3.1827335 3.2020796
OS 3.177441 3.1985433
OS 3.1739047 3.1932508
OS 3.1726629 3.1870079
OS 3.1739047 3.180765
OS 3.177441 3.1754725
OS 3.1827335 3.1719362
OS 3.1889764 3.1706944
OS 3.1952193 3.1719362
OS 3.2005118 3.1754725
OS 3.2040481 3.180765
OS 3.2052899 3.1870079
OS 3.2040481 3.1932508
OS 3.2005118 3.1985433
OS 3.1952193 3.2020796
OS 3.1889764 3.2033214
OE
OB 2.5918425 3.202534 H
OS 2.5855996 3.2012922
OS 2.5803071 3.1977559
OS 2.5767708 3.1924634
OS 2.575529 3.1862205
OS 2.5767708 3.1799776
OS 2.5803071 3.1746851
OS 2.5855996 3.1711488
OS 2.5918425 3.169907
OS 2.5980854 3.1711488
OS 2.6033779 3.1746851
OS 2.6069142 3.1799776
OS 2.608156 3.1862205
OS 2.6069142 3.1924634
OS 2.6033779 3.1977559
OS 2.5980854 3.2012922
OS 2.5918425 3.202534
OE
OB 2.462374 3.1885576 H
OS 2.4561311 3.1873158
OS 2.4508386 3.1837795
OS 2.4473023 3.178487
OS 2.4460605 3.1722441
OS 2.4473023 3.1660012
OS 2.4508386 3.1607087
OS 2.4561311 3.1571724
OS 2.462374 3.1559306
OS 2.4686169 3.1571724
OS 2.4739094 3.1607087
OS 2.4774457 3.1660012
OS 2.4786875 3.1722441
OS 2.4774457 3.178487
OS 2.4739094 3.1837795
OS 2.4686169 3.1873158
OS 2.462374 3.1885576
OE
OB 6.3398425 3.1673765 H
OS 6.3335996 3.1661347
OS 6.3283071 3.1625984
OS 6.3247708 3.1573059
OS 6.323529 3.151063
OS 6.3247708 3.1448201
OS 6.3283071 3.1395276
OS 6.3335996 3.1359913
OS 6.3398425 3.1347495
OS 6.3460854 3.1359913
OS 6.3513779 3.1395276
OS 6.3549142 3.1448201
OS 6.356156 3.151063
OS 6.3549142 3.1573059
OS 6.3513779 3.1625984
OS 6.3460854 3.1661347
OS 6.3398425 3.1673765
OE
OB 3.8298425 3.1923765 H
OS 3.8235996 3.1911347
OS 3.8183071 3.1875984
OS 3.8147708 3.1823059
OS 3.813529 3.176063
OS 3.8147708 3.1698201
OS 3.8183071 3.1645276
OS 3.8235996 3.1609913
OS 3.8298425 3.1597495
OS 3.8360854 3.1609913
OS 3.8363282 3.1611536
OS 3.8399331 3.1575487
OS 3.8397708 3.1573059
OS 3.838529 3.151063
OS 3.8397708 3.1448201
OS 3.8433071 3.1395276
OS 3.8485996 3.1359913
OS 3.8548425 3.1347495
OS 3.8610854 3.1359913
OS 3.8663779 3.1395276
OS 3.8699142 3.1448201
OS 3.871156 3.151063
OS 3.8699142 3.1573059
OS 3.8663779 3.1625984
OS 3.8610854 3.1661347
OS 3.8548425 3.1673765
OS 3.8485996 3.1661347
OS 3.8483568 3.1659724
OS 3.8447519 3.1695773
OS 3.8449142 3.1698201
OS 3.846156 3.176063
OS 3.8449142 3.1823059
OS 3.8413779 3.1875984
OS 3.8360854 3.1911347
OS 3.8298425 3.1923765
OE
OB 1.4598425 3.1633765 H
OS 1.4535996 3.1621347
OS 1.4483071 3.1585984
OS 1.4447708 3.1533059
OS 1.443529 3.147063
OS 1.4447708 3.1408201
OS 1.4483071 3.1355276
OS 1.4535996 3.1319913
OS 1.4598425 3.1307495
OS 1.4660854 3.1319913
OS 1.4713779 3.1355276
OS 1.4749142 3.1408201
OS 1.476156 3.147063
OS 1.4749142 3.1533059
OS 1.4713779 3.1585984
OS 1.4660854 3.1621347
OS 1.4598425 3.1633765
OE
OB 3.2755905 3.1580458 H
OS 3.2693476 3.156804
OS 3.2640551 3.1532677
OS 3.2605188 3.1479752
OS 3.259277 3.1417323
OS 3.2605188 3.1354894
OS 3.2640551 3.1301969
OS 3.2693476 3.1266606
OS 3.2755905 3.1254188
OS 3.2818334 3.1266606
OS 3.2871259 3.1301969
OS 3.2906622 3.1354894
OS 3.291904 3.1417323
OS 3.2906622 3.1479752
OS 3.2871259 3.1532677
OS 3.2818334 3.156804
OS 3.2755905 3.1580458
OE
OB 6.3048425 3.1373765 H
OS 6.2985996 3.1361347
OS 6.2933071 3.1325984
OS 6.2897708 3.1273059
OS 6.288529 3.121063
OS 6.2897708 3.1148201
OS 6.2933071 3.1095276
OS 6.2985996 3.1059913
OS 6.3048425 3.1047495
OS 6.3110854 3.1059913
OS 6.3163779 3.1095276
OS 6.3199142 3.1148201
OS 6.321156 3.121063
OS 6.3199142 3.1273059
OS 6.3163779 3.1325984
OS 6.3110854 3.1361347
OS 6.3048425 3.1373765
OE
OB 3.9398425 3.1373765 H
OS 3.9335996 3.1361347
OS 3.9283071 3.1325984
OS 3.9247708 3.1273059
OS 3.923529 3.121063
OS 3.9247708 3.1148201
OS 3.9283071 3.1095276
OS 3.9335996 3.1059913
OS 3.9398425 3.1047495
OS 3.9460854 3.1059913
OS 3.9513779 3.1095276
OS 3.9549142 3.1148201
OS 3.956156 3.121063
OS 3.9549142 3.1273059
OS 3.9513779 3.1325984
OS 3.9460854 3.1361347
OS 3.9398425 3.1373765
OE
OB 3.4918425 3.1193765 H
OS 3.4855996 3.1181347
OS 3.4803071 3.1145984
OS 3.4767708 3.1093059
OS 3.475529 3.103063
OS 3.4767708 3.0968201
OS 3.4803071 3.0915276
OS 3.4855996 3.0879913
OS 3.4918425 3.0867495
OS 3.4980854 3.0879913
OS 3.5033779 3.0915276
OS 3.5069142 3.0968201
OS 3.508156 3.103063
OS 3.5069142 3.1093059
OS 3.5033779 3.1145984
OS 3.4980854 3.1181347
OS 3.4918425 3.1193765
OE
OB 2.4187174 3.1348201 H
OS 2.4124745 3.1335783
OS 2.407182 3.130042
OS 2.4036457 3.1247495
OS 2.4024039 3.1185066
OS 2.4036457 3.1122637
OS 2.407182 3.1069712
OS 2.4081253 3.1063409
OS 2.4081253 3.1003275
OS 2.4057888 3.0987663
OS 2.4007141 3.0911714
OS 2.3989321 3.0822126
OS 2.4007141 3.0732538
OS 2.4057888 3.0656589
OS 2.4133837 3.0605842
OS 2.4223425 3.0588022
OS 2.4313013 3.0605842
OS 2.4388962 3.0656589
OS 2.4439709 3.0732538
OS 2.4457529 3.0822126
OS 2.4439709 3.0911714
OS 2.4388962 3.0987663
OS 2.4329346 3.1027496
OS 2.4313655 3.1052197
OS 2.4315364 3.1088922
OS 2.4337891 3.1122637
OS 2.4350309 3.1185066
OS 2.4337891 3.1247495
OS 2.4302528 3.130042
OS 2.4249603 3.1335783
OS 2.4187174 3.1348201
OE
OB 3.3688425 3.0663765 H
OS 3.3625996 3.0651347
OS 3.3573071 3.0615984
OS 3.3537708 3.0563059
OS 3.352529 3.050063
OS 3.3537708 3.0438201
OS 3.3573071 3.0385276
OS 3.3625996 3.0349913
OS 3.3688425 3.0337495
OS 3.3750854 3.0349913
OS 3.3803779 3.0385276
OS 3.3839142 3.0438201
OS 3.385156 3.050063
OS 3.3839142 3.0563059
OS 3.3803779 3.0615984
OS 3.3750854 3.0651347
OS 3.3688425 3.0663765
OE
OB 3.3448425 3.0123765 H
OS 3.3385996 3.0111347
OS 3.3333071 3.0075984
OS 3.3297708 3.0023059
OS 3.328529 2.996063
OS 3.3297708 2.9898201
OS 3.3333071 2.9845276
OS 3.3385996 2.9809913
OS 3.3448425 2.9797495
OS 3.3510854 2.9809913
OS 3.3563779 2.9845276
OS 3.3599142 2.9898201
OS 3.361156 2.996063
OS 3.3599142 3.0023059
OS 3.3563779 3.0075984
OS 3.3510854 3.0111347
OS 3.3448425 3.0123765
OE
OB 3.1978425 2.9863765 H
OS 3.1915996 2.9851347
OS 3.1863071 2.9815984
OS 3.1827708 2.9763059
OS 3.181529 2.970063
OS 3.1827708 2.9638201
OS 3.1863071 2.9585276
OS 3.1915996 2.9549913
OS 3.1978425 2.9537495
OS 3.2040854 2.9549913
OS 3.2093779 2.9585276
OS 3.2129142 2.9638201
OS 3.214156 2.970063
OS 3.2129142 2.9763059
OS 3.2093779 2.9815984
OS 3.2040854 2.9851347
OS 3.1978425 2.9863765
OE
OB 4.7942913 2.8243844 H
OS 4.7880484 2.8231426
OS 4.7827559 2.8196063
OS 4.7792196 2.8143138
OS 4.7779778 2.8080709
OS 4.7792196 2.801828
OS 4.7827559 2.7965355
OS 4.7880484 2.7929992
OS 4.7942913 2.7917574
OS 4.8005342 2.7929992
OS 4.8058267 2.7965355
OS 4.809363 2.801828
OS 4.8106048 2.8080709
OS 4.809363 2.8143138
OS 4.8058267 2.8196063
OS 4.8005342 2.8231426
OS 4.7942913 2.8243844
OE
OB 4.5036614 2.8061954 H
OS 4.4974185 2.8049536
OS 4.492126 2.8014173
OS 4.4885897 2.7961248
OS 4.4873479 2.7898819
OS 4.4885897 2.783639
OS 4.492126 2.7783465
OS 4.4974185 2.7748102
OS 4.5036614 2.7735684
OS 4.5099043 2.7748102
OS 4.5151968 2.7783465
OS 4.5187331 2.783639
OS 4.5199749 2.7898819
OS 4.5187331 2.7961248
OS 4.5151968 2.8014173
OS 4.5099043 2.8049536
OS 4.5036614 2.8061954
OE
OB 2.1468425 2.7693765 H
OS 2.1405996 2.7681347
OS 2.1353071 2.7645984
OS 2.1317708 2.7593059
OS 2.130529 2.753063
OS 2.1317708 2.7468201
OS 2.1353071 2.7415276
OS 2.1405996 2.7379913
OS 2.1468425 2.7367495
OS 2.1530854 2.7379913
OS 2.1583779 2.7415276
OS 2.1619142 2.7468201
OS 2.163156 2.753063
OS 2.1619142 2.7593059
OS 2.1583779 2.7645984
OS 2.1530854 2.7681347
OS 2.1468425 2.7693765
OE
OB 2.6929134 2.7377702 H
OS 2.6866705 2.7365284
OS 2.681378 2.7329921
OS 2.6778417 2.7276996
OS 2.6765999 2.7214567
OS 2.6778417 2.7152138
OS 2.681378 2.7099213
OS 2.6866705 2.706385
OS 2.6929134 2.7051432
OS 2.6991563 2.706385
OS 2.7044488 2.7099213
OS 2.7079851 2.7152138
OS 2.7092269 2.7214567
OS 2.7079851 2.7276996
OS 2.7044488 2.7329921
OS 2.6991563 2.7365284
OS 2.6929134 2.7377702
OE
OB 2.394685 2.7367859 H
OS 2.3884421 2.7355441
OS 2.3831496 2.7320078
OS 2.3796133 2.7267153
OS 2.3783715 2.7204724
OS 2.3796133 2.7142295
OS 2.3831496 2.708937
OS 2.3884421 2.7054007
OS 2.394685 2.7041589
OS 2.4009279 2.7054007
OS 2.4062204 2.708937
OS 2.4097567 2.7142295
OS 2.4109985 2.7204724
OS 2.4097567 2.7267153
OS 2.4062204 2.7320078
OS 2.4009279 2.7355441
OS 2.394685 2.7367859
OE
OB 2.4948425 2.7123765 H
OS 2.4885996 2.7111347
OS 2.4833071 2.7075984
OS 2.4797708 2.7023059
OS 2.478529 2.696063
OS 2.4797708 2.6898201
OS 2.4833071 2.6845276
OS 2.4883212 2.6811773
OS 2.4885995 2.6790399
OS 2.4885995 2.6780861
OS 2.4883212 2.6759487
OS 2.4833071 2.6725984
OS 2.4797708 2.6673059
OS 2.478529 2.661063
OS 2.4797708 2.6548201
OS 2.4833071 2.6495276
OS 2.4885996 2.6459913
OS 2.4948425 2.6447495
OS 2.5010854 2.6459913
OS 2.5063779 2.6495276
OS 2.5099142 2.6548201
OS 2.511156 2.661063
OS 2.5099142 2.6673059
OS 2.5063779 2.6725984
OS 2.5013638 2.6759487
OS 2.5010855 2.6780861
OS 2.5010855 2.6790399
OS 2.5013638 2.6811773
OS 2.5063779 2.6845276
OS 2.5099142 2.6898201
OS 2.511156 2.696063
OS 2.5099142 2.7023059
OS 2.5063779 2.7075984
OS 2.5010854 2.7111347
OS 2.4948425 2.7123765
OE
OB 2.9588425 2.6373765 H
OS 2.9525996 2.6361347
OS 2.9473071 2.6325984
OS 2.9437708 2.6273059
OS 2.942529 2.621063
OS 2.9437708 2.6148201
OS 2.9473071 2.6095276
OS 2.9525996 2.6059913
OS 2.9588425 2.6047495
OS 2.9650854 2.6059913
OS 2.9703779 2.6095276
OS 2.9739142 2.6148201
OS 2.975156 2.621063
OS 2.9739142 2.6273059
OS 2.9703779 2.6325984
OS 2.9650854 2.6361347
OS 2.9588425 2.6373765
OE
OB 2.4291925 2.6373765 H
OS 2.4229496 2.6361347
OS 2.4176571 2.6325984
OS 2.4141208 2.6273059
OS 2.412879 2.621063
OS 2.4141208 2.6148201
OS 2.4176571 2.6095276
OS 2.4229496 2.6059913
OS 2.4291925 2.6047495
OS 2.4354354 2.6059913
OS 2.4407279 2.6095276
OS 2.4442642 2.6148201
OS 2.445506 2.621063
OS 2.4442642 2.6273059
OS 2.4407279 2.6325984
OS 2.4354354 2.6361347
OS 2.4291925 2.6373765
OE
OB 2.2523425 2.6298765 H
OS 2.2460996 2.6286347
OS 2.2408071 2.6250984
OS 2.2372708 2.6198059
OS 2.236029 2.613563
OS 2.2372708 2.6073201
OS 2.239748 2.6036127
OS 2.2364566 2.5995388
OS 2.2317425 2.6004765
OS 2.2254996 2.5992347
OS 2.2202071 2.5956984
OS 2.2166708 2.5904059
OS 2.215429 2.584163
OS 2.2166708 2.5779201
OS 2.2202071 2.5726276
OS 2.2254996 2.5690913
OS 2.2317425 2.5678495
OS 2.2379854 2.5690913
OS 2.2432779 2.5726276
OS 2.2468142 2.5779201
OS 2.248056 2.584163
OS 2.2468142 2.5904059
OS 2.244337 2.5941133
OS 2.2476284 2.5981872
OS 2.2523425 2.5972495
OS 2.2585854 2.5984913
OS 2.2638779 2.6020276
OS 2.2674142 2.6073201
OS 2.268656 2.613563
OS 2.2674142 2.6198059
OS 2.2638779 2.6250984
OS 2.2585854 2.6286347
OS 2.2523425 2.6298765
OE
OB 2.8218425 2.6173765 H
OS 2.8155996 2.6161347
OS 2.8103071 2.6125984
OS 2.8067708 2.6073059
OS 2.805529 2.601063
OS 2.8067708 2.5948201
OS 2.8103071 2.5895276
OS 2.8155996 2.5859913
OS 2.8218425 2.5847495
OS 2.8280854 2.5859913
OS 2.8333779 2.5895276
OS 2.8369142 2.5948201
OS 2.838156 2.601063
OS 2.8369142 2.6073059
OS 2.8333779 2.6125984
OS 2.8280854 2.6161347
OS 2.8218425 2.6173765
OE
OB 3.6238425 2.6033765 H
OS 3.6175996 2.6021347
OS 3.6123071 2.5985984
OS 3.6087708 2.5933059
OS 3.607529 2.587063
OS 3.6087708 2.5808201
OS 3.6123071 2.5755276
OS 3.6175996 2.5719913
OS 3.6238425 2.5707495
OS 3.6300854 2.5719913
OS 3.6353779 2.5755276
OS 3.6389142 2.5808201
OS 3.640156 2.587063
OS 3.6389142 2.5933059
OS 3.6353779 2.5985984
OS 3.6300854 2.6021347
OS 3.6238425 2.6033765
OE
OB 4.2986248 2.6412356 H
OS 4.2867469 2.6396718
OS 4.2756785 2.6350872
OS 4.2661738 2.627794
OS 4.2588806 2.6182893
OS 4.254296 2.6072209
OS 4.2527322 2.595343
OS 4.254296 2.5834651
OS 4.2588806 2.5723967
OS 4.2661738 2.562892
OS 4.2756785 2.5555988
OS 4.2867469 2.5510142
OS 4.2986248 2.5494504
OS 4.3105027 2.5510142
OS 4.3215711 2.5555988
OS 4.3310758 2.562892
OS 4.338369 2.5723967
OS 4.3429536 2.5834651
OS 4.3445174 2.595343
OS 4.3429536 2.6072209
OS 4.338369 2.6182893
OS 4.3310758 2.627794
OS 4.3215711 2.6350872
OS 4.3105027 2.6396718
OS 4.2986248 2.6412356
OE
OB 4.1805146 2.6412356 H
OS 4.1686367 2.6396718
OS 4.1575683 2.6350872
OS 4.1480636 2.627794
OS 4.1407704 2.6182893
OS 4.1361858 2.6072209
OS 4.134622 2.595343
OS 4.1361858 2.5834651
OS 4.1407704 2.5723967
OS 4.1480636 2.562892
OS 4.1575683 2.5555988
OS 4.1686367 2.5510142
OS 4.1805146 2.5494504
OS 4.1923925 2.5510142
OS 4.2034609 2.5555988
OS 4.2129656 2.562892
OS 4.2202588 2.5723967
OS 4.2248434 2.5834651
OS 4.2264072 2.595343
OS 4.2248434 2.6072209
OS 4.2202588 2.6182893
OS 4.2129656 2.627794
OS 4.2034609 2.6350872
OS 4.1923925 2.6396718
OS 4.1805146 2.6412356
OE
OB 4.0624044 2.6412356 H
OS 4.0505265 2.6396718
OS 4.0394581 2.6350872
OS 4.0299534 2.627794
OS 4.0226602 2.6182893
OS 4.0180756 2.6072209
OS 4.0165118 2.595343
OS 4.0180756 2.5834651
OS 4.0226602 2.5723967
OS 4.0299534 2.562892
OS 4.0394581 2.5555988
OS 4.0505265 2.5510142
OS 4.0624044 2.5494504
OS 4.0742823 2.5510142
OS 4.0853507 2.5555988
OS 4.0948554 2.562892
OS 4.1021486 2.5723967
OS 4.1067332 2.5834651
OS 4.108297 2.595343
OS 4.1067332 2.6072209
OS 4.1021486 2.6182893
OS 4.0948554 2.627794
OS 4.0853507 2.6350872
OS 4.0742823 2.6396718
OS 4.0624044 2.6412356
OE
OB 6.2848425 2.5173765 H
OS 6.2785996 2.5161347
OS 6.2733071 2.5125984
OS 6.2697708 2.5073059
OS 6.268529 2.501063
OS 6.2697708 2.4948201
OS 6.2733071 2.4895276
OS 6.2785996 2.4859913
OS 6.2848425 2.4847495
OS 6.2910854 2.4859913
OS 6.2963779 2.4895276
OS 6.2999142 2.4948201
OS 6.301156 2.501063
OS 6.2999142 2.5073059
OS 6.2963779 2.5125984
OS 6.2910854 2.5161347
OS 6.2848425 2.5173765
OE
OB 1.0208425 2.4973765 H
OS 1.0145996 2.4961347
OS 1.0093071 2.4925984
OS 1.0057708 2.4873059
OS 1.004529 2.481063
OS 1.0057708 2.4748201
OS 1.0093071 2.4695276
OS 1.0145996 2.4659913
OS 1.0208425 2.4647495
OS 1.0270854 2.4659913
OS 1.0323779 2.4695276
OS 1.0359142 2.4748201
OS 1.037156 2.481063
OS 1.0359142 2.4873059
OS 1.0323779 2.4925984
OS 1.0270854 2.4961347
OS 1.0208425 2.4973765
OE
OB 2.6248425 2.4773765 H
OS 2.6185996 2.4761347
OS 2.6133071 2.4725984
OS 2.6097708 2.4673059
OS 2.608529 2.461063
OS 2.6097708 2.4548201
OS 2.6099331 2.4545773
OS 2.6063282 2.4509724
OS 2.6060854 2.4511347
OS 2.5998425 2.4523765
OS 2.5935996 2.4511347
OS 2.5883071 2.4475984
OS 2.5847708 2.4423059
OS 2.583529 2.436063
OS 2.5844621 2.4313719
OS 2.583986 2.4305231
OS 2.5813824 2.4279195
OS 2.5805336 2.4274434
OS 2.5758425 2.4283765
OS 2.5695996 2.4271347
OS 2.5643071 2.4235984
OS 2.5607708 2.4183059
OS 2.559529 2.412063
OS 2.5607708 2.4058201
OS 2.5643071 2.4005276
OS 2.5695996 2.3969913
OS 2.5758425 2.3957495
OS 2.5820854 2.3969913
OS 2.5873779 2.4005276
OS 2.5909142 2.4058201
OS 2.592156 2.412063
OS 2.5912229 2.4167541
OS 2.591699 2.4176029
OS 2.5943026 2.4202065
OS 2.5951514 2.4206826
OS 2.5998425 2.4197495
OS 2.6060854 2.4209913
OS 2.6113779 2.4245276
OS 2.6149142 2.4298201
OS 2.616156 2.436063
OS 2.6149142 2.4423059
OS 2.6147519 2.4425487
OS 2.6183568 2.4461536
OS 2.6185996 2.4459913
OS 2.6248425 2.4447495
OS 2.6310854 2.4459913
OS 2.6363779 2.4495276
OS 2.6399142 2.4548201
OS 2.641156 2.461063
OS 2.6399142 2.4673059
OS 2.6363779 2.4725984
OS 2.6310854 2.4761347
OS 2.6248425 2.4773765
OE
OB 2.2720325 2.4801865 H
OS 2.2657896 2.4789447
OS 2.2604971 2.4754084
OS 2.2569608 2.4701159
OS 2.255719 2.463873
OS 2.2569608 2.4576301
OS 2.2604971 2.4523376
OS 2.2657896 2.4488013
OS 2.2720325 2.4475595
OS 2.2782754 2.4488013
OS 2.2835679 2.4523376
OS 2.2871042 2.4576301
OS 2.288346 2.463873
OS 2.2871042 2.4701159
OS 2.2835679 2.4754084
OS 2.2782754 2.4789447
OS 2.2720325 2.4801865
OE
OB 2.5258425 2.4793765 H
OS 2.5195996 2.4781347
OS 2.5143071 2.4745984
OS 2.5107708 2.4693059
OS 2.509529 2.463063
OS 2.5107708 2.4568201
OS 2.5143071 2.4515276
OS 2.5195996 2.4479913
OS 2.5258425 2.4467495
OS 2.5320854 2.4479913
OS 2.5373779 2.4515276
OS 2.5409142 2.4568201
OS 2.542156 2.463063
OS 2.5409142 2.4693059
OS 2.5373779 2.4745984
OS 2.5320854 2.4781347
OS 2.5258425 2.4793765
OE
OB 5.5781524 2.5349364 H
OS 5.5662745 2.5333726
OS 5.5552061 2.528788
OS 5.5457014 2.5214948
OS 5.5384082 2.5119901
OS 5.5338236 2.5009217
OS 5.5322598 2.4890438
OS 5.5338236 2.4771659
OS 5.5384082 2.4660975
OS 5.5457014 2.4565928
OS 5.5552061 2.4492996
OS 5.5662745 2.444715
OS 5.5781524 2.4431512
OS 5.5900303 2.444715
OS 5.6010987 2.4492996
OS 5.6106034 2.4565928
OS 5.6178966 2.4660975
OS 5.6224812 2.4771659
OS 5.624045 2.4890438
OS 5.6224812 2.5009217
OS 5.6178966 2.5119901
OS 5.6106034 2.5214948
OS 5.6010987 2.528788
OS 5.5900303 2.5333726
OS 5.5781524 2.5349364
OE
OB 2.9488425 2.4723765 H
OS 2.9425996 2.4711347
OS 2.9373071 2.4675984
OS 2.9337708 2.4623059
OS 2.932529 2.456063
OS 2.9337708 2.4498201
OS 2.9373071 2.4445276
OS 2.9425996 2.4409913
OS 2.9488425 2.4397495
OS 2.9550854 2.4409913
OS 2.9603779 2.4445276
OS 2.9639142 2.4498201
OS 2.965156 2.456063
OS 2.9639142 2.4623059
OS 2.9603779 2.4675984
OS 2.9550854 2.4711347
OS 2.9488425 2.4723765
OE
OB 2.9905325 2.4577319 H
OS 2.9831854 2.4562705
OS 2.9769568 2.4521087
OS 2.972795 2.4458801
OS 2.9713336 2.438533
OS 2.972795 2.4311859
OS 2.9769568 2.4249573
OS 2.9831854 2.4207955
OS 2.9905325 2.4193341
OS 2.9978796 2.4207955
OS 3.0041082 2.4249573
OS 3.00827 2.4311859
OS 3.0097314 2.438533
OS 3.00827 2.4458801
OS 3.0041082 2.4521087
OS 2.9978796 2.4562705
OS 2.9905325 2.4577319
OE
OB 2.2031325 2.4577319 H
OS 2.1957854 2.4562705
OS 2.1895568 2.4521087
OS 2.185395 2.4458801
OS 2.1839336 2.438533
OS 2.185395 2.4311859
OS 2.1895568 2.4249573
OS 2.1957854 2.4207955
OS 2.2031325 2.4193341
OS 2.2104796 2.4207955
OS 2.2167082 2.4249573
OS 2.22087 2.4311859
OS 2.2223314 2.438533
OS 2.22087 2.4458801
OS 2.2167082 2.4521087
OS 2.2104796 2.4562705
OS 2.2031325 2.4577319
OE
OB 3.6179425 2.5536725 H
OS 3.6047974 2.5523778
OS 3.5921575 2.5485435
OS 3.5805085 2.542317
OS 3.570298 2.5339375
OS 3.5619185 2.523727
OS 3.555692 2.512078
OS 3.5518577 2.4994381
OS 3.550563 2.486293
OS 3.5518577 2.4731479
OS 3.555692 2.460508
OS 3.5619185 2.448859
OS 3.570298 2.4386485
OS 3.5805085 2.430269
OS 3.5921575 2.4240425
OS 3.6047974 2.4202082
OS 3.6179425 2.4189135
OS 3.6310876 2.4202082
OS 3.6437275 2.4240425
OS 3.6553765 2.430269
OS 3.665587 2.4386485
OS 3.6739665 2.448859
OS 3.680193 2.460508
OS 3.6840273 2.4731479
OS 3.685322 2.486293
OS 3.6840273 2.4994381
OS 3.680193 2.512078
OS 3.6739665 2.523727
OS 3.665587 2.5339375
OS 3.6553765 2.542317
OS 3.6437275 2.5485435
OS 3.6310876 2.5523778
OS 3.6179425 2.5536725
OE
OB 1.6519425 2.5536725 H
OS 1.6387974 2.5523778
OS 1.6261575 2.5485435
OS 1.6145085 2.542317
OS 1.604298 2.5339375
OS 1.5959185 2.523727
OS 1.589692 2.512078
OS 1.5858577 2.4994381
OS 1.584563 2.486293
OS 1.5858577 2.4731479
OS 1.589692 2.460508
OS 1.5959185 2.448859
OS 1.604298 2.4386485
OS 1.6145085 2.430269
OS 1.6261575 2.4240425
OS 1.6387974 2.4202082
OS 1.6519425 2.4189135
OS 1.6650876 2.4202082
OS 1.6777275 2.4240425
OS 1.6893765 2.430269
OS 1.699587 2.4386485
OS 1.7079665 2.448859
OS 1.714193 2.460508
OS 1.7180273 2.4731479
OS 1.719322 2.486293
OS 1.7180273 2.4994381
OS 1.714193 2.512078
OS 1.7079665 2.523727
OS 1.699587 2.5339375
OS 1.6893765 2.542317
OS 1.6777275 2.5485435
OS 1.6650876 2.5523778
OS 1.6519425 2.5536725
OE
OB 0.1998425 2.5453727 H
OS 0.1872963 2.544137
OS 0.1752322 2.5404774
OS 0.1641139 2.5345346
OS 0.1543687 2.5265368
OS 0.1463709 2.5167916
OS 0.1404281 2.5056733
OS 0.1367685 2.4936092
OS 0.1355328 2.481063
OS 0.1367685 2.4685168
OS 0.1404281 2.4564527
OS 0.1463709 2.4453344
OS 0.1543687 2.4355892
OS 0.1641139 2.4275914
OS 0.1752322 2.4216486
OS 0.1872963 2.417989
OS 0.1998425 2.4167533
OS 0.2123887 2.417989
OS 0.2244528 2.4216486
OS 0.2355711 2.4275914
OS 0.2453163 2.4355892
OS 0.2533141 2.4453344
OS 0.2592569 2.4564527
OS 0.2629165 2.4685168
OS 0.2641522 2.481063
OS 0.2629165 2.4936092
OS 0.2592569 2.5056733
OS 0.2533141 2.5167916
OS 0.2453163 2.5265368
OS 0.2355711 2.5345346
OS 0.2244528 2.5404774
OS 0.2123887 2.544137
OS 0.1998425 2.5453727
OE
OB 2.8948425 2.4473765 H
OS 2.8885996 2.4461347
OS 2.8833071 2.4425984
OS 2.8797708 2.4373059
OS 2.878529 2.431063
OS 2.8797708 2.4248201
OS 2.8833071 2.4195276
OS 2.8885996 2.4159913
OS 2.8948425 2.4147495
OS 2.9010854 2.4159913
OS 2.9063778 2.4195276
OS 2.9073026 2.4195276
OS 2.9093071 2.4165276
OS 2.9145996 2.4129913
OS 2.9208425 2.4117495
OS 2.9270854 2.4129913
OS 2.9323779 2.4165276
OS 2.9359142 2.4218201
OS 2.937156 2.428063
OS 2.9359142 2.4343059
OS 2.9323779 2.4395984
OS 2.9270854 2.4431347
OS 2.9208425 2.4443765
OS 2.9145996 2.4431347
OS 2.9093072 2.4395984
OS 2.9083824 2.4395984
OS 2.9063779 2.4425984
OS 2.9010854 2.4461347
OS 2.8948425 2.4473765
OE
OB 4.0398425 2.4223765 H
OS 4.0335996 2.4211347
OS 4.0283071 2.4175984
OS 4.0247708 2.4123059
OS 4.023529 2.406063
OS 4.0247708 2.3998201
OS 4.0283071 2.3945276
OS 4.0335996 2.3909913
OS 4.0398425 2.3897495
OS 4.0460854 2.3909913
OS 4.0513779 2.3945276
OS 4.0549142 2.3998201
OS 4.056156 2.406063
OS 4.0549142 2.4123059
OS 4.0513779 2.4175984
OS 4.0460854 2.4211347
OS 4.0398425 2.4223765
OE
OB 3.4988425 2.3573765 H
OS 3.4925996 2.3561347
OS 3.4873071 2.3525984
OS 3.4837708 2.3473059
OS 3.482529 2.341063
OS 3.4837708 2.3348201
OS 3.4873071 2.3295276
OS 3.4925996 2.3259913
OS 3.4988425 2.3247495
OS 3.5050854 2.3259913
OS 3.5103779 2.3295276
OS 3.5139142 2.3348201
OS 3.515156 2.341063
OS 3.5139142 2.3473059
OS 3.5103779 2.3525984
OS 3.5050854 2.3561347
OS 3.4988425 2.3573765
OE
OB 2.7268425 2.3093765 H
OS 2.7205996 2.3081347
OS 2.7153071 2.3045984
OS 2.7131725 2.3014038
OS 2.7090854 2.3041347
OS 2.7028425 2.3053765
OS 2.6965996 2.3041347
OS 2.6913071 2.3005984
OS 2.6877708 2.2953059
OS 2.6868962 2.2909101
OS 2.6821561 2.2910632
OS 2.6809142 2.2973059
OS 2.6773779 2.3025984
OS 2.6720854 2.3061347
OS 2.6658425 2.3073765
OS 2.6595996 2.3061347
OS 2.6543071 2.3025984
OS 2.6507708 2.2973059
OS 2.649529 2.2910631
OS 2.6483447 2.2898788
OS 2.6458425 2.2903765
OS 2.6395996 2.2891347
OS 2.6343071 2.2855984
OS 2.6307708 2.2803059
OS 2.629529 2.274063
OS 2.6307708 2.2678201
OS 2.6343071 2.2625276
OS 2.6395996 2.2589913
OS 2.6458425 2.2577495
OS 2.6520854 2.2589913
OS 2.6573779 2.2625276
OS 2.6609142 2.2678201
OS 2.662156 2.2740629
OS 2.6633403 2.2752472
OS 2.6658425 2.2747495
OS 2.6720854 2.2759913
OS 2.6773779 2.2795276
OS 2.6809142 2.2848201
OS 2.6817888 2.2892159
OS 2.6865289 2.2890628
OS 2.6877708 2.2828201
OS 2.6913071 2.2775276
OS 2.6965996 2.2739913
OS 2.7028425 2.2727495
OS 2.7090854 2.2739913
OS 2.7143779 2.2775276
OS 2.7165125 2.2807222
OS 2.7205996 2.2779913
OS 2.7268425 2.2767495
OS 2.7330854 2.2779913
OS 2.7383779 2.2815276
OS 2.7419142 2.2868201
OS 2.743156 2.293063
OS 2.7419142 2.2993059
OS 2.7383779 2.3045984
OS 2.7330854 2.3081347
OS 2.7268425 2.3093765
OE
OB 2.4758425 2.3073765 H
OS 2.4695996 2.3061347
OS 2.4643071 2.3025984
OS 2.4623321 2.2996425
OS 2.4575823 2.2973722
OS 2.4556938 2.2974115
OS 2.4508425 2.2983765
OS 2.4445996 2.2971347
OS 2.4393071 2.2935984
OS 2.4357708 2.2883059
OS 2.434529 2.282063
OS 2.4357708 2.2758201
OS 2.4393071 2.2705276
OS 2.4445996 2.2669913
OS 2.4508425 2.2657495
OS 2.4570854 2.2669913
OS 2.4623779 2.2705276
OS 2.4659142 2.27582
OS 2.4709912 2.2757145
OS 2.4758425 2.2747495
OS 2.4820854 2.2759913
OS 2.4873779 2.2795276
OS 2.4909142 2.2848201
OS 2.492156 2.291063
OS 2.4909142 2.2973059
OS 2.4873779 2.3025984
OS 2.4820854 2.3061347
OS 2.4758425 2.3073765
OE
OB 2.8038425 2.3233765 H
OS 2.7975996 2.3221347
OS 2.7923071 2.3185984
OS 2.7887708 2.3133059
OS 2.787529 2.307063
OS 2.7887708 2.3008201
OS 2.7923071 2.2955276
OS 2.7975996 2.2919913
OS 2.8038425 2.2907495
OS 2.8100854 2.2919913
OS 2.8153779 2.2955276
OS 2.8189142 2.3008201
OS 2.820156 2.307063
OS 2.8189142 2.3133059
OS 2.8153779 2.3185984
OS 2.8100854 2.3221347
OS 2.8038425 2.3233765
OE
OB 2.9858425 2.3033765 H
OS 2.9795996 2.3021347
OS 2.9743071 2.2985984
OS 2.9707708 2.2933059
OS 2.969529 2.287063
OS 2.9707708 2.2808201
OS 2.9743071 2.2755276
OS 2.9795996 2.2719913
OS 2.9858425 2.2707495
OS 2.9920854 2.2719913
OS 2.9973779 2.2755276
OS 3.0009142 2.2808201
OS 3.002156 2.287063
OS 3.0009142 2.2933059
OS 2.9973779 2.2985984
OS 2.9920854 2.3021347
OS 2.9858425 2.3033765
OE
OB 2.9428425 2.3023765 H
OS 2.9365996 2.3011347
OS 2.9313071 2.2975984
OS 2.9277708 2.2923059
OS 2.926529 2.286063
OS 2.9277708 2.2798201
OS 2.9313071 2.2745276
OS 2.9365996 2.2709913
OS 2.9428425 2.2697495
OS 2.9490854 2.2709913
OS 2.9543779 2.2745276
OS 2.9579142 2.2798201
OS 2.959156 2.286063
OS 2.9579142 2.2923059
OS 2.9543779 2.2975984
OS 2.9490854 2.3011347
OS 2.9428425 2.3023765
OE
OB 5.3277559 2.3463244 H
OS 5.3177023 2.3450008
OS 5.3083338 2.3411203
OS 5.300289 2.3349472
OS 5.2941159 2.3269023
OS 5.2902354 2.3175339
OS 5.2889118 2.3074803
OS 5.2902354 2.2974267
OS 5.2941159 2.2880583
OS 5.300289 2.2800134
OS 5.3083338 2.2738403
OS 5.3177023 2.2699598
OS 5.3277559 2.2686362
OS 5.3378095 2.2699598
OS 5.347178 2.2738403
OS 5.3552228 2.2800134
OS 5.3613959 2.2880583
OS 5.3652764 2.2974267
OS 5.3666 2.3074803
OS 5.3652764 2.3175339
OS 5.3613959 2.3269023
OS 5.3552228 2.3349472
OS 5.347178 2.3411203
OS 5.3378095 2.3450008
OS 5.3277559 2.3463244
OE
OB 4.9277559 2.3463244 H
OS 4.9177023 2.3450008
OS 4.9083338 2.3411203
OS 4.900289 2.3349472
OS 4.8941159 2.3269023
OS 4.8902354 2.3175339
OS 4.8889118 2.3074803
OS 4.8902354 2.2974267
OS 4.8941159 2.2880583
OS 4.900289 2.2800134
OS 4.9083338 2.2738403
OS 4.9177023 2.2699598
OS 4.9277559 2.2686362
OS 4.9378095 2.2699598
OS 4.947178 2.2738403
OS 4.9552228 2.2800134
OS 4.9613959 2.2880583
OS 4.9652764 2.2974267
OS 4.9666 2.3074803
OS 4.9652764 2.3175339
OS 4.9613959 2.3269023
OS 4.9552228 2.3349472
OS 4.947178 2.3411203
OS 4.9378095 2.3450008
OS 4.9277559 2.3463244
OE
OB 4.7277559 2.3463244 H
OS 4.7177023 2.3450008
OS 4.7083338 2.3411203
OS 4.700289 2.3349472
OS 4.6941159 2.3269023
OS 4.6902354 2.3175339
OS 4.6889118 2.3074803
OS 4.6902354 2.2974267
OS 4.6941159 2.2880583
OS 4.700289 2.2800134
OS 4.7083338 2.2738403
OS 4.7177023 2.2699598
OS 4.7277559 2.2686362
OS 4.7378095 2.2699598
OS 4.747178 2.2738403
OS 4.7552228 2.2800134
OS 4.7613959 2.2880583
OS 4.7652764 2.2974267
OS 4.7666 2.3074803
OS 4.7652764 2.3175339
OS 4.7613959 2.3269023
OS 4.7552228 2.3349472
OS 4.747178 2.3411203
OS 4.7378095 2.3450008
OS 4.7277559 2.3463244
OE
OB 4.3277559 2.3463244 H
OS 4.3177023 2.3450008
OS 4.3083338 2.3411203
OS 4.300289 2.3349472
OS 4.2941159 2.3269023
OS 4.2902354 2.3175339
OS 4.2889118 2.3074803
OS 4.2902354 2.2974267
OS 4.2941159 2.2880583
OS 4.300289 2.2800134
OS 4.3083338 2.2738403
OS 4.3177023 2.2699598
OS 4.3277559 2.2686362
OS 4.3378095 2.2699598
OS 4.347178 2.2738403
OS 4.3552228 2.2800134
OS 4.3613959 2.2880583
OS 4.3652764 2.2974267
OS 4.3666 2.3074803
OS 4.3652764 2.3175339
OS 4.3613959 2.3269023
OS 4.3552228 2.3349472
OS 4.347178 2.3411203
OS 4.3378095 2.3450008
OS 4.3277559 2.3463244
OE
OB 2.4098425 2.3303765 H
OS 2.4035996 2.3291347
OS 2.3983071 2.3255984
OS 2.3947708 2.3203059
OS 2.393529 2.314063
OS 2.3947708 2.3078201
OS 2.3983071 2.3025276
OS 2.3997406 2.3015697
OS 2.3997406 2.2955563
OS 2.3983071 2.2945984
OS 2.3947708 2.2893059
OS 2.393529 2.283063
OS 2.3947708 2.2768201
OS 2.3983071 2.2715276
OS 2.4035996 2.2679913
OS 2.4098425 2.2667495
OS 2.4160854 2.2679913
OS 2.4213779 2.2715276
OS 2.4249142 2.2768201
OS 2.426156 2.283063
OS 2.4249142 2.2893059
OS 2.4213779 2.2945984
OS 2.4199444 2.2955563
OS 2.4199444 2.3015697
OS 2.4213779 2.3025276
OS 2.4249142 2.3078201
OS 2.426156 2.314063
OS 2.4249142 2.3203059
OS 2.4213779 2.3255984
OS 2.4160854 2.3291347
OS 2.4098425 2.3303765
OE
OB 2.5798425 2.2973765 H
OS 2.5735996 2.2961347
OS 2.5683071 2.2925984
OS 2.5647708 2.2873059
OS 2.563529 2.281063
OS 2.5647708 2.2748201
OS 2.5683071 2.2695276
OS 2.5735996 2.2659913
OS 2.5798425 2.2647495
OS 2.5860854 2.2659913
OS 2.5913779 2.2695276
OS 2.5949142 2.2748201
OS 2.596156 2.281063
OS 2.5949142 2.2873059
OS 2.5913779 2.2925984
OS 2.5860854 2.2961347
OS 2.5798425 2.2973765
OE
OB 3.3428425 2.2793765 H
OS 3.3365996 2.2781347
OS 3.3313071 2.2745984
OS 3.3277708 2.2693059
OS 3.326529 2.263063
OS 3.3277708 2.2568201
OS 3.3313071 2.2515276
OS 3.3365996 2.2479913
OS 3.3428425 2.2467495
OS 3.3490854 2.2479913
OS 3.3543779 2.2515276
OS 3.3579142 2.2568201
OS 3.359156 2.263063
OS 3.3579142 2.2693059
OS 3.3543779 2.2745984
OS 3.3490854 2.2781347
OS 3.3428425 2.2793765
OE
OB 2.8418425 2.2793765 H
OS 2.8355996 2.2781347
OS 2.8303071 2.2745984
OS 2.8267708 2.2693059
OS 2.825529 2.263063
OS 2.8267708 2.2568201
OS 2.8303071 2.2515276
OS 2.8355996 2.2479913
OS 2.8418425 2.2467495
OS 2.8480854 2.2479913
OS 2.8533779 2.2515276
OS 2.8569142 2.2568201
OS 2.858156 2.263063
OS 2.8569142 2.2693059
OS 2.8533779 2.2745984
OS 2.8480854 2.2781347
OS 2.8418425 2.2793765
OE
OB 0.9968357 2.2723495 H
OS 0.9905928 2.2711077
OS 0.9853003 2.2675714
OS 0.981764 2.2622789
OS 0.9805222 2.256036
OS 0.981764 2.2497931
OS 0.9853003 2.2445006
OS 0.9905928 2.2409643
OS 0.9968357 2.2397225
OS 1.0030786 2.2409643
OS 1.0083711 2.2445006
OS 1.0119074 2.2497931
OS 1.0131492 2.256036
OS 1.0119074 2.2622789
OS 1.0083711 2.2675714
OS 1.0030786 2.2711077
OS 0.9968357 2.2723495
OE
OB 5.6348425 2.2523765 H
OS 5.6285996 2.2511347
OS 5.6233071 2.2475984
OS 5.6197708 2.2423059
OS 5.618529 2.236063
OS 5.6197708 2.2298201
OS 5.6233071 2.2245276
OS 5.6285996 2.2209913
OS 5.6348425 2.2197495
OS 5.6410854 2.2209913
OS 5.6463779 2.2245276
OS 5.6499142 2.2298201
OS 5.651156 2.236063
OS 5.6499142 2.2423059
OS 5.6463779 2.2475984
OS 5.6410854 2.2511347
OS 5.6348425 2.2523765
OE
OB 2.4998425 2.2523765 H
OS 2.4935996 2.2511347
OS 2.4883071 2.2475984
OS 2.4847708 2.2423059
OS 2.483529 2.236063
OS 2.4847708 2.2298201
OS 2.4883071 2.2245276
OS 2.4935996 2.2209913
OS 2.4998425 2.2197495
OS 2.5060854 2.2209913
OS 2.5113779 2.2245276
OS 2.5149142 2.2298201
OS 2.516156 2.236063
OS 2.5149142 2.2423059
OS 2.5113779 2.2475984
OS 2.5060854 2.2511347
OS 2.4998425 2.2523765
OE
OB 2.3308425 2.2313765 H
OS 2.3245996 2.2301347
OS 2.3193071 2.2265984
OS 2.3157708 2.2213059
OS 2.314529 2.215063
OS 2.3157708 2.2088201
OS 2.3193071 2.2035276
OS 2.3245996 2.1999913
OS 2.3308425 2.1987495
OS 2.3370854 2.1999913
OS 2.3423779 2.2035276
OS 2.3459142 2.2088201
OS 2.347156 2.215063
OS 2.3459142 2.2213059
OS 2.3423779 2.2265984
OS 2.3370854 2.2301347
OS 2.3308425 2.2313765
OE
OB 5.5778425 2.2303765 H
OS 5.5715996 2.2291347
OS 5.5663071 2.2255984
OS 5.5627708 2.2203059
OS 5.561529 2.214063
OS 5.5627708 2.2078201
OS 5.5663071 2.2025276
OS 5.5715996 2.1989913
OS 5.5778425 2.1977495
OS 5.5840854 2.1989913
OS 5.5893779 2.2025276
OS 5.5929142 2.2078201
OS 5.594156 2.214063
OS 5.5929142 2.2203059
OS 5.5893779 2.2255984
OS 5.5840854 2.2291347
OS 5.5778425 2.2303765
OE
OB 6.4248425 2.1973765 H
OS 6.4185996 2.1961347
OS 6.4133071 2.1925984
OS 6.4097708 2.1873059
OS 6.408529 2.181063
OS 6.4097708 2.1748201
OS 6.4133071 2.1695276
OS 6.4185996 2.1659913
OS 6.4248425 2.1647495
OS 6.4310854 2.1659913
OS 6.4363779 2.1695276
OS 6.4399142 2.1748201
OS 6.441156 2.181063
OS 6.4399142 2.1873059
OS 6.4363779 2.1925984
OS 6.4310854 2.1961347
OS 6.4248425 2.1973765
OE
OB 1.7548425 2.1423765 H
OS 1.7485996 2.1411347
OS 1.7433071 2.1375984
OS 1.7397708 2.1323059
OS 1.738529 2.126063
OS 1.7397708 2.1198201
OS 1.7433071 2.1145276
OS 1.7485996 2.1109913
OS 1.7548425 2.1097495
OS 1.7610854 2.1109913
OS 1.7663779 2.1145276
OS 1.7699142 2.1198201
OS 1.771156 2.126063
OS 1.7699142 2.1323059
OS 1.7663779 2.1375984
OS 1.7610854 2.1411347
OS 1.7548425 2.1423765
OE
OB 1.6198425 2.1373765 H
OS 1.6135996 2.1361347
OS 1.6083071 2.1325984
OS 1.6047708 2.1273059
OS 1.603529 2.121063
OS 1.6047708 2.1148201
OS 1.6083071 2.1095276
OS 1.6135996 2.1059913
OS 1.6198425 2.1047495
OS 1.6260854 2.1059913
OS 1.6313779 2.1095276
OS 1.6349142 2.1148201
OS 1.636156 2.121063
OS 1.6349142 2.1273059
OS 1.6313779 2.1325984
OS 1.6260854 2.1361347
OS 1.6198425 2.1373765
OE
OB 1.6968325 2.1164319 H
OS 1.6894854 2.1149705
OS 1.6832568 2.1108087
OS 1.679095 2.1045801
OS 1.6776336 2.097233
OS 1.679095 2.0898859
OS 1.6832568 2.0836573
OS 1.6894854 2.0794955
OS 1.6968325 2.0780341
OS 1.7041796 2.0794955
OS 1.7104082 2.0836573
OS 1.71457 2.0898859
OS 1.7160314 2.097233
OS 1.71457 2.1045801
OS 1.7104082 2.1108087
OS 1.7041796 2.1149705
OS 1.6968325 2.1164319
OE
OB 1.8848425 2.0873765 H
OS 1.8785996 2.0861347
OS 1.8733071 2.0825984
OS 1.8697708 2.0773059
OS 1.868529 2.071063
OS 1.8697708 2.0648201
OS 1.8733071 2.0595276
OS 1.8785996 2.0559913
OS 1.8848425 2.0547495
OS 1.8910854 2.0559913
OS 1.8963779 2.0595276
OS 1.8999142 2.0648201
OS 1.901156 2.071063
OS 1.8999142 2.0773059
OS 1.8963779 2.0825984
OS 1.8910854 2.0861347
OS 1.8848425 2.0873765
OE
OB 1.5682025 2.0840165 H
OS 1.5619596 2.0827747
OS 1.5566671 2.0792384
OS 1.5531308 2.0739459
OS 1.551889 2.067703
OS 1.5531308 2.0614601
OS 1.5566671 2.0561676
OS 1.5619596 2.0526313
OS 1.5682025 2.0513895
OS 1.5744454 2.0526313
OS 1.5797379 2.0561676
OS 1.5832742 2.0614601
OS 1.584516 2.067703
OS 1.5832742 2.0739459
OS 1.5797379 2.0792384
OS 1.5744454 2.0827747
OS 1.5682025 2.0840165
OE
OB 3.5717425 2.1163919 H
OS 3.5643954 2.1149305
OS 3.5581668 2.1107687
OS 3.554005 2.1045401
OS 3.5525436 2.097193
OS 3.554005 2.0898459
OS 3.5581668 2.0836173
OS 3.5643954 2.0794555
OS 3.5680713 2.0787243
OS 3.5680713 2.0736264
OS 3.5655996 2.0731347
OS 3.5603071 2.0695984
OS 3.5567708 2.0643059
OS 3.555529 2.058063
OS 3.5567708 2.0518201
OS 3.5584204 2.0493513
OS 3.5599241 2.045563
OS 3.5584204 2.0417747
OS 3.5567708 2.0393059
OS 3.555529 2.033063
OS 3.5567708 2.0268201
OS 3.5603071 2.0215276
OS 3.5655996 2.0179913
OS 3.5718425 2.0167495
OS 3.5780854 2.0179913
OS 3.5833779 2.0215276
OS 3.5869142 2.0268201
OS 3.588156 2.033063
OS 3.5869142 2.0393059
OS 3.5852646 2.0417747
OS 3.5837609 2.045563
OS 3.5852646 2.0493513
OS 3.5869142 2.0518201
OS 3.588156 2.058063
OS 3.5869142 2.0643059
OS 3.5833779 2.0695984
OS 3.5780854 2.0731347
OS 3.5755137 2.0736462
OS 3.5755137 2.0787442
OS 3.5790896 2.0794555
OS 3.5853182 2.0836173
OS 3.58948 2.0898459
OS 3.5909414 2.097193
OS 3.58948 2.1045401
OS 3.5853182 2.1107687
OS 3.5790896 2.1149305
OS 3.5717425 2.1163919
OE
OB 2.4098425 1.9833765 H
OS 2.4035996 1.9821347
OS 2.3983071 1.9785984
OS 2.3947708 1.9733059
OS 2.393529 1.967063
OS 2.3947708 1.9608201
OS 2.3961401 1.9587707
OS 2.3925353 1.9551659
OS 2.3910854 1.9561347
OS 2.3848425 1.9573765
OS 2.3785996 1.9561347
OS 2.3733071 1.9525984
OS 2.3697708 1.9473059
OS 2.368529 1.941063
OS 2.3697708 1.9348201
OS 2.3733071 1.9295276
OS 2.3785996 1.9259913
OS 2.3848425 1.9247495
OS 2.3910854 1.9259913
OS 2.3963779 1.9295276
OS 2.3999142 1.9348201
OS 2.401156 1.941063
OS 2.3999142 1.9473059
OS 2.3985449 1.9493553
OS 2.4021497 1.9529601
OS 2.4035996 1.9519913
OS 2.4098425 1.9507495
OS 2.4160854 1.9519913
OS 2.4213779 1.9555276
OS 2.4249142 1.9608201
OS 2.426156 1.967063
OS 2.4249142 1.9733059
OS 2.4213779 1.9785984
OS 2.4160854 1.9821347
OS 2.4098425 1.9833765
OE
OB 3.2988425 1.9873765 H
OS 3.2925996 1.9861347
OS 3.2873071 1.9825984
OS 3.2837708 1.9773059
OS 3.282529 1.971063
OS 3.2837708 1.9648201
OS 3.2873071 1.9595276
OS 3.2925996 1.9559913
OS 3.2988425 1.9547495
OS 3.3050854 1.9559913
OS 3.3103779 1.9595276
OS 3.3139142 1.9648201
OS 3.315156 1.971063
OS 3.3139142 1.9773059
OS 3.3103779 1.9825984
OS 3.3050854 1.9861347
OS 3.2988425 1.9873765
OE
OB 1.0098425 1.9723765 H
OS 1.0035996 1.9711347
OS 0.9983071 1.9675984
OS 0.9947708 1.9623059
OS 0.993529 1.956063
OS 0.9947708 1.9498201
OS 0.9983071 1.9445276
OS 1.0035996 1.9409913
OS 1.0098425 1.9397495
OS 1.0160854 1.9409913
OS 1.0213779 1.9445276
OS 1.0249142 1.9498201
OS 1.026156 1.956063
OS 1.0249142 1.9623059
OS 1.0213779 1.9675984
OS 1.0160854 1.9711347
OS 1.0098425 1.9723765
OE
OB 2.2998425 1.9323765 H
OS 2.2935996 1.9311347
OS 2.2883071 1.9275984
OS 2.2847708 1.9223059
OS 2.283529 1.916063
OS 2.2847708 1.9098201
OS 2.2883071 1.9045276
OS 2.2935996 1.9009913
OS 2.2998425 1.8997495
OS 2.3060854 1.9009913
OS 2.3113779 1.9045276
OS 2.3149142 1.9098201
OS 2.316156 1.916063
OS 2.3149142 1.9223059
OS 2.3113779 1.9275984
OS 2.3060854 1.9311347
OS 2.2998425 1.9323765
OE
OB 0.1998425 2.0203727 H
OS 0.1872963 2.019137
OS 0.1752322 2.0154774
OS 0.1641139 2.0095346
OS 0.1543687 2.0015368
OS 0.1463709 1.9917916
OS 0.1404281 1.9806733
OS 0.1367685 1.9686092
OS 0.1355328 1.956063
OS 0.1367685 1.9435168
OS 0.1404281 1.9314527
OS 0.1463709 1.9203344
OS 0.1543687 1.9105892
OS 0.1641139 1.9025914
OS 0.1752322 1.8966486
OS 0.1872963 1.892989
OS 0.1998425 1.8917533
OS 0.2123887 1.892989
OS 0.2244528 1.8966486
OS 0.2355711 1.9025914
OS 0.2453163 1.9105892
OS 0.2533141 1.9203344
OS 0.2592569 1.9314527
OS 0.2629165 1.9435168
OS 0.2641522 1.956063
OS 0.2629165 1.9686092
OS 0.2592569 1.9806733
OS 0.2533141 1.9917916
OS 0.2453163 2.0015368
OS 0.2355711 2.0095346
OS 0.2244528 2.0154774
OS 0.2123887 2.019137
OS 0.1998425 2.0203727
OE
OB 3.5548425 1.9073765 H
OS 3.5485996 1.9061347
OS 3.5433071 1.9025984
OS 3.5397708 1.8973059
OS 3.538529 1.891063
OS 3.5397708 1.8848201
OS 3.5433071 1.8795276
OS 3.5485996 1.8759913
OS 3.5548425 1.8747495
OS 3.5610854 1.8759913
OS 3.5663779 1.8795276
OS 3.5699142 1.8848201
OS 3.571156 1.891063
OS 3.5699142 1.8973059
OS 3.5663779 1.9025984
OS 3.5610854 1.9061347
OS 3.5548425 1.9073765
OE
OB 3.3928425 1.8873765 H
OS 3.3865996 1.8861347
OS 3.3813071 1.8825984
OS 3.3777708 1.8773059
OS 3.376529 1.871063
OS 3.3777708 1.8648201
OS 3.3813071 1.8595276
OS 3.3865996 1.8559913
OS 3.3928425 1.8547495
OS 3.3990854 1.8559913
OS 3.4043779 1.8595276
OS 3.4079142 1.8648201
OS 3.409156 1.871063
OS 3.4079142 1.8773059
OS 3.4043779 1.8825984
OS 3.3990854 1.8861347
OS 3.3928425 1.8873765
OE
OB 3.4392507 1.8872515 H
OS 3.4330078 1.8860097
OS 3.4277153 1.8824734
OS 3.424179 1.8771809
OS 3.4229372 1.870938
OS 3.424179 1.8646951
OS 3.4277153 1.8594026
OS 3.4330078 1.8558663
OS 3.4392507 1.8546245
OS 3.4454936 1.8558663
OS 3.4507861 1.8594026
OS 3.4543224 1.8646951
OS 3.4555642 1.870938
OS 3.4543224 1.8771809
OS 3.4507861 1.8824734
OS 3.4454936 1.8860097
OS 3.4392507 1.8872515
OE
OB 3.8048425 1.8563765 H
OS 3.7985996 1.8551347
OS 3.7933071 1.8515984
OS 3.7897708 1.8463059
OS 3.788529 1.840063
OS 3.7897708 1.8338201
OS 3.7933071 1.8285276
OS 3.7985996 1.8249913
OS 3.8048425 1.8237495
OS 3.8110854 1.8249913
OS 3.8163779 1.8285276
OS 3.8199142 1.8338201
OS 3.821156 1.840063
OS 3.8199142 1.8463059
OS 3.8163779 1.8515984
OS 3.8110854 1.8551347
OS 3.8048425 1.8563765
OE
OB 3.3291721 1.8423765 H
OS 3.3229292 1.8411347
OS 3.3176367 1.8375984
OS 3.3141004 1.8323059
OS 3.3128586 1.826063
OS 3.3141004 1.8198201
OS 3.3176367 1.8145276
OS 3.3229292 1.8109913
OS 3.3291721 1.8097495
OS 3.335415 1.8109913
OS 3.3407075 1.8145276
OS 3.3442438 1.8198201
OS 3.3454856 1.826063
OS 3.3442438 1.8323059
OS 3.3407075 1.8375984
OS 3.335415 1.8411347
OS 3.3291721 1.8423765
OE
OB 1.3937008 1.8332426 H
OS 1.3874579 1.8320008
OS 1.3821654 1.8284645
OS 1.3786291 1.823172
OS 1.3773873 1.8169291
OS 1.3786291 1.8106862
OS 1.3821654 1.8053937
OS 1.3874579 1.8018574
OS 1.3937008 1.8006156
OS 1.3999437 1.8018574
OS 1.4052362 1.8053937
OS 1.4087725 1.8106862
OS 1.4100143 1.8169291
OS 1.4087725 1.823172
OS 1.4052362 1.8284645
OS 1.3999437 1.8320008
OS 1.3937008 1.8332426
OE
OB 3.9448425 1.8323765 H
OS 3.9385996 1.8311347
OS 3.9333071 1.8275984
OS 3.9297708 1.8223059
OS 3.928529 1.816063
OS 3.9297708 1.8098201
OS 3.9333071 1.8045276
OS 3.9385996 1.8009913
OS 3.9448425 1.7997495
OS 3.9510854 1.8009913
OS 3.9563779 1.8045276
OS 3.9599142 1.8098201
OS 3.961156 1.816063
OS 3.9599142 1.8223059
OS 3.9563779 1.8275984
OS 3.9510854 1.8311347
OS 3.9448425 1.8323765
OE
OB 3.0568817 1.8281165 H
OS 3.0506388 1.8268747
OS 3.0453463 1.8233384
OS 3.04181 1.8180459
OS 3.0405682 1.811803
OS 3.04181 1.8055601
OS 3.0453463 1.8002676
OS 3.0506388 1.7967313
OS 3.0568817 1.7954895
OS 3.0631246 1.7967313
OS 3.0684171 1.8002676
OS 3.0719534 1.8055601
OS 3.0731952 1.811803
OS 3.0719534 1.8180459
OS 3.0684171 1.8233384
OS 3.0631246 1.8268747
OS 3.0568817 1.8281165
OE
OB 1.8799377 1.8281165 H
OS 1.8736948 1.8268747
OS 1.8684023 1.8233384
OS 1.864866 1.8180459
OS 1.8636242 1.811803
OS 1.864866 1.8055601
OS 1.8684023 1.8002676
OS 1.8736948 1.7967313
OS 1.8799377 1.7954895
OS 1.8861806 1.7967313
OS 1.8914731 1.8002676
OS 1.8950094 1.8055601
OS 1.8962512 1.811803
OS 1.8950094 1.8180459
OS 1.8914731 1.8233384
OS 1.8861806 1.8268747
OS 1.8799377 1.8281165
OE
OB 4.0648425 1.8123765 H
OS 4.0585996 1.8111347
OS 4.0533071 1.8075984
OS 4.0497708 1.8023059
OS 4.048529 1.796063
OS 4.0497708 1.7898201
OS 4.0533071 1.7845276
OS 4.0585996 1.7809913
OS 4.0648425 1.7797495
OS 4.0710854 1.7809913
OS 4.0763779 1.7845276
OS 4.0799142 1.7898201
OS 4.081156 1.796063
OS 4.0799142 1.8023059
OS 4.0763779 1.8075984
OS 4.0710854 1.8111347
OS 4.0648425 1.8123765
OE
OB 2.5798425 1.8063765 H
OS 2.5735996 1.8051347
OS 2.5683071 1.8015984
OS 2.5647708 1.7963059
OS 2.563529 1.790063
OS 2.5647708 1.7838201
OS 2.5683071 1.7785276
OS 2.5735996 1.7749913
OS 2.5798425 1.7737495
OS 2.5860854 1.7749913
OS 2.5913779 1.7785276
OS 2.5949142 1.7838201
OS 2.596156 1.790063
OS 2.5949142 1.7963059
OS 2.5913779 1.8015984
OS 2.5860854 1.8051347
OS 2.5798425 1.8063765
OE
OB 2.6268425 1.7863765 H
OS 2.6205996 1.7851347
OS 2.6153071 1.7815984
OS 2.6117708 1.7763059
OS 2.610529 1.770063
OS 2.6117708 1.7638201
OS 2.6153071 1.7585276
OS 2.6205996 1.7549913
OS 2.6268425 1.7537495
OS 2.6330854 1.7549913
OS 2.6383779 1.7585276
OS 2.6419142 1.7638201
OS 2.643156 1.770063
OS 2.6419142 1.7763059
OS 2.6383779 1.7815984
OS 2.6330854 1.7851347
OS 2.6268425 1.7863765
OE
OB 3.7198425 1.7823765 H
OS 3.7135996 1.7811347
OS 3.7083071 1.7775984
OS 3.7047708 1.7723059
OS 3.703529 1.766063
OS 3.7047708 1.7598201
OS 3.7083071 1.7545276
OS 3.7135996 1.7509913
OS 3.7198425 1.7497495
OS 3.7260854 1.7509913
OS 3.7313779 1.7545276
OS 3.7349142 1.7598201
OS 3.736156 1.766063
OS 3.7349142 1.7723059
OS 3.7313779 1.7775984
OS 3.7260854 1.7811347
OS 3.7198425 1.7823765
OE
OB 2.5498425 1.7713765 H
OS 2.5435996 1.7701347
OS 2.5383071 1.7665984
OS 2.5347708 1.7613059
OS 2.533529 1.755063
OS 2.5347708 1.7488201
OS 2.5383071 1.7435276
OS 2.5435996 1.7399913
OS 2.5498425 1.7387495
OS 2.5560854 1.7399913
OS 2.5613779 1.7435276
OS 2.5649142 1.7488201
OS 2.566156 1.755063
OS 2.5649142 1.7613059
OS 2.5613779 1.7665984
OS 2.5560854 1.7701347
OS 2.5498425 1.7713765
OE
OB 4.1348425 1.7673765 H
OS 4.1285996 1.7661347
OS 4.1233071 1.7625984
OS 4.1197708 1.7573059
OS 4.118529 1.751063
OS 4.1197708 1.7448201
OS 4.1233071 1.7395276
OS 4.1285996 1.7359913
OS 4.1348425 1.7347495
OS 4.1410854 1.7359913
OS 4.1463779 1.7395276
OS 4.1499142 1.7448201
OS 4.151156 1.751063
OS 4.1499142 1.7573059
OS 4.1463779 1.7625984
OS 4.1410854 1.7661347
OS 4.1348425 1.7673765
OE
OB 2.6048425 1.7503765 H
OS 2.5985996 1.7491347
OS 2.5933071 1.7455984
OS 2.5897708 1.7403059
OS 2.588529 1.734063
OS 2.5897708 1.7278201
OS 2.5933071 1.7225276
OS 2.5985996 1.7189913
OS 2.6048425 1.7177495
OS 2.6110854 1.7189913
OS 2.6163779 1.7225276
OS 2.6199142 1.7278201
OS 2.621156 1.734063
OS 2.6199142 1.7403059
OS 2.6163779 1.7455984
OS 2.6110854 1.7491347
OS 2.6048425 1.7503765
OE
OB 0.988189 1.7338332 H
OS 0.9819461 1.7325914
OS 0.9766536 1.7290551
OS 0.9731173 1.7237626
OS 0.9718755 1.7175197
OS 0.9731173 1.7112768
OS 0.9766536 1.7059843
OS 0.9819461 1.702448
OS 0.988189 1.7012062
OS 0.9944319 1.702448
OS 0.9997244 1.7059843
OS 1.0032607 1.7112768
OS 1.0045025 1.7175197
OS 1.0032607 1.7237626
OS 0.9997244 1.7290551
OS 0.9944319 1.7325914
OS 0.988189 1.7338332
OE
OB 3.1972633 1.7303765 H
OS 3.1910204 1.7291347
OS 3.1857279 1.7255984
OS 3.1821916 1.7203059
OS 3.1809498 1.714063
OS 3.1821916 1.7078201
OS 3.1857279 1.7025276
OS 3.1910204 1.6989913
OS 3.1972633 1.6977495
OS 3.2035062 1.6989913
OS 3.2087987 1.7025276
OS 3.212335 1.7078201
OS 3.2135768 1.714063
OS 3.212335 1.7203059
OS 3.2087987 1.7255984
OS 3.2035062 1.7291347
OS 3.1972633 1.7303765
OE
OB 3.5898425 1.7273765 H
OS 3.5835996 1.7261347
OS 3.5783071 1.7225984
OS 3.5747708 1.7173059
OS 3.573529 1.711063
OS 3.5747708 1.7048201
OS 3.5783071 1.6995276
OS 3.5835996 1.6959913
OS 3.5898425 1.6947495
OS 3.5960854 1.6959913
OS 3.6013779 1.6995276
OS 3.6049142 1.7048201
OS 3.606156 1.711063
OS 3.6049142 1.7173059
OS 3.6013779 1.7225984
OS 3.5960854 1.7261347
OS 3.5898425 1.7273765
OE
OB 1.8938425 1.7093765 H
OS 1.8875996 1.7081347
OS 1.8823071 1.7045984
OS 1.8787708 1.6993059
OS 1.877529 1.693063
OS 1.8787708 1.6868201
OS 1.8823071 1.6815276
OS 1.8875996 1.6779913
OS 1.8938425 1.6767495
OS 1.9000854 1.6779913
OS 1.9053779 1.6815276
OS 1.9089142 1.6868201
OS 1.910156 1.693063
OS 1.9089142 1.6993059
OS 1.9053779 1.7045984
OS 1.9000854 1.7081347
OS 1.8938425 1.7093765
OE
OB 3.8038425 1.7073765 H
OS 3.7975996 1.7061347
OS 3.7923071 1.7025984
OS 3.7887708 1.6973059
OS 3.787529 1.691063
OS 3.7887708 1.6848201
OS 3.7923071 1.6795276
OS 3.7975996 1.6759913
OS 3.8038425 1.6747495
OS 3.8100854 1.6759913
OS 3.8153779 1.6795276
OS 3.8189142 1.6848201
OS 3.820156 1.691063
OS 3.8189142 1.6973059
OS 3.8153779 1.7025984
OS 3.8100854 1.7061347
OS 3.8038425 1.7073765
OE
OB 3.7248425 1.6913765 H
OS 3.7185996 1.6901347
OS 3.7133071 1.6865984
OS 3.7097708 1.6813059
OS 3.708529 1.675063
OS 3.7097708 1.6688201
OS 3.7133071 1.6635276
OS 3.7185996 1.6599913
OS 3.7248425 1.6587495
OS 3.7310854 1.6599913
OS 3.7363779 1.6635276
OS 3.7399142 1.6688201
OS 3.741156 1.675063
OS 3.7399142 1.6813059
OS 3.7363779 1.6865984
OS 3.7310854 1.6901347
OS 3.7248425 1.6913765
OE
OB 1.8227825 1.6903165 H
OS 1.8165396 1.6890747
OS 1.8112471 1.6855384
OS 1.8077108 1.6802459
OS 1.806469 1.674003
OS 1.8077108 1.6677601
OS 1.8112471 1.6624676
OS 1.8165396 1.6589313
OS 1.8227825 1.6576895
OS 1.8290254 1.6589313
OS 1.8343179 1.6624676
OS 1.8378542 1.6677601
OS 1.839096 1.674003
OS 1.8378542 1.6802459
OS 1.8343179 1.6855384
OS 1.8290254 1.6890747
OS 1.8227825 1.6903165
OE
OB 3.7738632 1.6824156 H
OS 3.7676203 1.6811738
OS 3.7623278 1.6776375
OS 3.7587915 1.672345
OS 3.7575497 1.6661021
OS 3.7587915 1.6598592
OS 3.7623278 1.6545667
OS 3.7676203 1.6510304
OS 3.7738632 1.6497886
OS 3.7801061 1.6510304
OS 3.7853986 1.6545667
OS 3.7889349 1.6598592
OS 3.7901767 1.6661021
OS 3.7889349 1.672345
OS 3.7853986 1.6776375
OS 3.7801061 1.6811738
OS 3.7738632 1.6824156
OE
OB 6.8448425 1.6773765 H
OS 6.8385996 1.6761347
OS 6.8333071 1.6725984
OS 6.8297708 1.6673059
OS 6.828529 1.661063
OS 6.8297708 1.6548201
OS 6.8333071 1.6495276
OS 6.8385996 1.6459913
OS 6.8448425 1.6447495
OS 6.8510854 1.6459913
OS 6.8563779 1.6495276
OS 6.8599142 1.6548201
OS 6.861156 1.661063
OS 6.8599142 1.6673059
OS 6.8563779 1.6725984
OS 6.8510854 1.6761347
OS 6.8448425 1.6773765
OE
OB 3.2248425 1.6776607 H
OS 3.2185996 1.6764189
OS 3.2133071 1.6728826
OS 3.2097708 1.6675901
OS 3.208529 1.6613472
OS 3.2097708 1.6551043
OS 3.2133071 1.6498118
OS 3.2185996 1.6462755
OS 3.2248425 1.6450337
OS 3.2310854 1.6462755
OS 3.235497 1.6492232
OS 3.2395781 1.6496996
OS 3.2419254 1.6491144
OS 3.2465996 1.6459913
OS 3.2528425 1.6447495
OS 3.2590854 1.6459913
OS 3.2643779 1.6495276
OS 3.2679142 1.6548201
OS 3.269156 1.661063
OS 3.2679142 1.6673059
OS 3.2643779 1.6725984
OS 3.2590854 1.6761347
OS 3.2528425 1.6773765
OS 3.2465996 1.6761347
OS 3.242188 1.673187
OS 3.2381069 1.6727106
OS 3.2357596 1.6732958
OS 3.2310854 1.6764189
OS 3.2248425 1.6776607
OE
OB 2.6668425 1.6563765 H
OS 2.6605996 1.6551347
OS 2.6553071 1.6515984
OS 2.6517708 1.6463059
OS 2.650529 1.640063
OS 2.6513707 1.6358317
OS 2.6479104 1.6318625
OS 2.6474924 1.6316505
OS 2.6438425 1.6323765
OS 2.6375996 1.6311347
OS 2.6323071 1.6275984
OS 2.6287708 1.6223059
OS 2.627529 1.616063
OS 2.6287708 1.6098201
OS 2.6323071 1.6045276
OS 2.6375996 1.6009913
OS 2.6438425 1.5997495
OS 2.6500854 1.6009913
OS 2.6553779 1.6045276
OS 2.6589142 1.6098201
OS 2.660156 1.616063
OS 2.6593143 1.6202943
OS 2.6627746 1.6242635
OS 2.6631926 1.6244755
OS 2.6668425 1.6237495
OS 2.6730854 1.6249913
OS 2.6783779 1.6285276
OS 2.6819142 1.6338201
OS 2.683156 1.640063
OS 2.6819142 1.6463059
OS 2.6783779 1.6515984
OS 2.6730854 1.6551347
OS 2.6668425 1.6563765
OE
OB 4.1348425 1.6673765 H
OS 4.1285996 1.6661347
OS 4.1233071 1.6625984
OS 4.1197708 1.6573059
OS 4.118529 1.651063
OS 4.1197708 1.6448201
OS 4.1233071 1.6395276
OS 4.1285996 1.6359913
OS 4.1336434 1.634988
OS 4.1357664 1.6316625
OS 4.1362826 1.629938
OS 4.1362346 1.6298661
OS 4.1349928 1.6236232
OS 4.1362346 1.6173803
OS 4.1397709 1.6120878
OS 4.1450634 1.6085515
OS 4.1513063 1.6073097
OS 4.1575492 1.6085515
OS 4.1612353 1.6110144
OS 4.1648401 1.6074096
OS 4.1647708 1.6073059
OS 4.163529 1.601063
OS 4.1647708 1.5948201
OS 4.1683071 1.5895276
OS 4.1735996 1.5859913
OS 4.1798425 1.5847495
OS 4.1860854 1.5859913
OS 4.1913779 1.5895276
OS 4.1949142 1.5948201
OS 4.196156 1.601063
OS 4.1949142 1.6073059
OS 4.1913779 1.6125984
OS 4.1860854 1.6161347
OS 4.1798425 1.6173765
OS 4.1735996 1.6161347
OS 4.1699135 1.6136718
OS 4.1663087 1.6172766
OS 4.166378 1.6173803
OS 4.1676198 1.6236232
OS 4.166378 1.6298661
OS 4.1628417 1.6351586
OS 4.1575492 1.6386949
OS 4.1525054 1.6396982
OS 4.1503824 1.6430237
OS 4.1498662 1.6447482
OS 4.1499142 1.6448201
OS 4.151156 1.651063
OS 4.1499142 1.6573059
OS 4.1463779 1.6625984
OS 4.1410854 1.6661347
OS 4.1348425 1.6673765
OE
OB 2.7198425 1.6073765 H
OS 2.7135996 1.6061347
OS 2.7083071 1.6025984
OS 2.7047708 1.5973059
OS 2.703529 1.591063
OS 2.7047708 1.5848201
OS 2.7083071 1.5795276
OS 2.7135996 1.5759913
OS 2.7198425 1.5747495
OS 2.7260854 1.5759913
OS 2.7313779 1.5795276
OS 2.7349142 1.5848201
OS 2.736156 1.591063
OS 2.7349142 1.5973059
OS 2.7313779 1.6025984
OS 2.7260854 1.6061347
OS 2.7198425 1.6073765
OE
OB 3.8948425 1.5823765 H
OS 3.8885996 1.5811347
OS 3.8833071 1.5775984
OS 3.8797708 1.5723059
OS 3.878529 1.566063
OS 3.8797708 1.5598201
OS 3.8833071 1.5545276
OS 3.8885996 1.5509913
OS 3.8948425 1.5497495
OS 3.9010854 1.5509913
OS 3.9063779 1.5545276
OS 3.9099142 1.5598201
OS 3.911156 1.566063
OS 3.9099142 1.5723059
OS 3.9063779 1.5775984
OS 3.9010854 1.5811347
OS 3.8948425 1.5823765
OE
OB 3.9698425 1.5683765 H
OS 3.9635996 1.5671347
OS 3.9583071 1.5635984
OS 3.9547708 1.5583059
OS 3.953529 1.552063
OS 3.9547708 1.5458201
OS 3.9583071 1.5405276
OS 3.9635996 1.5369913
OS 3.9698425 1.5357495
OS 3.9760854 1.5369913
OS 3.9780923 1.5383323
OS 3.9831154 1.5394836
OS 3.9856688 1.5379496
OS 3.9885996 1.5359913
OS 3.9948425 1.5347495
OS 4.0010854 1.5359913
OS 4.0063779 1.5395276
OS 4.0099142 1.5448201
OS 4.011156 1.551063
OS 4.0099142 1.5573059
OS 4.0063779 1.5625984
OS 4.0010854 1.5661347
OS 3.9948425 1.5673765
OS 3.9885996 1.5661347
OS 3.9833072 1.5625984
OS 3.982046 1.5625984
OS 3.9813779 1.5635984
OS 3.9760854 1.5671347
OS 3.9698425 1.5683765
OE
OB 4.0348425 1.5623765 H
OS 4.0285996 1.5611347
OS 4.0233071 1.5575984
OS 4.0197708 1.5523059
OS 4.018529 1.546063
OS 4.0197708 1.5398201
OS 4.0233071 1.5345276
OS 4.0285996 1.5309913
OS 4.0348425 1.5297495
OS 4.0410854 1.5309913
OS 4.0463779 1.5345276
OS 4.0499142 1.5398201
OS 4.051156 1.546063
OS 4.0499142 1.5523059
OS 4.0463779 1.5575984
OS 4.0410854 1.5611347
OS 4.0348425 1.5623765
OE
OB 3.9248425 1.5523765 H
OS 3.9185996 1.5511347
OS 3.9133071 1.5475984
OS 3.9097708 1.5423059
OS 3.908529 1.536063
OS 3.9097708 1.5298201
OS 3.9133071 1.5245276
OS 3.9185996 1.5209913
OS 3.9248425 1.5197495
OS 3.9310854 1.5209913
OS 3.9363779 1.5245276
OS 3.9399142 1.5298201
OS 3.941156 1.536063
OS 3.9399142 1.5423059
OS 3.9363779 1.5475984
OS 3.9310854 1.5511347
OS 3.9248425 1.5523765
OE
OB 2.8948425 1.5773765 H
OS 2.8885996 1.5761347
OS 2.8833071 1.5725984
OS 2.8797708 1.5673059
OS 2.878529 1.561063
OS 2.8797708 1.5548201
OS 2.8833071 1.5495276
OS 2.8885996 1.5459913
OS 2.8948425 1.5447495
OS 2.9010854 1.5459913
OS 2.9013282 1.5461536
OS 2.9049331 1.5425487
OS 2.9047708 1.5423059
OS 2.903529 1.536063
OS 2.9047708 1.5298201
OS 2.9083071 1.5245276
OS 2.9135996 1.5209913
OS 2.9198425 1.5197495
OS 2.9260854 1.5209913
OS 2.9313779 1.5245276
OS 2.9349142 1.5298201
OS 2.936156 1.536063
OS 2.9349142 1.5423059
OS 2.9313779 1.5475984
OS 2.9260854 1.5511347
OS 2.9198425 1.5523765
OS 2.9135996 1.5511347
OS 2.9133568 1.5509724
OS 2.9097519 1.5545773
OS 2.9099142 1.5548201
OS 2.911156 1.561063
OS 2.9099142 1.5673059
OS 2.9063779 1.5725984
OS 2.9010854 1.5761347
OS 2.8948425 1.5773765
OE
OB 1.7198425 1.5523765 H
OS 1.7135996 1.5511347
OS 1.7083071 1.5475984
OS 1.7047708 1.5423059
OS 1.703529 1.536063
OS 1.7047708 1.5298201
OS 1.7083071 1.5245276
OS 1.7135996 1.5209913
OS 1.7198425 1.5197495
OS 1.7260854 1.5209913
OS 1.7313779 1.5245276
OS 1.7349142 1.5298201
OS 1.736156 1.536063
OS 1.7349142 1.5423059
OS 1.7313779 1.5475984
OS 1.7260854 1.5511347
OS 1.7198425 1.5523765
OE
OB 1.8973025 1.5328365 H
OS 1.8910596 1.5315947
OS 1.8857671 1.5280584
OS 1.8822308 1.5227659
OS 1.880989 1.516523
OS 1.8822308 1.5102801
OS 1.8857671 1.5049876
OS 1.8910596 1.5014513
OS 1.8973025 1.5002095
OS 1.9035454 1.5014513
OS 1.9088379 1.5049876
OS 1.9123742 1.5102801
OS 1.913616 1.516523
OS 1.9123742 1.5227659
OS 1.9088379 1.5280584
OS 1.9035454 1.5315947
OS 1.8973025 1.5328365
OE
OB 4.0648425 1.5273765 H
OS 4.0585996 1.5261347
OS 4.0533071 1.5225984
OS 4.0497708 1.5173059
OS 4.048529 1.511063
OS 4.0497708 1.5048201
OS 4.0533071 1.4995276
OS 4.0585996 1.4959913
OS 4.0648425 1.4947495
OS 4.0710854 1.4959913
OS 4.0763779 1.4995276
OS 4.0799142 1.5048201
OS 4.081156 1.511063
OS 4.0799142 1.5173059
OS 4.0763779 1.5225984
OS 4.0710854 1.5261347
OS 4.0648425 1.5273765
OE
OB 3.8648425 1.5273765 H
OS 3.8585996 1.5261347
OS 3.8533071 1.5225984
OS 3.8497708 1.5173059
OS 3.848529 1.511063
OS 3.8497708 1.5048201
OS 3.8533071 1.4995276
OS 3.8585996 1.4959913
OS 3.8648425 1.4947495
OS 3.8710854 1.4959913
OS 3.8763779 1.4995276
OS 3.8799142 1.5048201
OS 3.881156 1.511063
OS 3.8799142 1.5173059
OS 3.8763779 1.5225984
OS 3.8710854 1.5261347
OS 3.8648425 1.5273765
OE
OB 2.2748425 1.5223765 H
OS 2.2685996 1.5211347
OS 2.2633071 1.5175984
OS 2.2597708 1.5123059
OS 2.258529 1.506063
OS 2.2597708 1.4998201
OS 2.2633071 1.4945276
OS 2.2685996 1.4909913
OS 2.2748425 1.4897495
OS 2.2810854 1.4909913
OS 2.2863779 1.4945276
OS 2.2899142 1.4998201
OS 2.291156 1.506063
OS 2.2899142 1.5123059
OS 2.2863779 1.5175984
OS 2.2810854 1.5211347
OS 2.2748425 1.5223765
OE
OB 3.8348425 1.4973765 H
OS 3.8285996 1.4961347
OS 3.8233071 1.4925984
OS 3.8197708 1.4873059
OS 3.818529 1.481063
OS 3.8197708 1.4748201
OS 3.8233071 1.4695276
OS 3.8285996 1.4659913
OS 3.8348425 1.4647495
OS 3.8410854 1.4659913
OS 3.8463779 1.4695276
OS 3.8499142 1.4748201
OS 3.851156 1.481063
OS 3.8499142 1.4873059
OS 3.8463779 1.4925984
OS 3.8410854 1.4961347
OS 3.8348425 1.4973765
OE
OB 2.6948425 1.4973765 H
OS 2.6885996 1.4961347
OS 2.6833071 1.4925984
OS 2.6797708 1.4873059
OS 2.678529 1.481063
OS 2.6797708 1.4748201
OS 2.6833071 1.4695276
OS 2.6885996 1.4659913
OS 2.6948425 1.4647495
OS 2.7010854 1.4659913
OS 2.7063779 1.4695276
OS 2.7099142 1.4748201
OS 2.711156 1.481063
OS 2.7099142 1.4873059
OS 2.7063779 1.4925984
OS 2.7010854 1.4961347
OS 2.6948425 1.4973765
OE
OB 3.5498425 1.4573765 H
OS 3.5435996 1.4561347
OS 3.5383071 1.4525984
OS 3.5347708 1.4473059
OS 3.533529 1.441063
OS 3.5347708 1.4348201
OS 3.5383071 1.4295276
OS 3.5435996 1.4259913
OS 3.5498425 1.4247495
OS 3.5560854 1.4259913
OS 3.5613779 1.4295276
OS 3.5649142 1.4348201
OS 3.566156 1.441063
OS 3.5649142 1.4473059
OS 3.5613779 1.4525984
OS 3.5560854 1.4561347
OS 3.5498425 1.4573765
OE
OB 2.4468425 1.4533765 H
OS 2.4405996 1.4521347
OS 2.4353071 1.4485984
OS 2.4317708 1.4433059
OS 2.430529 1.437063
OS 2.4317708 1.4308201
OS 2.4353071 1.4255276
OS 2.4405996 1.4219913
OS 2.4468425 1.4207495
OS 2.4530854 1.4219913
OS 2.4583779 1.4255276
OS 2.4619142 1.4308201
OS 2.463156 1.437063
OS 2.4619142 1.4433059
OS 2.4583779 1.4485984
OS 2.4530854 1.4521347
OS 2.4468425 1.4533765
OE
OB 1.0088425 1.4463765 H
OS 1.0025996 1.4451347
OS 0.9973071 1.4415984
OS 0.9937708 1.4363059
OS 0.992529 1.430063
OS 0.9937708 1.4238201
OS 0.9973071 1.4185276
OS 1.0025996 1.4149913
OS 1.0088425 1.4137495
OS 1.0150854 1.4149913
OS 1.0203779 1.4185276
OS 1.0239142 1.4238201
OS 1.025156 1.430063
OS 1.0239142 1.4363059
OS 1.0203779 1.4415984
OS 1.0150854 1.4451347
OS 1.0088425 1.4463765
OE
OB 2.0838425 1.4279765 H
OS 2.0775996 1.4267347
OS 2.0723071 1.4231984
OS 2.0687708 1.4179059
OS 2.067529 1.411663
OS 2.0687708 1.4054201
OS 2.0688553 1.4052937
OS 2.0669242 1.4023943
OS 2.0655495 1.4012413
OS 2.0598425 1.4023765
OS 2.0535996 1.4011347
OS 2.0483071 1.3975984
OS 2.0447708 1.3923059
OS 2.043529 1.386063
OS 2.0447708 1.3798201
OS 2.0483071 1.3745276
OS 2.0535996 1.3709913
OS 2.0598425 1.3697495
OS 2.0660854 1.3709913
OS 2.0713779 1.3745276
OS 2.0749142 1.3798201
OS 2.076156 1.386063
OS 2.0749142 1.3923059
OS 2.0748297 1.3924323
OS 2.0767608 1.3953317
OS 2.0781355 1.3964847
OS 2.0838425 1.3953495
OS 2.0900854 1.3965913
OS 2.0953779 1.4001276
OS 2.0989142 1.4054201
OS 2.100156 1.411663
OS 2.0989142 1.4179059
OS 2.0953779 1.4231984
OS 2.0900854 1.4267347
OS 2.0838425 1.4279765
OE
OB 3.4072822 1.4276365 H
OS 3.4010393 1.4263947
OS 3.3957468 1.4228584
OS 3.3922105 1.4175659
OS 3.3909687 1.411323
OS 3.3922105 1.4050801
OS 3.3952066 1.4005957
OS 3.3913778 1.3975986
OS 3.3860854 1.4011347
OS 3.3798425 1.4023765
OS 3.3735996 1.4011347
OS 3.3683071 1.3975984
OS 3.3647708 1.3923059
OS 3.363529 1.386063
OS 3.3647708 1.3798201
OS 3.3683071 1.3745276
OS 3.3735996 1.3709913
OS 3.3798425 1.3697495
OS 3.3850268 1.3707807
OS 3.3880585 1.3685992
OS 3.3892832 1.3671145
OS 3.388529 1.363323
OS 3.3897708 1.3570801
OS 3.3920261 1.3537048
OS 3.3926608 1.3527545
OS 3.3890562 1.3491499
OS 3.3882815 1.3496673
OS 3.3860854 1.3511347
OS 3.3798425 1.3523765
OS 3.3735996 1.3511347
OS 3.3683071 1.3475984
OS 3.3647708 1.3423059
OS 3.363529 1.336063
OS 3.3647708 1.3298201
OS 3.3683071 1.3245276
OS 3.3735996 1.3209913
OS 3.3798425 1.3197495
OS 3.3860854 1.3209913
OS 3.3913779 1.3245276
OS 3.3949142 1.3298201
OS 3.396156 1.336063
OS 3.3949142 1.3423059
OS 3.3926589 1.3456812
OS 3.3920242 1.3466315
OS 3.3956288 1.3502361
OS 3.3964035 1.3497187
OS 3.3985996 1.3482513
OS 3.4048425 1.3470095
OS 3.4110854 1.3482513
OS 3.4163779 1.3517876
OS 3.4199142 1.3570801
OS 3.421156 1.363323
OS 3.4199142 1.3695659
OS 3.4163779 1.3748584
OS 3.4110854 1.3783947
OS 3.4048425 1.3796365
OS 3.3996582 1.3786053
OS 3.3966265 1.3807868
OS 3.3954018 1.3822715
OS 3.396156 1.386063
OS 3.3949142 1.3923059
OS 3.3919181 1.3967903
OS 3.3957469 1.3997874
OS 3.4010393 1.3962513
OS 3.4072822 1.3950095
OS 3.4135251 1.3962513
OS 3.4188176 1.3997876
OS 3.4223539 1.4050801
OS 3.4235957 1.411323
OS 3.4223539 1.4175659
OS 3.4188176 1.4228584
OS 3.4135251 1.4263947
OS 3.4072822 1.4276365
OE
OB 0.1998425 1.4953727 H
OS 0.1872963 1.494137
OS 0.1752322 1.4904774
OS 0.1641139 1.4845346
OS 0.1543687 1.4765368
OS 0.1463709 1.4667916
OS 0.1404281 1.4556733
OS 0.1367685 1.4436092
OS 0.1355328 1.431063
OS 0.1367685 1.4185168
OS 0.1404281 1.4064527
OS 0.1463709 1.3953344
OS 0.1543687 1.3855892
OS 0.1641139 1.3775914
OS 0.1752322 1.3716486
OS 0.1872963 1.367989
OS 0.1998425 1.3667533
OS 0.2123887 1.367989
OS 0.2244528 1.3716486
OS 0.2355711 1.3775914
OS 0.2453163 1.3855892
OS 0.2533141 1.3953344
OS 0.2592569 1.4064527
OS 0.2629165 1.4185168
OS 0.2641522 1.431063
OS 0.2629165 1.4436092
OS 0.2592569 1.4556733
OS 0.2533141 1.4667916
OS 0.2453163 1.4765368
OS 0.2355711 1.4845346
OS 0.2244528 1.4904774
OS 0.2123887 1.494137
OS 0.1998425 1.4953727
OE
OB 2.0288425 1.3779765 H
OS 2.0225996 1.3767347
OS 2.0173071 1.3731984
OS 2.0137708 1.3679059
OS 2.012529 1.361663
OS 2.0137708 1.3554201
OS 2.0138553 1.3552937
OS 2.0119242 1.3523943
OS 2.0105495 1.3512413
OS 2.0048425 1.3523765
OS 1.9985996 1.3511347
OS 1.9933071 1.3475984
OS 1.9897708 1.3423059
OS 1.988529 1.336063
OS 1.9897708 1.3298201
OS 1.9933071 1.3245276
OS 1.9985996 1.3209913
OS 2.0048425 1.3197495
OS 2.0110854 1.3209913
OS 2.0163779 1.3245276
OS 2.0199142 1.3298201
OS 2.021156 1.336063
OS 2.0199142 1.3423059
OS 2.0198297 1.3424323
OS 2.0217608 1.3453317
OS 2.0231355 1.3464847
OS 2.0288425 1.3453495
OS 2.0350854 1.3465913
OS 2.0403779 1.3501276
OS 2.0439142 1.3554201
OS 2.045156 1.361663
OS 2.0439142 1.3679059
OS 2.0403779 1.3731984
OS 2.0350854 1.3767347
OS 2.0288425 1.3779765
OE
OB 2.5028425 1.3323765 H
OS 2.4965996 1.3311347
OS 2.4913071 1.3275984
OS 2.4877708 1.3223059
OS 2.486529 1.316063
OS 2.4877708 1.3098201
OS 2.4913071 1.3045276
OS 2.4965996 1.3009913
OS 2.5028425 1.2997495
OS 2.5090854 1.3009913
OS 2.5143779 1.3045276
OS 2.5179142 1.3098201
OS 2.519156 1.316063
OS 2.5179142 1.3223059
OS 2.5143779 1.3275984
OS 2.5090854 1.3311347
OS 2.5028425 1.3323765
OE
OB 1.6968325 1.3290319 H
OS 1.6894854 1.3275705
OS 1.6832568 1.3234087
OS 1.679095 1.3171801
OS 1.6776336 1.309833
OS 1.679095 1.3024859
OS 1.6832568 1.2962573
OS 1.6894854 1.2920955
OS 1.6968325 1.2906341
OS 1.7041796 1.2920955
OS 1.7104082 1.2962573
OS 1.71457 1.3024859
OS 1.7160314 1.309833
OS 1.71457 1.3171801
OS 1.7104082 1.3234087
OS 1.7041796 1.3275705
OS 1.6968325 1.3290319
OE
OB 3.5717425 1.3289919 H
OS 3.5643954 1.3275305
OS 3.5581668 1.3233687
OS 3.554005 1.3171401
OS 3.5525436 1.309793
OS 3.554005 1.3024459
OS 3.5581668 1.2962173
OS 3.5643954 1.2920555
OS 3.5717425 1.2905941
OS 3.5790896 1.2920555
OS 3.5853182 1.2962173
OS 3.58948 1.3024459
OS 3.5909414 1.309793
OS 3.58948 1.3171401
OS 3.5853182 1.3233687
OS 3.5790896 1.3275305
OS 3.5717425 1.3289919
OE
OB 1.7982283 1.3204474 H
OS 1.7919854 1.3192056
OS 1.7866929 1.3156693
OS 1.7831566 1.3103768
OS 1.7819148 1.3041339
OS 1.7831566 1.297891
OS 1.7866929 1.2925985
OS 1.7919854 1.2890622
OS 1.7982283 1.2878204
OS 1.8044712 1.2890622
OS 1.8097637 1.2925985
OS 1.8133 1.297891
OS 1.8145418 1.3041339
OS 1.8133 1.3103768
OS 1.8097637 1.3156693
OS 1.8044712 1.3192056
OS 1.7982283 1.3204474
OE
OB 2.2068425 1.3143765 H
OS 2.2005996 1.3131347
OS 2.1953071 1.3095984
OS 2.1917708 1.3043059
OS 2.190529 1.298063
OS 2.1917708 1.2918201
OS 2.1953071 1.2865276
OS 2.2005996 1.2829913
OS 2.2068425 1.2817495
OS 2.2130854 1.2829913
OS 2.2183779 1.2865276
OS 2.2219142 1.2918201
OS 2.223156 1.298063
OS 2.2219142 1.3043059
OS 2.2183779 1.3095984
OS 2.2130854 1.3131347
OS 2.2068425 1.3143765
OE
OB 1.5679134 1.3017466 H
OS 1.5616705 1.3005048
OS 1.556378 1.2969685
OS 1.5528417 1.291676
OS 1.5515999 1.2854331
OS 1.5528417 1.2791902
OS 1.556378 1.2738977
OS 1.5616705 1.2703614
OS 1.5679134 1.2691196
OS 1.5741563 1.2703614
OS 1.5794488 1.2738977
OS 1.5829851 1.2791902
OS 1.5842269 1.2854331
OS 1.5829851 1.291676
OS 1.5794488 1.2969685
OS 1.5741563 1.3005048
OS 1.5679134 1.3017466
OE
OB 0.996063 1.2033214 H
OS 0.9898201 1.2020796
OS 0.9845276 1.1985433
OS 0.9809913 1.1932508
OS 0.9797495 1.1870079
OS 0.9809913 1.180765
OS 0.9845276 1.1754725
OS 0.9898201 1.1719362
OS 0.996063 1.1706944
OS 1.0023059 1.1719362
OS 1.0075984 1.1754725
OS 1.0111347 1.180765
OS 1.0123765 1.1870079
OS 1.0111347 1.1932508
OS 1.0075984 1.1985433
OS 1.0023059 1.2020796
OS 0.996063 1.2033214
OE
OB 2.8267717 0.9926915 H
OS 2.8205288 0.9914497
OS 2.8152364 0.9879134
OS 2.8107479 0.9879134
OS 2.8054555 0.9914497
OS 2.7992126 0.9926915
OS 2.7929697 0.9914497
OS 2.7876772 0.9879134
OS 2.7864713 0.9861086
OS 2.7804578 0.9861086
OS 2.7792519 0.9879134
OS 2.7739594 0.9914497
OS 2.7677165 0.9926915
OS 2.7614736 0.9914497
OS 2.7561812 0.9879134
OS 2.7516928 0.9879134
OS 2.7464004 0.9914497
OS 2.7401575 0.9926915
OS 2.7339146 0.9914497
OS 2.7286221 0.9879134
OS 2.7274162 0.9861086
OS 2.7214027 0.9861086
OS 2.7201968 0.9879134
OS 2.7149043 0.9914497
OS 2.7086614 0.9926915
OS 2.7024185 0.9914497
OS 2.6971261 0.9879134
OS 2.6926377 0.9879134
OS 2.6873453 0.9914497
OS 2.6811024 0.9926915
OS 2.6748595 0.9914497
OS 2.669567 0.9879134
OS 2.6683611 0.9861086
OS 2.6623476 0.9861086
OS 2.6611417 0.9879134
OS 2.6558492 0.9914497
OS 2.6496063 0.9926915
OS 2.6433634 0.9914497
OS 2.638071 0.9879134
OS 2.6335825 0.9879134
OS 2.6282901 0.9914497
OS 2.6220472 0.9926915
OS 2.6158043 0.9914497
OS 2.6105118 0.9879134
OS 2.6069755 0.9826209
OS 2.6057337 0.976378
OS 2.6069755 0.9701351
OS 2.6105118 0.9648426
OS 2.6158043 0.9613063
OS 2.6220472 0.9600645
OS 2.6282901 0.9613063
OS 2.6335825 0.9648426
OS 2.638071 0.9648426
OS 2.6433634 0.9613063
OS 2.6496063 0.9600645
OS 2.6558492 0.9613063
OS 2.6611417 0.9648426
OS 2.6623476 0.9666474
OS 2.6683611 0.9666474
OS 2.669567 0.9648426
OS 2.6748595 0.9613063
OS 2.6811024 0.9600645
OS 2.6873453 0.9613063
OS 2.6926377 0.9648426
OS 2.6971261 0.9648426
OS 2.7024185 0.9613063
OS 2.7086614 0.9600645
OS 2.7149043 0.9613063
OS 2.7201968 0.9648426
OS 2.7214027 0.9666474
OS 2.7274162 0.9666474
OS 2.7286221 0.9648426
OS 2.7339146 0.9613063
OS 2.7401575 0.9600645
OS 2.7464004 0.9613063
OS 2.7516928 0.9648426
OS 2.7561812 0.9648426
OS 2.7614736 0.9613063
OS 2.7677165 0.9600645
OS 2.7739594 0.9613063
OS 2.7792519 0.9648426
OS 2.7804578 0.9666474
OS 2.7864713 0.9666474
OS 2.7876772 0.9648426
OS 2.7929697 0.9613063
OS 2.7992126 0.9600645
OS 2.8054555 0.9613063
OS 2.8107479 0.9648426
OS 2.8152364 0.9648426
OS 2.8205288 0.9613063
OS 2.8267717 0.9600645
OS 2.8330146 0.9613063
OS 2.8383071 0.9648426
OS 2.8418434 0.9701351
OS 2.8430852 0.976378
OS 2.8418434 0.9826209
OS 2.8383071 0.9879134
OS 2.8330146 0.9914497
OS 2.8267717 0.9926915
OE
OB 4.3662677 1.0459921 H
OS 4.2892441 1.0459921
OS 4.2892441 0.9689685
OS 4.3662677 0.9689685
OS 4.3662677 1.0459921
OE
OB 5.3277559 1.0463244 H
OS 5.3177023 1.0450008
OS 5.3083338 1.0411203
OS 5.300289 1.0349472
OS 5.2941159 1.0269023
OS 5.2902354 1.0175339
OS 5.2889118 1.0074803
OS 5.2902354 0.9974267
OS 5.2941159 0.9880583
OS 5.300289 0.9800134
OS 5.3083338 0.9738403
OS 5.3177023 0.9699598
OS 5.3277559 0.9686362
OS 5.3378095 0.9699598
OS 5.347178 0.9738403
OS 5.3552228 0.9800134
OS 5.3613959 0.9880583
OS 5.3652764 0.9974267
OS 5.3666 1.0074803
OS 5.3652764 1.0175339
OS 5.3613959 1.0269023
OS 5.3552228 1.0349472
OS 5.347178 1.0411203
OS 5.3378095 1.0450008
OS 5.3277559 1.0463244
OE
OB 5.1277559 1.0463244 H
OS 5.1177023 1.0450008
OS 5.1083338 1.0411203
OS 5.100289 1.0349472
OS 5.0941159 1.0269023
OS 5.0902354 1.0175339
OS 5.0889118 1.0074803
OS 5.0902354 0.9974267
OS 5.0941159 0.9880583
OS 5.100289 0.9800134
OS 5.1083338 0.9738403
OS 5.1177023 0.9699598
OS 5.1277559 0.9686362
OS 5.1378095 0.9699598
OS 5.147178 0.9738403
OS 5.1552228 0.9800134
OS 5.1613959 0.9880583
OS 5.1652764 0.9974267
OS 5.1666 1.0074803
OS 5.1652764 1.0175339
OS 5.1613959 1.0269023
OS 5.1552228 1.0349472
OS 5.147178 1.0411203
OS 5.1378095 1.0450008
OS 5.1277559 1.0463244
OE
OB 4.9277559 1.0463244 H
OS 4.9177023 1.0450008
OS 4.9083338 1.0411203
OS 4.900289 1.0349472
OS 4.8941159 1.0269023
OS 4.8902354 1.0175339
OS 4.8889118 1.0074803
OS 4.8902354 0.9974267
OS 4.8941159 0.9880583
OS 4.900289 0.9800134
OS 4.9083338 0.9738403
OS 4.9177023 0.9699598
OS 4.9277559 0.9686362
OS 4.9378095 0.9699598
OS 4.947178 0.9738403
OS 4.9552228 0.9800134
OS 4.9613959 0.9880583
OS 4.9652764 0.9974267
OS 4.9666 1.0074803
OS 4.9652764 1.0175339
OS 4.9613959 1.0269023
OS 4.9552228 1.0349472
OS 4.947178 1.0411203
OS 4.9378095 1.0450008
OS 4.9277559 1.0463244
OE
OB 2.9905425 0.9777919 H
OS 2.9831954 0.9763305
OS 2.9769668 0.9721687
OS 2.972805 0.9659401
OS 2.9713436 0.958593
OS 2.972805 0.9512459
OS 2.9769668 0.9450173
OS 2.9831954 0.9408555
OS 2.9905425 0.9393941
OS 2.9978896 0.9408555
OS 3.0041182 0.9450173
OS 3.00828 0.9512459
OS 3.0097414 0.958593
OS 3.00828 0.9659401
OS 3.0041182 0.9721687
OS 2.9978896 0.9763305
OS 2.9905425 0.9777919
OE
OB 2.2031425 0.9777919 H
OS 2.1957954 0.9763305
OS 2.1895668 0.9721687
OS 2.185405 0.9659401
OS 2.1839436 0.958593
OS 2.185405 0.9512459
OS 2.1895668 0.9450173
OS 2.1957954 0.9408555
OS 2.2031425 0.9393941
OS 2.2104896 0.9408555
OS 2.2167182 0.9450173
OS 2.22088 0.9512459
OS 2.2223414 0.958593
OS 2.22088 0.9659401
OS 2.2167182 0.9721687
OS 2.2104896 0.9763305
OS 2.2031425 0.9777919
OE
OB 2.4788425 0.9533765 H
OS 2.4725996 0.9521347
OS 2.4673071 0.9485984
OS 2.4637708 0.9433059
OS 2.462529 0.937063
OS 2.4637708 0.9308201
OS 2.4673071 0.9255276
OS 2.4725996 0.9219913
OS 2.4788425 0.9207495
OS 2.4850854 0.9219913
OS 2.4903779 0.9255276
OS 2.4939142 0.9308201
OS 2.495156 0.937063
OS 2.4939142 0.9433059
OS 2.4903779 0.9485984
OS 2.4850854 0.9521347
OS 2.4788425 0.9533765
OE
OB 1.0048425 0.9223765 H
OS 0.9985996 0.9211347
OS 0.9933071 0.9175984
OS 0.9897708 0.9123059
OS 0.988529 0.906063
OS 0.9897708 0.8998201
OS 0.9933071 0.8945276
OS 0.9985996 0.8909913
OS 1.0048425 0.8897495
OS 1.0110854 0.8909913
OS 1.0163779 0.8945276
OS 1.0199142 0.8998201
OS 1.021156 0.906063
OS 1.0199142 0.9123059
OS 1.0163779 0.9175984
OS 1.0110854 0.9211347
OS 1.0048425 0.9223765
OE
OB 3.6179425 0.9836725 H
OS 3.6047974 0.9823778
OS 3.5921575 0.9785435
OS 3.5805085 0.972317
OS 3.570298 0.9639375
OS 3.5619185 0.953727
OS 3.555692 0.942078
OS 3.5518577 0.9294381
OS 3.550563 0.916293
OS 3.5518577 0.9031479
OS 3.555692 0.890508
OS 3.5619185 0.878859
OS 3.570298 0.8686485
OS 3.5805085 0.860269
OS 3.5921575 0.8540425
OS 3.6047974 0.8502082
OS 3.6179425 0.8489135
OS 3.6310876 0.8502082
OS 3.6437275 0.8540425
OS 3.6553765 0.860269
OS 3.665587 0.8686485
OS 3.6739665 0.878859
OS 3.680193 0.890508
OS 3.6840273 0.9031479
OS 3.685322 0.916293
OS 3.6840273 0.9294381
OS 3.680193 0.942078
OS 3.6739665 0.953727
OS 3.665587 0.9639375
OS 3.6553765 0.972317
OS 3.6437275 0.9785435
OS 3.6310876 0.9823778
OS 3.6179425 0.9836725
OE
OB 1.6529425 0.9836725 H
OS 1.6397974 0.9823778
OS 1.6271575 0.9785435
OS 1.6155085 0.972317
OS 1.605298 0.9639375
OS 1.5969185 0.953727
OS 1.590692 0.942078
OS 1.5868577 0.9294381
OS 1.585563 0.916293
OS 1.5868577 0.9031479
OS 1.590692 0.890508
OS 1.5969185 0.878859
OS 1.605298 0.8686485
OS 1.6155085 0.860269
OS 1.6271575 0.8540425
OS 1.6397974 0.8502082
OS 1.6529425 0.8489135
OS 1.6660876 0.8502082
OS 1.6787275 0.8540425
OS 1.6903765 0.860269
OS 1.700587 0.8686485
OS 1.7089665 0.878859
OS 1.715193 0.890508
OS 1.7190273 0.9031479
OS 1.720322 0.916293
OS 1.7190273 0.9294381
OS 1.715193 0.942078
OS 1.7089665 0.953727
OS 1.700587 0.9639375
OS 1.6903765 0.972317
OS 1.6787275 0.9785435
OS 1.6660876 0.9823778
OS 1.6529425 0.9836725
OE
OB 5.5781524 0.9365112 H
OS 5.5662745 0.9349474
OS 5.5552061 0.9303628
OS 5.5457014 0.9230696
OS 5.5384082 0.9135649
OS 5.5338236 0.9024965
OS 5.5322598 0.8906186
OS 5.5338236 0.8787407
OS 5.5384082 0.8676723
OS 5.5457014 0.8581676
OS 5.5552061 0.8508744
OS 5.5662745 0.8462898
OS 5.5781524 0.844726
OS 5.5900303 0.8462898
OS 5.6010987 0.8508744
OS 5.6106034 0.8581676
OS 5.6178966 0.8676723
OS 5.6224812 0.8787407
OS 5.624045 0.8906186
OS 5.6224812 0.9024965
OS 5.6178966 0.9135649
OS 5.6106034 0.9230696
OS 5.6010987 0.9303628
OS 5.5900303 0.9349474
OS 5.5781524 0.9365112
OE
OB 3.9797272 0.9365112 H
OS 3.9678493 0.9349474
OS 3.9567809 0.9303628
OS 3.9472762 0.9230696
OS 3.939983 0.9135649
OS 3.9353984 0.9024965
OS 3.9338346 0.8906186
OS 3.9353984 0.8787407
OS 3.939983 0.8676723
OS 3.9472762 0.8581676
OS 3.9567809 0.8508744
OS 3.9678493 0.8462898
OS 3.9797272 0.844726
OS 3.9916051 0.8462898
OS 4.0026735 0.8508744
OS 4.0121782 0.8581676
OS 4.0194714 0.8676723
OS 4.024056 0.8787407
OS 4.0256198 0.8906186
OS 4.024056 0.9024965
OS 4.0194714 0.9135649
OS 4.0121782 0.9230696
OS 4.0026735 0.9303628
OS 3.9916051 0.9349474
OS 3.9797272 0.9365112
OE
OB 0.1998425 0.9703727 H
OS 0.1872963 0.969137
OS 0.1752322 0.9654774
OS 0.1641139 0.9595346
OS 0.1543687 0.9515368
OS 0.1463709 0.9417916
OS 0.1404281 0.9306733
OS 0.1367685 0.9186092
OS 0.1355328 0.906063
OS 0.1367685 0.8935168
OS 0.1404281 0.8814527
OS 0.1463709 0.8703344
OS 0.1543687 0.8605892
OS 0.1641139 0.8525914
OS 0.1752322 0.8466486
OS 0.1872963 0.842989
OS 0.1998425 0.8417533
OS 0.2123887 0.842989
OS 0.2244528 0.8466486
OS 0.2355711 0.8525914
OS 0.2453163 0.8605892
OS 0.2533141 0.8703344
OS 0.2592569 0.8814527
OS 0.2629165 0.8935168
OS 0.2641522 0.906063
OS 0.2629165 0.9186092
OS 0.2592569 0.9306733
OS 0.2533141 0.9417916
OS 0.2453163 0.9515368
OS 0.2355711 0.9595346
OS 0.2244528 0.9654774
OS 0.2123887 0.969137
OS 0.1998425 0.9703727
OE
OB 2.7598425 0.8115891 H
OS 2.7535996 0.8103473
OS 2.7483072 0.806811
OS 2.7438188 0.806811
OS 2.7385264 0.8103473
OS 2.7322835 0.8115891
OS 2.7260406 0.8103473
OS 2.7207481 0.806811
OS 2.7172118 0.8015185
OS 2.71597 0.7952756
OS 2.7172118 0.7890327
OS 2.7207481 0.7837402
OS 2.7260406 0.7802039
OS 2.7322835 0.7789621
OS 2.7385264 0.7802039
OS 2.7438188 0.7837402
OS 2.7483072 0.7837402
OS 2.7535996 0.7802039
OS 2.7598425 0.7789621
OS 2.7660854 0.7802039
OS 2.7713779 0.7837402
OS 2.7749142 0.7890327
OS 2.776156 0.7952756
OS 2.7749142 0.8015185
OS 2.7713779 0.806811
OS 2.7660854 0.8103473
OS 2.7598425 0.8115891
OE
OB 2.6929134 0.8115891 H
OS 2.6866705 0.8103473
OS 2.6813781 0.806811
OS 2.6768896 0.806811
OS 2.6715972 0.8103473
OS 2.6653543 0.8115891
OS 2.6591114 0.8103473
OS 2.6538189 0.806811
OS 2.6502826 0.8015185
OS 2.6490408 0.7952756
OS 2.6502826 0.7890327
OS 2.6538189 0.7837402
OS 2.6591114 0.7802039
OS 2.6653543 0.7789621
OS 2.6715972 0.7802039
OS 2.6768896 0.7837402
OS 2.6813781 0.7837402
OS 2.6866705 0.7802039
OS 2.6929134 0.7789621
OS 2.6991563 0.7802039
OS 2.7044488 0.7837402
OS 2.7079851 0.7890327
OS 2.7092269 0.7952756
OS 2.7079851 0.8015185
OS 2.7044488 0.806811
OS 2.6991563 0.8103473
OS 2.6929134 0.8115891
OE
OB 2.6259843 0.8115891 H
OS 2.6197414 0.8103473
OS 2.614449 0.806811
OS 2.6099605 0.806811
OS 2.6046681 0.8103473
OS 2.5984252 0.8115891
OS 2.5921823 0.8103473
OS 2.5868898 0.806811
OS 2.5833535 0.8015185
OS 2.5821117 0.7952756
OS 2.5833535 0.7890327
OS 2.5868898 0.7837402
OS 2.5921823 0.7802039
OS 2.5984252 0.7789621
OS 2.6046681 0.7802039
OS 2.6099605 0.7837402
OS 2.614449 0.7837402
OS 2.6197414 0.7802039
OS 2.6259843 0.7789621
OS 2.6322272 0.7802039
OS 2.6375197 0.7837402
OS 2.641056 0.7890327
OS 2.6422978 0.7952756
OS 2.641056 0.8015185
OS 2.6375197 0.806811
OS 2.6322272 0.8103473
OS 2.6259843 0.8115891
OE
OB 2.8937008 0.8115891 H
OS 2.8874579 0.8103473
OS 2.8821654 0.806811
OS 2.8809595 0.8050062
OS 2.874946 0.8050062
OS 2.8737401 0.806811
OS 2.8684476 0.8103473
OS 2.8622047 0.8115891
OS 2.8559618 0.8103473
OS 2.8506693 0.806811
OS 2.847133 0.8015185
OS 2.8470372 0.8010368
OS 2.8419392 0.8010368
OS 2.8418434 0.8015185
OS 2.8383071 0.806811
OS 2.8330146 0.8103473
OS 2.8267717 0.8115891
OS 2.8205288 0.8103473
OS 2.8152364 0.806811
OS 2.8107479 0.806811
OS 2.8054555 0.8103473
OS 2.7992126 0.8115891
OS 2.7929697 0.8103473
OS 2.7876772 0.806811
OS 2.7841409 0.8015185
OS 2.7828991 0.7952756
OS 2.7841409 0.7890327
OS 2.7876772 0.7837402
OS 2.7929697 0.7802039
OS 2.7992126 0.7789621
OS 2.8054555 0.7802039
OS 2.8107479 0.7837402
OS 2.8152364 0.7837402
OS 2.8205288 0.7802039
OS 2.8267717 0.7789621
OS 2.8330146 0.7802039
OS 2.8383071 0.7837402
OS 2.8418434 0.7890327
OS 2.8419392 0.7895144
OS 2.8470372 0.7895144
OS 2.847133 0.7890327
OS 2.8506693 0.7837402
OS 2.8559618 0.7802039
OS 2.8622047 0.7789621
OS 2.8684476 0.7802039
OS 2.8737401 0.7837402
OS 2.874946 0.785545
OS 2.8809595 0.785545
OS 2.8821654 0.7837402
OS 2.8874579 0.7802039
OS 2.8937008 0.7789621
OS 2.8999437 0.7802039
OS 2.9052362 0.7837402
OS 2.9087725 0.7890327
OS 2.9100143 0.7952756
OS 2.9087725 0.8015185
OS 2.9052362 0.806811
OS 2.8999437 0.8103473
OS 2.8937008 0.8115891
OE
OB 0.9901575 0.7033214 H
OS 0.9839146 0.7020796
OS 0.9786221 0.6985433
OS 0.9750858 0.6932508
OS 0.973844 0.6870079
OS 0.9750858 0.680765
OS 0.9786221 0.6754725
OS 0.9839146 0.6719362
OS 0.9901575 0.6706944
OS 0.9964004 0.6719362
OS 1.0016929 0.6754725
OS 1.0052292 0.680765
OS 1.006471 0.6870079
OS 1.0052292 0.6932508
OS 1.0016929 0.6985433
OS 0.9964004 0.7020796
OS 0.9901575 0.7033214
OE
OB 2.4698827 0.4273018 H
OS 2.4636398 0.42606
OS 2.4583473 0.4225237
OS 2.454811 0.4172312
OS 2.4535692 0.4109883
OS 2.454811 0.4047454
OS 2.4583473 0.3994529
OS 2.4636398 0.3959166
OS 2.4698827 0.3946748
OS 2.4761256 0.3959166
OS 2.4814181 0.3994529
OS 2.4849544 0.4047454
OS 2.4861962 0.4109883
OS 2.4849544 0.4172312
OS 2.4814181 0.4225237
OS 2.4761256 0.42606
OS 2.4698827 0.4273018
OE
OB 2.980457 0.4254674 H
OS 2.9742141 0.4242256
OS 2.9689216 0.4206893
OS 2.9653853 0.4153968
OS 2.9641435 0.4091539
OS 2.9653853 0.402911
OS 2.9689216 0.3976185
OS 2.9742141 0.3940822
OS 2.980457 0.3928404
OS 2.9866999 0.3940822
OS 2.9919924 0.3976185
OS 2.9955287 0.402911
OS 2.9967705 0.4091539
OS 2.9955287 0.4153968
OS 2.9919924 0.4206893
OS 2.9866999 0.4242256
OS 2.980457 0.4254674
OE
OB 3.019685 0.4218253 H
OS 3.0134421 0.4205835
OS 3.0081496 0.4170472
OS 3.0046133 0.4117547
OS 3.0033715 0.4055118
OS 3.0046133 0.3992689
OS 3.0081496 0.3939764
OS 3.0134421 0.3904401
OS 3.019685 0.3891983
OS 3.0259279 0.3904401
OS 3.0312204 0.3939764
OS 3.0347567 0.3992689
OS 3.0359985 0.4055118
OS 3.0347567 0.4117547
OS 3.0312204 0.4170472
OS 3.0259279 0.4205835
OS 3.019685 0.4218253
OE
OB 2.8219832 0.4241654 H
OS 2.8157403 0.4229236
OS 2.8104478 0.4193873
OS 2.8069115 0.4140948
OS 2.8056697 0.4078519
OS 2.8069115 0.401609
OS 2.8104478 0.3963165
OS 2.8157403 0.3927802
OS 2.8219832 0.3915384
OS 2.8282261 0.3927802
OS 2.8335186 0.3963165
OS 2.8345973 0.3979309
OS 2.8352825 0.3981275
OS 2.8403819 0.3975883
OS 2.8427953 0.3939764
OS 2.8480878 0.3904401
OS 2.8543307 0.3891983
OS 2.8605736 0.3904401
OS 2.8658661 0.3939764
OS 2.8694024 0.3992689
OS 2.8706442 0.4055118
OS 2.8694024 0.4117547
OS 2.8658661 0.4170472
OS 2.8605736 0.4205835
OS 2.8543307 0.4218253
OS 2.8480878 0.4205835
OS 2.8427953 0.4170472
OS 2.8417166 0.4154328
OS 2.8410314 0.4152362
OS 2.835932 0.4157754
OS 2.8335186 0.4193873
OS 2.8282261 0.4229236
OS 2.8219832 0.4241654
OE
OB 2.7047244 0.4218253 H
OS 2.6984815 0.4205835
OS 2.693189 0.4170472
OS 2.6896527 0.4117547
OS 2.6884109 0.4055118
OS 2.6896527 0.3992689
OS 2.693189 0.3939764
OS 2.6984815 0.3904401
OS 2.7047244 0.3891983
OS 2.7109673 0.3904401
OS 2.7162598 0.3939764
OS 2.7197961 0.3992689
OS 2.7210379 0.4055118
OS 2.7197961 0.4117547
OS 2.7162598 0.4170472
OS 2.7109673 0.4205835
OS 2.7047244 0.4218253
OE
OB 2.6653543 0.4218253 H
OS 2.6591114 0.4205835
OS 2.6538189 0.4170472
OS 2.6502826 0.4117547
OS 2.6490408 0.4055118
OS 2.6502826 0.3992689
OS 2.6538189 0.3939764
OS 2.6591114 0.3904401
OS 2.6653543 0.3891983
OS 2.6715972 0.3904401
OS 2.6768897 0.3939764
OS 2.680426 0.3992689
OS 2.6816678 0.4055118
OS 2.680426 0.4117547
OS 2.6768897 0.4170472
OS 2.6715972 0.4205835
OS 2.6653543 0.4218253
OE
OB 2.511811 0.4218253 H
OS 2.5055681 0.4205835
OS 2.5002756 0.4170472
OS 2.4967393 0.4117547
OS 2.4954975 0.4055118
OS 2.4967393 0.3992689
OS 2.5002756 0.3939764
OS 2.5055681 0.3904401
OS 2.511811 0.3891983
OS 2.5180539 0.3904401
OS 2.5233464 0.3939764
OS 2.5268827 0.3992689
OS 2.5281245 0.4055118
OS 2.5268827 0.4117547
OS 2.5233464 0.4170472
OS 2.5180539 0.4205835
OS 2.511811 0.4218253
OE
OB 2.3897638 0.4218253 H
OS 2.3835209 0.4205835
OS 2.3782284 0.4170472
OS 2.3746921 0.4117547
OS 2.3734503 0.4055118
OS 2.3746921 0.3992689
OS 2.3782284 0.3939764
OS 2.3835209 0.3904401
OS 2.3897638 0.3891983
OS 2.3960067 0.3904401
OS 2.4012992 0.3939764
OS 2.4048355 0.3992689
OS 2.4060773 0.4055118
OS 2.4048355 0.4117547
OS 2.4012992 0.4170472
OS 2.3960067 0.4205835
OS 2.3897638 0.4218253
OE
OB 2.3503937 0.4218253 H
OS 2.3441508 0.4205835
OS 2.3388583 0.4170472
OS 2.335322 0.4117547
OS 2.3340802 0.4055118
OS 2.335322 0.3992689
OS 2.3388583 0.3939764
OS 2.3441508 0.3904401
OS 2.3503937 0.3891983
OS 2.3566366 0.3904401
OS 2.3619291 0.3939764
OS 2.3654654 0.3992689
OS 2.3667072 0.4055118
OS 2.3654654 0.4117547
OS 2.3619291 0.4170472
OS 2.3566366 0.4205835
OS 2.3503937 0.4218253
OE
OB 1.8720472 0.3037151 H
OS 1.8658043 0.3024733
OS 1.8622047 0.3000681
OS 1.8586051 0.3024733
OS 1.8523622 0.3037151
OS 1.8461193 0.3024733
OS 1.8425197 0.3000681
OS 1.83892 0.3024733
OS 1.8326771 0.3037151
OS 1.8264342 0.3024733
OS 1.8211417 0.298937
OS 1.8176054 0.2936445
OS 1.8163636 0.2874016
OS 1.8176054 0.2811587
OS 1.8211417 0.2758662
OS 1.8229465 0.2746603
OS 1.8229465 0.2686468
OS 1.8211417 0.2674409
OS 1.8176054 0.2621484
OS 1.8163636 0.2559055
OS 1.8176054 0.2496626
OS 1.8211417 0.2443701
OS 1.8264342 0.2408338
OS 1.8326771 0.239592
OS 1.83892 0.2408338
OS 1.8425197 0.243239
OS 1.8461193 0.2408338
OS 1.8523622 0.239592
OS 1.8586051 0.2408338
OS 1.8622047 0.243239
OS 1.8658043 0.2408338
OS 1.8720472 0.239592
OS 1.8782901 0.2408338
OS 1.8835826 0.2443701
OS 1.8871189 0.2496626
OS 1.8883607 0.2559055
OS 1.8871189 0.2621484
OS 1.8835826 0.2674409
OS 1.8817778 0.2686468
OS 1.8817778 0.2746603
OS 1.8835826 0.2758662
OS 1.8871189 0.2811587
OS 1.8883607 0.2874016
OS 1.8871189 0.2936445
OS 1.8835826 0.298937
OS 1.8782901 0.3024733
OS 1.8720472 0.3037151
OE
OB 2.1122047 0.3037151 H
OS 2.1059618 0.3024733
OS 2.1006693 0.298937
OS 2.097133 0.2936445
OS 2.0970371 0.2931626
OS 2.0919392 0.2931626
OS 2.0918433 0.2936445
OS 2.088307 0.298937
OS 2.0830145 0.3024733
OS 2.0767716 0.3037151
OS 2.0705287 0.3024733
OS 2.0652362 0.298937
OS 2.0616999 0.2936445
OS 2.0604581 0.2874016
OS 2.0616999 0.2811587
OS 2.0652362 0.2758662
OS 2.067041 0.2746603
OS 2.067041 0.2686468
OS 2.0652362 0.2674409
OS 2.0616999 0.2621484
OS 2.0604581 0.2559055
OS 2.0616999 0.2496626
OS 2.0652362 0.2443701
OS 2.0705287 0.2408338
OS 2.0767716 0.239592
OS 2.0830145 0.2408338
OS 2.088307 0.2443701
OS 2.0918433 0.2496626
OS 2.0919392 0.2501445
OS 2.0970371 0.2501445
OS 2.097133 0.2496626
OS 2.1006693 0.2443701
OS 2.1059618 0.2408338
OS 2.1122047 0.239592
OS 2.1184476 0.2408338
OS 2.1237401 0.2443701
OS 2.1272764 0.2496626
OS 2.1285182 0.2559055
OS 2.1272764 0.2621484
OS 2.1237401 0.2674409
OS 2.1219353 0.2686468
OS 2.1219353 0.2746603
OS 2.1237401 0.2758662
OS 2.1272764 0.2811587
OS 2.1285182 0.2874016
OS 2.1272764 0.2936445
OS 2.1237401 0.298937
OS 2.1184476 0.3024733
OS 2.1122047 0.3037151
OE
OB 2.6102362 0.2958411 H
OS 2.6039933 0.2945993
OS 2.5987008 0.291063
OS 2.5974949 0.2892583
OS 2.5914815 0.2892583
OS 2.5902756 0.291063
OS 2.5849831 0.2945993
OS 2.5787402 0.2958411
OS 2.5724973 0.2945993
OS 2.5672048 0.291063
OS 2.5636685 0.2857705
OS 2.5624267 0.2795276
OS 2.5636685 0.2732847
OS 2.5672048 0.2679922
OS 2.5724973 0.2644559
OS 2.5787402 0.2632141
OS 2.5849831 0.2644559
OS 2.5902756 0.2679922
OS 2.5914815 0.2697969
OS 2.5974949 0.2697969
OS 2.5987008 0.2679922
OS 2.6039933 0.2644559
OS 2.6102362 0.2632141
OS 2.6164791 0.2644559
OS 2.6217716 0.2679922
OS 2.6253079 0.2732847
OS 2.6265497 0.2795276
OS 2.6253079 0.2857705
OS 2.6217716 0.291063
OS 2.6164791 0.2945993
OS 2.6102362 0.2958411
OE
OB 2.4448819 0.2958411 H
OS 2.438639 0.2945993
OS 2.4333465 0.291063
OS 2.4321406 0.2892582
OS 2.4261271 0.2892582
OS 2.4249212 0.291063
OS 2.4196287 0.2945993
OS 2.4133858 0.2958411
OS 2.4071429 0.2945993
OS 2.4018504 0.291063
OS 2.3983141 0.2857705
OS 2.3970723 0.2795276
OS 2.3983141 0.2732847
OS 2.4018504 0.2679922
OS 2.4071429 0.2644559
OS 2.4133858 0.2632141
OS 2.4196287 0.2644559
OS 2.4249212 0.2679922
OS 2.4261271 0.269797
OS 2.4321406 0.269797
OS 2.4333465 0.2679922
OS 2.438639 0.2644559
OS 2.4448819 0.2632141
OS 2.4511248 0.2644559
OS 2.4564173 0.2679922
OS 2.4599536 0.2732847
OS 2.4611954 0.2795276
OS 2.4599536 0.2857705
OS 2.4564173 0.291063
OS 2.4511248 0.2945993
OS 2.4448819 0.2958411
OE
OB 2.9370079 0.2958411 H
OS 2.930765 0.2945993
OS 2.9254725 0.291063
OS 2.9242523 0.2892367
OS 2.9182388 0.2892367
OS 2.91703 0.2910458
OS 2.9117375 0.2945821
OS 2.9054946 0.2958239
OS 2.8992517 0.2945821
OS 2.8939592 0.2910458
OS 2.8904229 0.2857533
OS 2.8891811 0.2795104
OS 2.8904229 0.2732675
OS 2.8939592 0.267975
OS 2.8992517 0.2644387
OS 2.9054946 0.2631969
OS 2.9117375 0.2644387
OS 2.91703 0.267975
OS 2.9182502 0.2698013
OS 2.9242637 0.2698013
OS 2.9254725 0.2679922
OS 2.930765 0.2644559
OS 2.9370079 0.2632141
OS 2.9432508 0.2644559
OS 2.9485433 0.2679922
OS 2.9520796 0.2732847
OS 2.9533214 0.2795276
OS 2.9520796 0.2857705
OS 2.9485433 0.291063
OS 2.9432508 0.2945993
OS 2.9370079 0.2958411
OE
OB 2.74882 0.2986255 H
OS 2.7425771 0.2973837
OS 2.7372846 0.2938474
OS 2.7337483 0.2885549
OS 2.7325065 0.282312
OS 2.7337483 0.2760691
OS 2.7372846 0.2707766
OS 2.7425771 0.2672403
OS 2.74882 0.2659985
OS 2.7550629 0.2672403
OS 2.7603553 0.2707766
OS 2.7662503 0.2705991
OS 2.7679922 0.2679922
OS 2.7732847 0.2644559
OS 2.7795276 0.2632141
OS 2.7857705 0.2644559
OS 2.791063 0.2679922
OS 2.7945993 0.2732847
OS 2.7958411 0.2795276
OS 2.7945993 0.2857705
OS 2.791063 0.291063
OS 2.7857705 0.2945993
OS 2.7795276 0.2958411
OS 2.7732847 0.2945993
OS 2.7679923 0.291063
OS 2.7620973 0.2912405
OS 2.7603554 0.2938474
OS 2.7550629 0.2973837
OS 2.74882 0.2986255
OE
OB 2.1515748 0.3037151 H
OS 2.1453319 0.3024733
OS 2.1400394 0.298937
OS 2.1365031 0.2936445
OS 2.1352613 0.2874016
OS 2.1365031 0.2811587
OS 2.1400394 0.2758662
OS 2.1418442 0.2746603
OS 2.1418442 0.2686468
OS 2.1400394 0.2674409
OS 2.1365031 0.2621484
OS 2.1352613 0.2559055
OS 2.1365031 0.2496626
OS 2.1400394 0.2443701
OS 2.1453319 0.2408338
OS 2.1515748 0.239592
OS 2.1578177 0.2408338
OS 2.1631102 0.2443701
OS 2.1666465 0.2496626
OS 2.1678883 0.2559055
OS 2.1666465 0.2621484
OS 2.1631102 0.2674409
OS 2.1613054 0.2686468
OS 2.1613054 0.2746603
OS 2.1631102 0.2758662
OS 2.1666465 0.2811587
OS 2.1678883 0.2874016
OS 2.1666465 0.2936445
OS 2.1631102 0.298937
OS 2.1578177 0.3024733
OS 2.1515748 0.3037151
OE
OB 0.2854331 0.5015215 H
OS 0.264563 0.499879
OS 0.2442067 0.4949919
OS 0.2248656 0.4869805
OS 0.2070159 0.4760422
OS 0.1910971 0.4624462
OS 0.1775011 0.4465274
OS 0.1665628 0.4286777
OS 0.1585514 0.4093366
OS 0.1536643 0.3889803
OS 0.1520218 0.3681102
OS 0.1536643 0.3472401
OS 0.1585514 0.3268838
OS 0.1665628 0.3075427
OS 0.1775011 0.289693
OS 0.1910971 0.2737742
OS 0.2070159 0.2601782
OS 0.2248656 0.2492399
OS 0.2442067 0.2412285
OS 0.264563 0.2363414
OS 0.2854331 0.2346989
OS 0.3063032 0.2363414
OS 0.3266595 0.2412285
OS 0.3460006 0.2492399
OS 0.3638503 0.2601782
OS 0.3797691 0.2737742
OS 0.3933651 0.289693
OS 0.4043034 0.3075427
OS 0.4123148 0.3268838
OS 0.4172019 0.3472401
OS 0.4188444 0.3681102
OS 0.4172019 0.3889803
OS 0.4123148 0.4093366
OS 0.4043034 0.4286777
OS 0.3933651 0.4465274
OS 0.3797691 0.4624462
OS 0.3638503 0.4760422
OS 0.3460006 0.4869805
OS 0.3266595 0.4949919
OS 0.3063032 0.499879
OS 0.2854331 0.5015215
OE
SE
P 0.149508 2.830047 9 P 0 0 ;0=7,1=1
P 0.149508 3.853669 9 P 0 0 ;0=7,1=1
P 0.6538425 1.551063 8 P 0 0 ;0=6,1=1
P 0.6539669 2.5938902 8 P 0 0 ;0=6,1=1
P 0.6548425 0.790063 8 P 0 0 ;0=6,1=1
P 0.6548425 1.314063 8 P 0 0 ;0=6,1=1
P 0.6548425 1.839063 8 P 0 0 ;0=6,1=1
P 0.6548425 2.073063 8 P 0 0 ;0=6,1=1
P 0.6548425 2.365063 8 P 0 0 ;0=6,1=1
P 0.6558425 1.028063 8 P 0 0 ;0=6,1=1
P 0.9370078 2.3179133 8 P 0 0 ;0=6,1=1
P 1.2428425 1.472063 8 P 0 0 ;0=6,1=1
P 1.2488425 2.000063 8 P 0 0 ;0=6,1=1
P 1.2568425 0.942063 8 P 0 0 ;0=6,1=1
P 1.2618425 2.482063 8 P 0 0 ;0=6,1=1
P 1.6708425 1.595063 8 P 0 0 ;0=6,1=1
P 1.6708425 1.694063 8 P 0 0 ;0=6,1=1
P 1.6718425 1.399063 8 P 0 0 ;0=6,1=1
P 1.6718425 1.497063 8 P 0 0 ;0=6,1=1
P 1.6718425 1.792063 8 P 0 0 ;0=6,1=1
P 1.6748425 1.989063 8 P 0 0 ;0=6,1=1
P 1.6758425 1.891063 8 P 0 0 ;0=6,1=1
P 1.6918425 4.079063 8 P 0 0 ;0=6,1=1
P 1.7148425 1.595063 8 P 0 0 ;0=6,1=1
P 1.7168425 1.399063 8 P 0 0 ;0=6,1=1
P 1.7188425 1.497063 8 P 0 0 ;0=6,1=1
P 1.7188425 1.792063 8 P 0 0 ;0=6,1=1
P 1.7218425 1.694063 8 P 0 0 ;0=6,1=1
P 1.7218425 1.890063 8 P 0 0 ;0=6,1=1
P 1.7218425 1.989063 8 P 0 0 ;0=6,1=1
P 1.7268425 4.329374 8 P 0 0 ;0=6,1=1
P 1.7498425 4.110063 8 P 0 0 ;0=6,1=1
P 1.7888425 4.329374 8 P 0 0 ;0=6,1=1
P 1.9161425 0.244763 8 P 0 0 ;0=6,1=1
P 2.0348425 0.246063 8 P 0 0 ;0=6,1=1
P 2.1398425 3.738063 8 P 0 0 ;0=6,1=1
P 2.2538425 2.279063 8 P 0 0 ;0=6,1=1
P 2.2588425 3.741063 8 P 0 0 ;0=6,1=1
P 2.2908425 4.217063 8 P 0 0 ;0=6,1=1
P 2.3098425 0.246063 8 P 0 0 ;0=6,1=1
P 2.3114125 1.0900094 8 P 0 0 ;0=6,1=1
P 2.3118425 0.934063 8 P 0 0 ;0=6,1=1
P 2.3215354 2.586063 8 P 0 0 ;0=6,1=1
P 2.3215354 3.361063 8 P 0 0 ;0=6,1=1
P 2.4048425 2.412063 8 P 0 0 ;0=6,1=1
P 2.4098325 0.932053 8 P 0 0 ;0=6,1=1
P 2.4098325 1.088053 8 P 0 0 ;0=6,1=1
P 2.4098425 2.579063 8 P 0 0 ;0=6,1=1
P 2.4138425 3.295063 8 P 0 0 ;0=6,1=1
P 2.4192759 2.7886295 8 P 0 0 ;0=6,1=1
P 2.4470546 0.2425914 8 P 0 0 ;0=6,1=1
P 2.4738425 2.980063 8 P 0 0 ;0=6,1=1
P 2.4758425 2.456063 8 P 0 0 ;0=6,1=1
P 2.4888425 2.413063 8 P 0 0 ;0=6,1=1
P 2.5082625 0.931483 8 P 0 0 ;0=6,1=1
P 2.5088425 1.090063 8 P 0 0 ;0=6,1=1
P 2.531398 2.830047 9 P 0 0 ;0=7,1=1
P 2.531398 3.853669 9 P 0 0 ;0=7,1=1
P 2.5460625 0.244843 8 P 0 0 ;0=6,1=1
P 2.5818425 2.308063 8 P 0 0 ;0=6,1=1
P 2.5868425 2.569063 8 P 0 0 ;0=6,1=1
P 2.6066825 0.931903 8 P 0 0 ;0=6,1=1
P 2.6068425 1.091063 8 P 0 0 ;0=6,1=1
P 2.6318425 2.876063 8 P 0 0 ;0=6,1=1
P 2.636874 0.2479055 8 P 0 0 ;0=6,1=1
P 2.6658425 1.092063 8 P 0 0 ;0=6,1=1
P 2.6748425 3.501063 8 P 0 0 ;0=6,1=1
P 2.6858425 2.311063 8 P 0 0 ;0=6,1=1
P 2.6858425 2.568063 8 P 0 0 ;0=6,1=1
P 2.7244825 1.093063 8 P 0 0 ;0=6,1=1
P 2.7248425 3.521063 8 P 0 0 ;0=6,1=1
P 2.7248425 3.729063 8 P 0 0 ;0=6,1=1
P 2.7838425 2.429063 8 P 0 0 ;0=6,1=1
P 2.7838425 2.568063 8 P 0 0 ;0=6,1=1
P 2.7841625 1.094063 8 P 0 0 ;0=6,1=1
P 2.7999951 0.2519685 8 P 0 0 ;0=6,1=1
P 2.8428425 1.095063 8 P 0 0 ;0=6,1=1
P 2.8608425 3.787063 8 P 0 0 ;0=6,1=1
P 2.8718425 2.297063 8 P 0 0 ;0=6,1=1
P 2.8782843 0.2495967 8 P 0 0 ;0=6,1=1
P 2.8818425 2.566063 8 P 0 0 ;0=6,1=1
P 2.8888425 4.221063 8 P 0 0 ;0=6,1=1
P 2.9018425 1.095063 8 P 0 0 ;0=6,1=1
P 2.9338425 0.953063 8 P 0 0 ;0=6,1=1
P 2.9574751 0.2519685 8 P 0 0 ;0=6,1=1
P 3.0974409 0.2519685 8 P 0 0 ;0=6,1=1
P 3.1830708 3.1358268 8 P 0 0 ;0=6,1=1
P 3.2698425 3.788063 8 P 0 0 ;0=6,1=1
P 3.277559 2.9635827 8 P 0 0 ;0=6,1=1
P 3.3308425 3.301063 8 P 0 0 ;0=6,1=1
P 3.3708425 2.888063 8 P 0 0 ;0=6,1=1
P 3.3958425 4.222063 8 P 0 0 ;0=6,1=1
P 3.4068425 1.461063 8 P 0 0 ;0=6,1=1
P 3.4108425 1.7136509 8 P 0 0 ;0=6,1=1
P 3.4138425 1.573063 8 P 0 0 ;0=6,1=1
P 3.4144661 1.805063 8 P 0 0 ;0=6,1=1
P 3.5318425 3.660063 8 P 0 0 ;0=6,1=1
P 3.5498425 1.413063 8 P 0 0 ;0=6,1=1
P 3.5548425 1.841063 8 P 0 0 ;0=6,1=1
P 3.5548425 1.941063 8 P 0 0 ;0=6,1=1
P 3.5548425 1.991063 8 P 0 0 ;0=6,1=1
P 3.5908425 1.662063 8 P 0 0 ;0=6,1=1
P 3.5948425 1.514063 8 P 0 0 ;0=6,1=1
P 3.6038425 0.682063 8 P 0 0 ;0=6,1=1
P 3.6428425 0.636063 8 P 0 0 ;0=6,1=1
P 3.7178425 3.072063 8 P 0 0 ;0=6,1=1
P 3.7188425 1.713063 8 P 0 0 ;0=6,1=1
P 3.7198425 1.921063 8 P 0 0 ;0=6,1=1
P 3.7198425 1.996063 8 P 0 0 ;0=6,1=1
P 3.7328425 1.418063 8 P 0 0 ;0=6,1=1
P 3.7448425 3.342063 8 P 0 0 ;0=6,1=1
P 3.7778425 4.023063 8 P 0 0 ;0=6,1=1
P 3.8308425 3.762063 8 P 0 0 ;0=6,1=1
P 3.8808425 3.109063 8 P 0 0 ;0=6,1=1
P 3.9608425 2.724063 8 P 0 0 ;0=6,1=1
P 3.9688425 1.671063 8 P 0 0 ;0=6,1=1
P 3.9968425 1.711063 8 P 0 0 ;0=6,1=1
P 4.0398425 3.784063 8 P 0 0 ;0=6,1=1
P 4.0648425 2.722063 8 P 0 0 ;0=6,1=1
P 4.0688425 3.135063 8 P 0 0 ;0=6,1=1
P 4.0858425 3.892063 8 P 0 0 ;0=6,1=1
P 4.1148425 3.135063 8 P 0 0 ;0=6,1=1
P 4.1203866 3.5941508 8 P 0 0 ;0=6,1=1
P 4.1318425 1.686063 8 P 0 0 ;0=6,1=1
P 4.1528425 3.135063 8 P 0 0 ;0=6,1=1
P 4.1948425 3.884063 8 P 0 0 ;0=6,1=1
P 4.2088425 3.135063 8 P 0 0 ;0=6,1=1
P 4.2348425 2.725063 8 P 0 0 ;0=6,1=1
P 4.2728425 3.135063 8 P 0 0 ;0=6,1=1
P 4.3338425 3.135063 8 P 0 0 ;0=6,1=1
P 4.3398425 2.725063 8 P 0 0 ;0=6,1=1
P 4.3878425 4.206063 8 P 0 0 ;0=6,1=1
P 4.4318425 3.135063 8 P 0 0 ;0=6,1=1
P 4.4778425 3.135063 8 P 0 0 ;0=6,1=1
P 4.9108425 4.203063 8 P 0 0 ;0=6,1=1
P 5.6768425 3.546063 8 P 0 0 ;0=6,1=1
P 5.7338425 3.556063 8 P 0 0 ;0=6,1=1
P 6.0048425 2.434063 8 P 0 0 ;0=6,1=1
P 6.0488425 2.171063 8 P 0 0 ;0=6,1=1
P 6.253937 2.9094488 8 P 0 0 ;0=6,1=1
P 6.2748425 2.391063 8 P 0 0 ;0=6,1=1
P 6.3720472 2.9094488 8 P 0 0 ;0=6,1=1
P 6.3958425 2.111063 8 P 0 0 ;0=6,1=1
P 6.3968425 2.556063 8 P 0 0 ;0=6,1=1
P 6.3978425 2.501063 8 P 0 0 ;0=6,1=1
P 6.3978425 2.610063 8 P 0 0 ;0=6,1=1
P 6.3988425 2.453063 8 P 0 0 ;0=6,1=1
P 6.3988425 2.657063 8 P 0 0 ;0=6,1=1
P 6.4568425 3.009063 8 P 0 0 ;0=6,1=1
P 6.4768425 3.231063 8 P 0 0 ;0=6,1=1
P 6.5488425 1.531063 8 P 0 0 ;0=6,1=1
P 6.6018425 1.777063 8 P 0 0 ;0=6,1=1
P 6.6028425 1.612063 8 P 0 0 ;0=6,1=1
P 6.6028425 1.672063 8 P 0 0 ;0=6,1=1
P 6.6028425 1.722063 8 P 0 0 ;0=6,1=1
P 6.6078425 2.176063 8 P 0 0 ;0=6,1=1
P 6.6268425 3.032063 8 P 0 0 ;0=6,1=1
P 6.6288425 1.372063 8 P 0 0 ;0=6,1=1
P 6.6476378 3.1299213 8 P 0 0 ;0=6,1=1
P 6.6488425 3.341063 8 P 0 0 ;0=6,1=1
P 6.6858425 1.828063 8 P 0 0 ;0=6,1=1
P 6.6998425 1.881063 8 P 0 0 ;0=6,1=1
P 6.9498425 2.095063 8 P 0 0 ;0=6,1=1
P 6.9744094 1.9399606 8 P 0 0 ;0=6,1=1

### steps/pcb/layers/sgnd1/features
#Layer_Physical_Order=5
#Layer_Color=16737945
#
#Feature symbol names
#
$0 r3.937
$1 r1
$2 r61.0236
$3 r75
$4 oval88.5827x177.1654
$5 oval177.1654x88.5827
$6 r120
$7 r98.4252
$8 r16
$9 r200

#
#Feature attribute names
#
@0 .geometry
@1 .pad_usage

#
#Feature attribute text strings
#
&0 Pad_Simple_X61.0236Y61.0236H41.3386C81.3386
&1 Pad_Simple_X75.0000Y75.0000H50.0000C90.0000
&2 Pad_Simple_X88.5827Y177.1654H39.3701C79.3701
&3 Pad_Simple_X177.1654Y88.5827H39.3701C79.3701
&4 Pad_Simple_X120.0000Y120.0000H68.0000C108.0000
&5 Pad_Simple_X98.4252Y98.4252H70.8661C110.8661
&6 VIA_RoundD16.0000H8.0000C48.0000
&7 VIA_RoundD200.0000H125.9843C165.9843

#
#Layer features
#
A 1.7712204 0.4310709 1.6275196 0.4310709 1.69937 0.4310709 0 P 0 N
L -0.0001175 0.177913 0.5908825 0.177913 1 P 0
L -0.0004331 0.1781182 0.5901181 0.1781182 0 P 0
L 0.5901181 0.1781182 0.5901181 0.5029213 0 P 0
L 0.5901181 0.5029213 1.312559 0.5029213 0 P 0
L 0.5908825 0.177913 0.5908825 0.502913 1 P 0
L 1.312559 0.313945 1.312559 0.5029213 0 P 0
L 1.312559 0.313945 1.6275197 0.313945 0 P 0
L 1.6275197 0.313945 1.6275197 0.4310709 0 P 0
P 0.0998425 0.806063 6 P 0 0 ;0=4,1=0
P 0.0998425 1.006063 6 P 0 0 ;0=4,1=0
P 0.0998425 1.331063 6 P 0 0 ;0=4,1=0
P 0.0998425 1.531063 6 P 0 0 ;0=4,1=0
P 0.0998425 1.856063 6 P 0 0 ;0=4,1=0
P 0.0998425 2.056063 6 P 0 0 ;0=4,1=0
P 0.0998425 2.381063 6 P 0 0 ;0=4,1=0
P 0.0998425 2.581063 6 P 0 0 ;0=4,1=0
P 0.2998425 0.806063 6 P 0 0 ;0=4,1=0
P 0.2998425 1.006063 6 P 0 0 ;0=4,1=0
P 0.2998425 1.331063 6 P 0 0 ;0=4,1=0
P 0.2998425 1.531063 6 P 0 0 ;0=4,1=0
P 0.2998425 1.856063 6 P 0 0 ;0=4,1=0
P 0.2998425 2.056063 6 P 0 0 ;0=4,1=0
P 0.2998425 2.381063 6 P 0 0 ;0=4,1=0
P 0.2998425 2.581063 6 P 0 0 ;0=4,1=0
P 3.9797272 2.4890438 3 P 0 0 ;0=1,1=0
P 5.1277559 2.3074803 2 P 0 0 ;0=0,1=0
P 5.5781524 1.6898312 3 P 0 0 ;0=1,1=0
P 5.9348031 3.9379527 4 P 0 0 ;0=2,1=0
P 6.1198425 4.056063 5 P 0 0 ;0=3,1=0
P 6.5694882 3.5895276 7 P 0 0 ;0=5,1=0
P 6.7348425 3.5895276 7 P 0 0 ;0=5,1=0
P 6.9001969 3.5895276 7 P 0 0 ;0=5,1=0
S P 0
OB 7.0826772 4.3531339 I
OS 7.0826772 0.5051339
OS 3.1099214 0.505134
OS 3.1099214 0.2253937
OS 2.2899214 0.2253937
OS 2.2899214 0.310134
OS 2.2579214 0.342134
OS 2.2299214 0.342134
OS 2.1979214 0.310134
OS 2.1979214 0.2253937
OS 1.7769214 0.2253937
OS 1.7769214 0.3525976
OS 1.7819212 0.3530901
OS 1.7820868 0.3522587
OS 1.7827708 0.3488201
OS 1.7863071 0.3435276
OS 1.7915996 0.3399913
OS 1.7978425 0.3387495
OS 1.8040854 0.3399913
OS 1.8093779 0.3435276
OS 1.8129142 0.3488201
OS 1.814156 0.355063
OS 1.8129142 0.3613059
OS 1.8093779 0.3665984
OS 1.8040854 0.3701347
OS 1.7978425 0.3713765
OS 1.7915996 0.3701347
OS 1.7863071 0.3665984
OS 1.7827708 0.3613059
OS 1.7820868 0.3578674
OS 1.7819212 0.3570359
OS 1.7769214 0.3575284
OS 1.7769214 0.465134
OS 1.7309214 0.511134
OS 1.6589214 0.511134
OS 1.6139214 0.466134
OS 1.6139214 0.3129921
OS 1.3169214 0.3129921
OS 1.3169214 0.508134
OS 0.5769214 0.508134
OS 0.5769214 0.184134
OS 0.0029214 0.184134
OS 0.0029214 4.3493766
OS 0.0066788 4.353134
OS 7.0826772 4.3531339
OE
OB 2.5708425 4.2993765 H
OS 2.5645996 4.2981347
OS 2.5593071 4.2945984
OS 2.5557708 4.2893059
OS 2.554529 4.283063
OS 2.5557708 4.2768201
OS 2.5593071 4.2715276
OS 2.5645996 4.2679913
OS 2.5708425 4.2667495
OS 2.5770854 4.2679913
OS 2.5823779 4.2715276
OS 2.5859142 4.2768201
OS 2.587156 4.283063
OS 2.5859142 4.2893059
OS 2.5823779 4.2945984
OS 2.5770854 4.2981347
OS 2.5708425 4.2993765
OE
OB 1.2948425 4.2723765 H
OS 1.2885996 4.2711347
OS 1.2833071 4.2675984
OS 1.2797708 4.2623059
OS 1.278529 4.256063
OS 1.2797708 4.2498201
OS 1.2833071 4.2445276
OS 1.2885996 4.2409913
OS 1.2948425 4.2397495
OS 1.3010854 4.2409913
OS 1.3063779 4.2445276
OS 1.3099142 4.2498201
OS 1.311156 4.256063
OS 1.3099142 4.2623059
OS 1.3063779 4.2675984
OS 1.3010854 4.2711347
OS 1.2948425 4.2723765
OE
OB 2.0788071 4.293374 H
OS 2.0078071 4.293374
OS 2.0078071 4.222374
OS 2.0788071 4.222374
OS 2.0788071 4.293374
OE
OB 1.4931771 4.289437 H
OS 1.4221771 4.289437
OS 1.4221771 4.218437
OS 1.4931771 4.218437
OS 1.4931771 4.289437
OE
OB 1.5578425 4.2453765 H
OS 1.5515996 4.2441347
OS 1.5463071 4.2405984
OS 1.5427708 4.2353059
OS 1.541529 4.229063
OS 1.5427708 4.2228201
OS 1.5463071 4.2175276
OS 1.5515996 4.2139913
OS 1.5578425 4.2127495
OS 1.5640854 4.2139913
OS 1.5693779 4.2175276
OS 1.5729142 4.2228201
OS 1.574156 4.229063
OS 1.5729142 4.2353059
OS 1.5693779 4.2405984
OS 1.5640854 4.2441347
OS 1.5578425 4.2453765
OE
OB 1.3454724 4.1915104 H
OS 1.3392295 4.1902686
OS 1.333937 4.1867323
OS 1.3304007 4.1814398
OS 1.3291589 4.1751969
OS 1.3304007 4.168954
OS 1.333937 4.1636615
OS 1.3392295 4.1601252
OS 1.3454724 4.1588834
OS 1.3517153 4.1601252
OS 1.3570078 4.1636615
OS 1.3605441 4.168954
OS 1.3617859 4.1751969
OS 1.3605441 4.1814398
OS 1.3570078 4.1867323
OS 1.3517153 4.1902686
OS 1.3454724 4.1915104
OE
OB 1.5698819 4.1875734 H
OS 1.563639 4.1863316
OS 1.5583465 4.1827953
OS 1.5548102 4.1775028
OS 1.5535684 4.1712599
OS 1.5548102 4.165017
OS 1.5583465 4.1597245
OS 1.563639 4.1561882
OS 1.5698819 4.1549464
OS 1.5761248 4.1561882
OS 1.5814173 4.1597245
OS 1.5849536 4.165017
OS 1.5861954 4.1712599
OS 1.5849536 4.1775028
OS 1.5814173 4.1827953
OS 1.5761248 4.1863316
OS 1.5698819 4.1875734
OE
OB 1.7798425 4.1723765 H
OS 1.7735996 4.1711347
OS 1.7683071 4.1675984
OS 1.7647708 4.1623059
OS 1.763529 4.156063
OS 1.7647708 4.1498201
OS 1.7683071 4.1445276
OS 1.7735996 4.1409913
OS 1.7798425 4.1397495
OS 1.7860854 4.1409913
OS 1.7913779 4.1445276
OS 1.7949142 4.1498201
OS 1.796156 4.156063
OS 1.7949142 4.1623059
OS 1.7913779 4.1675984
OS 1.7860854 4.1711347
OS 1.7798425 4.1723765
OE
OB 2.0433071 4.1936803 H
OS 2.0340397 4.1924602
OS 2.0254039 4.1888832
OS 2.0179882 4.1831929
OS 2.0122979 4.1757772
OS 2.0087209 4.1671414
OS 2.0075008 4.157874
OS 2.0087209 4.1486066
OS 2.0122979 4.1399708
OS 2.0179882 4.1325551
OS 2.0254039 4.1268648
OS 2.0340397 4.1232878
OS 2.0433071 4.1220677
OS 2.0525745 4.1232878
OS 2.0612103 4.1268648
OS 2.068626 4.1325551
OS 2.0743163 4.1399708
OS 2.0778933 4.1486066
OS 2.0791134 4.157874
OS 2.0778933 4.1671414
OS 2.0743163 4.1757772
OS 2.068626 4.1831929
OS 2.0612103 4.1888832
OS 2.0525745 4.1924602
OS 2.0433071 4.1936803
OE
OB 1.4576771 4.1897433 H
OS 1.4484097 4.1885232
OS 1.4397739 4.1849462
OS 1.4323582 4.1792559
OS 1.4266679 4.1718402
OS 1.4230909 4.1632044
OS 1.4218708 4.153937
OS 1.4230909 4.1446696
OS 1.4266679 4.1360338
OS 1.4323582 4.1286181
OS 1.4397739 4.1229278
OS 1.4484097 4.1193508
OS 1.4576771 4.1181307
OS 1.4669445 4.1193508
OS 1.4755803 4.1229278
OS 1.482996 4.1286181
OS 1.4886863 4.1360338
OS 1.4922633 4.1446696
OS 1.4934834 4.153937
OS 1.4922633 4.1632044
OS 1.4886863 4.1718402
OS 1.482996 4.1792559
OS 1.4755803 4.1849462
OS 1.4669445 4.1885232
OS 1.4576771 4.1897433
OE
OB 3.9580709 4.1520014 H
OS 3.9513575 4.1511176
OS 3.9451017 4.1485263
OS 3.9397297 4.1444042
OS 3.9356076 4.1390322
OS 3.9330163 4.1327764
OS 3.9321325 4.126063
OS 3.9330163 4.1193496
OS 3.9356076 4.1130938
OS 3.9397297 4.1077218
OS 3.9451017 4.1035997
OS 3.9513575 4.1010084
OS 3.9580709 4.1001246
OS 3.9647843 4.1010084
OS 3.9710401 4.1035997
OS 3.9764121 4.1077218
OS 3.9805342 4.1130938
OS 3.9831255 4.1193496
OS 3.9840093 4.126063
OS 3.9831255 4.1327764
OS 3.9805342 4.1390322
OS 3.9764121 4.1444042
OS 3.9710401 4.1485263
OS 3.9647843 4.1511176
OS 3.9580709 4.1520014
OE
OB 3.7848425 4.1520014 H
OS 3.7781291 4.1511176
OS 3.7718733 4.1485263
OS 3.7665013 4.1444042
OS 3.7623792 4.1390322
OS 3.7597879 4.1327764
OS 3.7589041 4.126063
OS 3.7597879 4.1193496
OS 3.7623792 4.1130938
OS 3.7665013 4.1077218
OS 3.7718733 4.1035997
OS 3.7781291 4.1010084
OS 3.7848425 4.1001246
OS 3.7915559 4.1010084
OS 3.7978117 4.1035997
OS 3.8031837 4.1077218
OS 3.8073058 4.1130938
OS 3.8098971 4.1193496
OS 3.8107809 4.126063
OS 3.8098971 4.1327764
OS 3.8073058 4.1390322
OS 3.8031837 4.1444042
OS 3.7978117 4.1485263
OS 3.7915559 4.1511176
OS 3.7848425 4.1520014
OE
OB 4.7547119 4.1322459 H
OS 4.748469 4.1310041
OS 4.7431765 4.1274678
OS 4.7396402 4.1221753
OS 4.7383984 4.1159324
OS 4.7396402 4.1096895
OS 4.7431765 4.104397
OS 4.748469 4.1008607
OS 4.7547119 4.0996189
OS 4.7609548 4.1008607
OS 4.7662473 4.104397
OS 4.7697836 4.1096895
OS 4.7710254 4.1159324
OS 4.7697836 4.1221753
OS 4.7662473 4.1274678
OS 4.7609548 4.1310041
OS 4.7547119 4.1322459
OE
OB 2.1460663 4.1201044 H
OS 2.1398234 4.1188626
OS 2.1345309 4.1153263
OS 2.1309946 4.1100338
OS 2.1297528 4.1037909
OS 2.1309946 4.097548
OS 2.1345309 4.0922555
OS 2.1398234 4.0887192
OS 2.1460663 4.0874774
OS 2.1523092 4.0887192
OS 2.1576017 4.0922555
OS 2.161138 4.097548
OS 2.1623798 4.1037909
OS 2.161138 4.1100338
OS 2.1576017 4.1153263
OS 2.1523092 4.1188626
OS 2.1460663 4.1201044
OE
OB 5.2670079 4.1052111 H
OS 5.260765 4.1039693
OS 5.2554725 4.100433
OS 5.2519362 4.0951405
OS 5.2506944 4.0888976
OS 5.2519362 4.0826547
OS 5.2554725 4.0773622
OS 5.260765 4.0738259
OS 5.2670079 4.0725841
OS 5.2732508 4.0738259
OS 5.2785433 4.0773622
OS 5.2820796 4.0826547
OS 5.2833214 4.0888976
OS 5.2820796 4.0951405
OS 5.2785433 4.100433
OS 5.2732508 4.1039693
OS 5.2670079 4.1052111
OE
OB 2.253937 4.1029277 H
OS 2.2476941 4.1016859
OS 2.2424016 4.0981496
OS 2.2388653 4.0928571
OS 2.2376235 4.0866142
OS 2.2388653 4.0803713
OS 2.2424016 4.0750788
OS 2.2476941 4.0715425
OS 2.253937 4.0703007
OS 2.2601799 4.0715425
OS 2.2654724 4.0750788
OS 2.2690087 4.0803713
OS 2.2702505 4.0866142
OS 2.2690087 4.0928571
OS 2.2654724 4.0981496
OS 2.2601799 4.1016859
OS 2.253937 4.1029277
OE
OB 3.5048425 4.1023765 H
OS 3.4985996 4.1011347
OS 3.4933071 4.0975984
OS 3.4897708 4.0923059
OS 3.488529 4.086063
OS 3.4897708 4.0798201
OS 3.4933071 4.0745276
OS 3.4985996 4.0709913
OS 3.5048425 4.0697495
OS 3.5110854 4.0709913
OS 3.5163779 4.0745276
OS 3.5199142 4.0798201
OS 3.521156 4.086063
OS 3.5199142 4.0923059
OS 3.5163779 4.0975984
OS 3.5110854 4.1011347
OS 3.5048425 4.1023765
OE
OB 3.2948425 4.1274482 H
OS 3.2841414 4.1260394
OS 3.2741696 4.1219089
OS 3.2656066 4.1153383
OS 3.259036 4.1067753
OS 3.2549055 4.0968035
OS 3.2534967 4.0861024
OS 3.2549055 4.0754013
OS 3.259036 4.0654295
OS 3.2656066 4.0568665
OS 3.2741696 4.0502959
OS 3.2841414 4.0461654
OS 3.2948425 4.0447566
OS 3.3055436 4.0461654
OS 3.3155154 4.0502959
OS 3.3240784 4.0568665
OS 3.330649 4.0654295
OS 3.3347795 4.0754013
OS 3.3361883 4.0861024
OS 3.3347795 4.0968035
OS 3.330649 4.1067753
OS 3.3240784 4.1153383
OS 3.3155154 4.1219089
OS 3.3055436 4.1260394
OS 3.2948425 4.1274482
OE
OB 2.9948425 4.1274482 H
OS 2.9841414 4.1260394
OS 2.9741696 4.1219089
OS 2.9656066 4.1153383
OS 2.959036 4.1067753
OS 2.9549055 4.0968035
OS 2.9534967 4.0861024
OS 2.9549055 4.0754013
OS 2.959036 4.0654295
OS 2.9656066 4.0568665
OS 2.9741696 4.0502959
OS 2.9841414 4.0461654
OS 2.9948425 4.0447566
OS 3.0055436 4.0461654
OS 3.0155154 4.0502959
OS 3.0240784 4.0568665
OS 3.030649 4.0654295
OS 3.0347795 4.0754013
OS 3.0361883 4.0861024
OS 3.0347795 4.0968035
OS 3.030649 4.1067753
OS 3.0240784 4.1153383
OS 3.0155154 4.1219089
OS 3.0055436 4.1260394
OS 2.9948425 4.1274482
OE
OB 6.9001969 4.1608442 H
OS 6.8870518 4.1595495
OS 6.8744118 4.1557152
OS 6.8627628 4.1494887
OS 6.8525523 4.1411092
OS 6.8441728 4.1308987
OS 6.8379463 4.1192497
OS 6.834112 4.1066097
OS 6.8328173 4.0934646
OS 6.834112 4.0803195
OS 6.8379463 4.0676795
OS 6.8441728 4.0560305
OS 6.8525523 4.04582
OS 6.8627628 4.0374405
OS 6.8744118 4.031214
OS 6.8870518 4.0273797
OS 6.9001969 4.026085
OS 6.913342 4.0273797
OS 6.925982 4.031214
OS 6.937631 4.0374405
OS 6.9478415 4.04582
OS 6.956221 4.0560305
OS 6.9624475 4.0676795
OS 6.9662818 4.0803195
OS 6.9675765 4.0934646
OS 6.9662818 4.1066097
OS 6.9624475 4.1192497
OS 6.956221 4.1308987
OS 6.9478415 4.1411092
OS 6.937631 4.1494887
OS 6.925982 4.1557152
OS 6.913342 4.1595495
OS 6.9001969 4.1608442
OE
OB 6.5694882 4.1608442 H
OS 6.5563431 4.1595495
OS 6.5437031 4.1557152
OS 6.5320541 4.1494887
OS 6.5218436 4.1411092
OS 6.5134641 4.1308987
OS 6.5072376 4.1192497
OS 6.5034033 4.1066097
OS 6.5021086 4.0934646
OS 6.5034033 4.0803195
OS 6.5072376 4.0676795
OS 6.5134641 4.0560305
OS 6.5218436 4.04582
OS 6.5320541 4.0374405
OS 6.5437031 4.031214
OS 6.5563431 4.0273797
OS 6.5694882 4.026085
OS 6.5826333 4.0273797
OS 6.5952733 4.031214
OS 6.6069223 4.0374405
OS 6.6171328 4.04582
OS 6.6255123 4.0560305
OS 6.6317388 4.0676795
OS 6.6355731 4.0803195
OS 6.6368678 4.0934646
OS 6.6355731 4.1066097
OS 6.6317388 4.1192497
OS 6.6255123 4.1308987
OS 6.6171328 4.1411092
OS 6.6069223 4.1494887
OS 6.5952733 4.1557152
OS 6.5826333 4.1595495
OS 6.5694882 4.1608442
OE
OB 2.0433071 4.0936803 H
OS 2.0340397 4.0924602
OS 2.0254039 4.0888832
OS 2.0179882 4.0831929
OS 2.0122979 4.0757772
OS 2.0087209 4.0671414
OS 2.0075008 4.057874
OS 2.0087209 4.0486066
OS 2.0122979 4.0399708
OS 2.0179882 4.0325551
OS 2.0254039 4.0268648
OS 2.0340397 4.0232878
OS 2.0433071 4.0220677
OS 2.0525745 4.0232878
OS 2.0612103 4.0268648
OS 2.068626 4.0325551
OS 2.0743163 4.0399708
OS 2.0778933 4.0486066
OS 2.0791134 4.057874
OS 2.0778933 4.0671414
OS 2.0743163 4.0757772
OS 2.068626 4.0831929
OS 2.0612103 4.0888832
OS 2.0525745 4.0924602
OS 2.0433071 4.0936803
OE
OB 0.285433 4.2854743 H
OS 0.2645629 4.2838318
OS 0.2442066 4.2789447
OS 0.2248655 4.2709333
OS 0.2070158 4.259995
OS 0.191097 4.246399
OS 0.177501 4.2304802
OS 0.1665627 4.2126305
OS 0.1585513 4.1932894
OS 0.1536642 4.1729331
OS 0.1520217 4.152063
OS 0.1536642 4.1311929
OS 0.1585513 4.1108366
OS 0.1665627 4.0914955
OS 0.177501 4.0736458
OS 0.191097 4.057727
OS 0.2070158 4.044131
OS 0.2248655 4.0331927
OS 0.2442066 4.0251813
OS 0.2645629 4.0202942
OS 0.285433 4.0186517
OS 0.3063031 4.0202942
OS 0.3266594 4.0251813
OS 0.3460005 4.0331927
OS 0.3638502 4.044131
OS 0.379769 4.057727
OS 0.393365 4.0736458
OS 0.4043033 4.0914955
OS 0.4123147 4.1108366
OS 0.4172018 4.1311929
OS 0.4188443 4.152063
OS 0.4172018 4.1729331
OS 0.4123147 4.1932894
OS 0.4043033 4.2126305
OS 0.393365 4.2304802
OS 0.379769 4.246399
OS 0.3638502 4.259995
OS 0.3460005 4.2709333
OS 0.3266594 4.2789447
OS 0.3063031 4.2838318
OS 0.285433 4.2854743
OE
OB 1.4576771 4.0897433 H
OS 1.4484097 4.0885232
OS 1.4397739 4.0849462
OS 1.4323582 4.0792559
OS 1.4266679 4.0718402
OS 1.4230909 4.0632044
OS 1.4218708 4.053937
OS 1.4230909 4.0446696
OS 1.4266679 4.0360338
OS 1.4323582 4.0286181
OS 1.4397739 4.0229278
OS 1.4484097 4.0193508
OS 1.4576771 4.0181307
OS 1.4669445 4.0193508
OS 1.4755803 4.0229278
OS 1.482996 4.0286181
OS 1.4886863 4.0360338
OS 1.4922633 4.0446696
OS 1.4934834 4.053937
OS 1.4922633 4.0632044
OS 1.4886863 4.0718402
OS 1.482996 4.0792559
OS 1.4755803 4.0849462
OS 1.4669445 4.0885232
OS 1.4576771 4.0897433
OE
OB 1.9038425 4.0343765 H
OS 1.8975996 4.0331347
OS 1.8923071 4.0295984
OS 1.8887708 4.0243059
OS 1.887529 4.018063
OS 1.8887708 4.0118201
OS 1.8923071 4.0065276
OS 1.8975996 4.0029913
OS 1.9038425 4.0017495
OS 1.9100854 4.0029913
OS 1.9153779 4.0065276
OS 1.9189142 4.0118201
OS 1.920156 4.018063
OS 1.9189142 4.0243059
OS 1.9153779 4.0295984
OS 1.9100854 4.0331347
OS 1.9038425 4.0343765
OE
OB 2.3533464 4.03403 H
OS 2.3471035 4.0327882
OS 2.341811 4.0292519
OS 2.3382747 4.0239594
OS 2.3370329 4.0177165
OS 2.3382747 4.0114736
OS 2.341811 4.0061811
OS 2.3471035 4.0026448
OS 2.3533464 4.001403
OS 2.3595893 4.0026448
OS 2.3648818 4.0061811
OS 2.3684181 4.0114736
OS 2.3696599 4.0177165
OS 2.3684181 4.0239594
OS 2.3648818 4.0292519
OS 2.3595893 4.0327882
OS 2.3533464 4.03403
OE
OB 5.7234252 4.0832969 H
OS 5.7084897 4.0813306
OS 5.6945721 4.0755657
OS 5.6826207 4.0663951
OS 5.6734501 4.0544438
OS 5.6676852 4.0405261
OS 5.6657189 4.0255906
OS 5.6676852 4.0106551
OS 5.6734501 3.9967374
OS 5.6826207 3.9847861
OS 5.6945721 3.9756155
OS 5.7084897 3.9698506
OS 5.7234252 3.9678843
OS 5.7383607 3.9698506
OS 5.7522783 3.9756155
OS 5.7642297 3.9847861
OS 5.7734003 3.9967374
OS 5.7791652 4.0106551
OS 5.7811315 4.0255906
OS 5.7791652 4.0405261
OS 5.7734003 4.0544438
OS 5.7642297 4.0663951
OS 5.7522783 4.0755657
OS 5.7383607 4.0813306
OS 5.7234252 4.0832969
OE
OB 1.4084645 3.9966285 H
OS 1.4022216 3.9953867
OS 1.3969291 3.9918504
OS 1.3933928 3.9865579
OS 1.392151 3.980315
OS 1.3933928 3.9740721
OS 1.3969291 3.9687796
OS 1.4022216 3.9652433
OS 1.4084645 3.9640015
OS 1.4147074 3.9652433
OS 1.4199999 3.9687796
OS 1.4235362 3.9740721
OS 1.424778 3.980315
OS 1.4235362 3.9865579
OS 1.4199999 3.9918504
OS 1.4147074 3.9953867
OS 1.4084645 3.9966285
OE
OB 2.0848425 3.9123765 H
OS 2.0785996 3.9111347
OS 2.0733071 3.9075984
OS 2.0697708 3.9023059
OS 2.068529 3.896063
OS 2.0697708 3.8898201
OS 2.0699331 3.8895773
OS 2.0663282 3.8859724
OS 2.0660854 3.8861347
OS 2.0598425 3.8873765
OS 2.0535996 3.8861347
OS 2.0483071 3.8825984
OS 2.0447708 3.8773059
OS 2.043529 3.871063
OS 2.0447708 3.8648201
OS 2.0483071 3.8595276
OS 2.0535996 3.8559913
OS 2.0598425 3.8547495
OS 2.0660854 3.8559913
OS 2.0713779 3.8595276
OS 2.0749142 3.8648201
OS 2.076156 3.871063
OS 2.0749142 3.8773059
OS 2.0747519 3.8775487
OS 2.0783568 3.8811536
OS 2.0785996 3.8809913
OS 2.0848425 3.8797495
OS 2.0910854 3.8809913
OS 2.0963779 3.8845276
OS 2.0999142 3.8898201
OS 2.101156 3.896063
OS 2.0999142 3.9023059
OS 2.0963779 3.9075984
OS 2.0910854 3.9111347
OS 2.0848425 3.9123765
OE
OB 2.0298425 3.8523765 H
OS 2.0235996 3.8511347
OS 2.0183071 3.8475984
OS 2.0147708 3.8423059
OS 2.013529 3.836063
OS 2.0136749 3.8353296
OS 2.0130932 3.8343873
OS 2.0093423 3.8314814
OS 2.0048425 3.8323765
OS 1.9985996 3.8311347
OS 1.9933071 3.8275984
OS 1.9897708 3.8223059
OS 1.988529 3.816063
OS 1.9897708 3.8098201
OS 1.9933071 3.8045276
OS 1.9985996 3.8009913
OS 2.0048425 3.7997495
OS 2.0110854 3.8009913
OS 2.0163779 3.8045276
OS 2.0199142 3.8098201
OS 2.021156 3.816063
OS 2.0210101 3.8167964
OS 2.0215918 3.8177387
OS 2.0253427 3.8206446
OS 2.0298425 3.8197495
OS 2.0360854 3.8209913
OS 2.0413779 3.8245276
OS 2.0449142 3.8298201
OS 2.046156 3.836063
OS 2.0449142 3.8423059
OS 2.0413779 3.8475984
OS 2.0360854 3.8511347
OS 2.0298425 3.8523765
OE
OB 3.6998425 3.8523765 H
OS 3.6935996 3.8511347
OS 3.6883071 3.8475984
OS 3.6847708 3.8423059
OS 3.683529 3.836063
OS 3.6847708 3.8298201
OS 3.6883071 3.8245276
OS 3.6935996 3.8209913
OS 3.6998425 3.8197495
OS 3.7060854 3.8209913
OS 3.7113779 3.8245276
OS 3.7149142 3.8298201
OS 3.716156 3.836063
OS 3.7149142 3.8423059
OS 3.7113779 3.8475984
OS 3.7060854 3.8511347
OS 3.6998425 3.8523765
OE
OB 3.0148425 3.8473765 H
OS 3.0085996 3.8461347
OS 3.0033071 3.8425984
OS 2.9997708 3.8373059
OS 2.998529 3.831063
OS 2.9997708 3.8248201
OS 3.0033071 3.8195276
OS 3.0085996 3.8159913
OS 3.0148425 3.8147495
OS 3.0210854 3.8159913
OS 3.0263779 3.8195276
OS 3.0299142 3.8248201
OS 3.031156 3.831063
OS 3.0299142 3.8373059
OS 3.0263779 3.8425984
OS 3.0210854 3.8461347
OS 3.0148425 3.8473765
OE
OB 3.8298425 3.8223765 H
OS 3.8235996 3.8211347
OS 3.8183071 3.8175984
OS 3.8147708 3.8123059
OS 3.813529 3.806063
OS 3.8147708 3.7998201
OS 3.8183071 3.7945276
OS 3.8235996 3.7909913
OS 3.8298425 3.7897495
OS 3.8360854 3.7909913
OS 3.8413779 3.7945276
OS 3.8449142 3.7998201
OS 3.846156 3.806063
OS 3.8449142 3.8123059
OS 3.8413779 3.8175984
OS 3.8360854 3.8211347
OS 3.8298425 3.8223765
OE
OB 3.5398425 3.8223765 H
OS 3.5335996 3.8211347
OS 3.5283071 3.8175984
OS 3.5247708 3.8123059
OS 3.523529 3.806063
OS 3.5247708 3.7998201
OS 3.5283071 3.7945276
OS 3.5335996 3.7909913
OS 3.5398425 3.7897495
OS 3.5460854 3.7909913
OS 3.5513779 3.7945276
OS 3.5549142 3.7998201
OS 3.556156 3.806063
OS 3.5549142 3.8123059
OS 3.5513779 3.8175984
OS 3.5460854 3.8211347
OS 3.5398425 3.8223765
OE
OB 3.2198425 3.8223765 H
OS 3.2135996 3.8211347
OS 3.2083071 3.8175984
OS 3.2047708 3.8123059
OS 3.203529 3.806063
OS 3.2047708 3.7998201
OS 3.2083071 3.7945276
OS 3.2135996 3.7909913
OS 3.2198425 3.7897495
OS 3.2260854 3.7909913
OS 3.2313779 3.7945276
OS 3.2349142 3.7998201
OS 3.236156 3.806063
OS 3.2349142 3.8123059
OS 3.2313779 3.8175984
OS 3.2260854 3.8211347
OS 3.2198425 3.8223765
OE
OB 5.7234252 3.9021945 H
OS 5.7084897 3.9002282
OS 5.6945721 3.8944633
OS 5.6826207 3.8852927
OS 5.6734501 3.8733414
OS 5.6676852 3.8594237
OS 5.6657189 3.8444882
OS 5.6676852 3.8295527
OS 5.6734501 3.815635
OS 5.6826207 3.8036837
OS 5.6945721 3.7945131
OS 5.7084897 3.7887482
OS 5.7234252 3.7867819
OS 5.7383607 3.7887482
OS 5.7522783 3.7945131
OS 5.7642297 3.8036837
OS 5.7734003 3.815635
OS 5.7791652 3.8295527
OS 5.7811315 3.8444882
OS 5.7791652 3.8594237
OS 5.7734003 3.8733414
OS 5.7642297 3.8852927
OS 5.7522783 3.8944633
OS 5.7383607 3.9002282
OS 5.7234252 3.9021945
OE
OB 2.7224094 3.8023844 H
OS 2.7161665 3.8011426
OS 2.710874 3.7976063
OS 2.7073377 3.7923138
OS 2.7060959 3.7860709
OS 2.7073377 3.779828
OS 2.710874 3.7745355
OS 2.7161665 3.7709992
OS 2.7224094 3.7697574
OS 2.7286523 3.7709992
OS 2.7339448 3.7745355
OS 2.7374811 3.779828
OS 2.7387229 3.7860709
OS 2.7374811 3.7923138
OS 2.7339448 3.7976063
OS 2.7286523 3.8011426
OS 2.7224094 3.8023844
OE
OB 6.1690551 3.8775488 H
OS 6.0706299 3.8775488
OS 6.0556944 3.8755825
OS 6.0417767 3.8698176
OS 6.0298254 3.860647
OS 6.0206548 3.8486956
OS 6.0148899 3.834778
OS 6.0129236 3.8198425
OS 6.0148899 3.804907
OS 6.0206548 3.7909894
OS 6.0298254 3.779038
OS 6.0417767 3.7698674
OS 6.0556944 3.7641025
OS 6.0706299 3.7621362
OS 6.1690551 3.7621362
OS 6.1839906 3.7641025
OS 6.1979083 3.7698674
OS 6.2098596 3.779038
OS 6.2190302 3.7909894
OS 6.2247951 3.804907
OS 6.2267614 3.8198425
OS 6.2247951 3.834778
OS 6.2190302 3.8486956
OS 6.2098596 3.860647
OS 6.1979083 3.8698176
OS 6.1839906 3.8755825
OS 6.1690551 3.8775488
OE
OB 4.2548425 3.7923765 H
OS 4.2485996 3.7911347
OS 4.2433071 3.7875984
OS 4.2397708 3.7823059
OS 4.238529 3.776063
OS 4.2397708 3.7698201
OS 4.2433071 3.7645276
OS 4.2485996 3.7609913
OS 4.2548425 3.7597495
OS 4.2610854 3.7609913
OS 4.2663779 3.7645276
OS 4.2699142 3.7698201
OS 4.271156 3.776063
OS 4.2699142 3.7823059
OS 4.2663779 3.7875984
OS 4.2610854 3.7911347
OS 4.2548425 3.7923765
OE
OB 6.9001969 3.8637693 H
OS 6.8852614 3.861803
OS 6.8713437 3.8560381
OS 6.8593924 3.8468675
OS 6.8502218 3.8349162
OS 6.8444569 3.8209985
OS 6.8424906 3.806063
OS 6.8444569 3.7911275
OS 6.8502218 3.7772098
OS 6.8593924 3.7652585
OS 6.8713437 3.7560879
OS 6.8852614 3.750323
OS 6.9001969 3.7483567
OS 6.9151324 3.750323
OS 6.9290501 3.7560879
OS 6.9410014 3.7652585
OS 6.950172 3.7772098
OS 6.9559369 3.7911275
OS 6.9579032 3.806063
OS 6.9559369 3.8209985
OS 6.950172 3.8349162
OS 6.9410014 3.8468675
OS 6.9290501 3.8560381
OS 6.9151324 3.861803
OS 6.9001969 3.8637693
OE
OB 6.7348425 3.8637693 H
OS 6.719907 3.861803
OS 6.7059893 3.8560381
OS 6.694038 3.8468675
OS 6.6848674 3.8349162
OS 6.6791025 3.8209985
OS 6.6771362 3.806063
OS 6.6791025 3.7911275
OS 6.6848674 3.7772098
OS 6.694038 3.7652585
OS 6.7059893 3.7560879
OS 6.719907 3.750323
OS 6.7348425 3.7483567
OS 6.749778 3.750323
OS 6.7636957 3.7560879
OS 6.775647 3.7652585
OS 6.7848176 3.7772098
OS 6.7905825 3.7911275
OS 6.7925488 3.806063
OS 6.7905825 3.8209985
OS 6.7848176 3.8349162
OS 6.775647 3.8468675
OS 6.7636957 3.8560381
OS 6.749778 3.861803
OS 6.7348425 3.8637693
OE
OB 6.5694882 3.8637693 H
OS 6.5545527 3.861803
OS 6.540635 3.8560381
OS 6.5286837 3.8468675
OS 6.5195131 3.8349161
OS 6.5137482 3.8209985
OS 6.5117819 3.806063
OS 6.5137482 3.7911275
OS 6.5195131 3.7772099
OS 6.5286837 3.7652585
OS 6.540635 3.7560879
OS 6.5545527 3.750323
OS 6.5694882 3.7483567
OS 6.5844237 3.750323
OS 6.5983414 3.7560879
OS 6.6102927 3.7652585
OS 6.6194633 3.7772099
OS 6.6252282 3.7911275
OS 6.6271945 3.806063
OS 6.6252282 3.8209985
OS 6.6194633 3.8349161
OS 6.6102927 3.8468675
OS 6.5983414 3.8560381
OS 6.5844237 3.861803
OS 6.5694882 3.8637693
OE
OB 3.6998425 3.7673765 H
OS 3.6935996 3.7661347
OS 3.6883071 3.7625984
OS 3.6847708 3.7573059
OS 3.683529 3.751063
OS 3.6847708 3.7448201
OS 3.6883071 3.7395276
OS 3.6935996 3.7359913
OS 3.6998425 3.7347495
OS 3.7060854 3.7359913
OS 3.7113779 3.7395276
OS 3.7149142 3.7448201
OS 3.716156 3.751063
OS 3.7149142 3.7573059
OS 3.7113779 3.7625984
OS 3.7060854 3.7661347
OS 3.6998425 3.7673765
OE
OB 2.9933858 3.7673765 H
OS 2.9871429 3.7661347
OS 2.9818504 3.7625984
OS 2.9783141 3.7573059
OS 2.9770723 3.751063
OS 2.9783141 3.7448201
OS 2.9818504 3.7395276
OS 2.9871429 3.7359913
OS 2.9933858 3.7347495
OS 2.9996287 3.7359913
OS 3.0049212 3.7395276
OS 3.0084575 3.7448201
OS 3.0096993 3.751063
OS 3.0084575 3.7573059
OS 3.0049212 3.7625984
OS 2.9996287 3.7661347
OS 2.9933858 3.7673765
OE
OB 6.2948425 3.7173765 H
OS 6.2885996 3.7161347
OS 6.2833071 3.7125984
OS 6.2797708 3.7073059
OS 6.278529 3.701063
OS 6.2797708 3.6948201
OS 6.2833071 3.6895276
OS 6.2885996 3.6859913
OS 6.2948425 3.6847495
OS 6.3010854 3.6859913
OS 6.3063779 3.6895276
OS 6.3099142 3.6948201
OS 6.311156 3.701063
OS 6.3099142 3.7073059
OS 6.3063779 3.7125984
OS 6.3010854 3.7161347
OS 6.2948425 3.7173765
OE
OB 1.8498425 3.7173765 H
OS 1.8435996 3.7161347
OS 1.8383071 3.7125984
OS 1.8347708 3.7073059
OS 1.833529 3.701063
OS 1.8347708 3.6948201
OS 1.8383071 3.6895276
OS 1.8435996 3.6859913
OS 1.8498425 3.6847495
OS 1.8560854 3.6859913
OS 1.8613779 3.6895276
OS 1.8649142 3.6948201
OS 1.866156 3.701063
OS 1.8649142 3.7073059
OS 1.8613779 3.7125984
OS 1.8560854 3.7161347
OS 1.8498425 3.7173765
OE
OB 4.0498425 3.6813765 H
OS 4.0435996 3.6801347
OS 4.0383071 3.6765984
OS 4.0347708 3.6713059
OS 4.033529 3.665063
OS 4.0347708 3.6588201
OS 4.0383071 3.6535276
OS 4.0435996 3.6499913
OS 4.0498425 3.6487495
OS 4.0560854 3.6499913
OS 4.0613779 3.6535276
OS 4.0649142 3.6588201
OS 4.066156 3.665063
OS 4.0649142 3.6713059
OS 4.0613779 3.6765984
OS 4.0560854 3.6801347
OS 4.0498425 3.6813765
OE
OB 2.6798425 3.6773765 H
OS 2.6735996 3.6761347
OS 2.6683071 3.6725984
OS 2.6647708 3.6673059
OS 2.663529 3.661063
OS 2.6647708 3.6548201
OS 2.6683071 3.6495276
OS 2.6735996 3.6459913
OS 2.6798425 3.6447495
OS 2.6860854 3.6459913
OS 2.6913779 3.6495276
OS 2.6949142 3.6548201
OS 2.696156 3.661063
OS 2.6949142 3.6673059
OS 2.6913779 3.6725984
OS 2.6860854 3.6761347
OS 2.6798425 3.6773765
OE
OB 1.7548425 3.6773765 H
OS 1.7485996 3.6761347
OS 1.7433071 3.6725984
OS 1.7397708 3.6673059
OS 1.738529 3.661063
OS 1.7397708 3.6548201
OS 1.7433071 3.6495276
OS 1.7485996 3.6459913
OS 1.7548425 3.6447495
OS 1.7610854 3.6459913
OS 1.7663779 3.6495276
OS 1.7699142 3.6548201
OS 1.771156 3.661063
OS 1.7699142 3.6673059
OS 1.7663779 3.6725984
OS 1.7610854 3.6761347
OS 1.7548425 3.6773765
OE
OB 3.4248425 3.6523765 H
OS 3.4185996 3.6511347
OS 3.4133071 3.6475984
OS 3.4097708 3.6423059
OS 3.408529 3.636063
OS 3.4097708 3.6298201
OS 3.4133071 3.6245276
OS 3.4185996 3.6209913
OS 3.4248425 3.6197495
OS 3.4310854 3.6209913
OS 3.4363779 3.6245276
OS 3.4399142 3.6298201
OS 3.441156 3.636063
OS 3.4399142 3.6423059
OS 3.4363779 3.6475984
OS 3.4310854 3.6511347
OS 3.4248425 3.6523765
OE
OB 2.7998425 3.6323765 H
OS 2.7935996 3.6311347
OS 2.7883071 3.6275984
OS 2.7847708 3.6223059
OS 2.783529 3.616063
OS 2.7847708 3.6098201
OS 2.7883071 3.6045276
OS 2.7935996 3.6009913
OS 2.7998425 3.5997495
OS 2.8060854 3.6009913
OS 2.8113779 3.6045276
OS 2.8149142 3.6098201
OS 2.816156 3.616063
OS 2.8149142 3.6223059
OS 2.8113779 3.6275984
OS 2.8060854 3.6311347
OS 2.7998425 3.6323765
OE
OB 2.1398425 3.6273765 H
OS 2.1335996 3.6261347
OS 2.1283071 3.6225984
OS 2.1247708 3.6173059
OS 2.123529 3.611063
OS 2.1247708 3.6048201
OS 2.1283071 3.5995276
OS 2.1335996 3.5959913
OS 2.1398425 3.5947495
OS 2.1460854 3.5959913
OS 2.1513779 3.5995276
OS 2.1549142 3.6048201
OS 2.156156 3.611063
OS 2.1549142 3.6173059
OS 2.1513779 3.6225984
OS 2.1460854 3.6261347
OS 2.1398425 3.6273765
OE
OB 1.8848425 3.6173765 H
OS 1.8785996 3.6161347
OS 1.8733071 3.6125984
OS 1.8697708 3.6073059
OS 1.868529 3.601063
OS 1.8697708 3.5948201
OS 1.8733071 3.5895276
OS 1.8785996 3.5859913
OS 1.8848425 3.5847495
OS 1.8910854 3.5859913
OS 1.8963779 3.5895276
OS 1.8999142 3.5948201
OS 1.901156 3.601063
OS 1.8999142 3.6073059
OS 1.8963779 3.6125984
OS 1.8910854 3.6161347
OS 1.8848425 3.6173765
OE
OB 3.2398425 3.6123765 H
OS 3.2335996 3.6111347
OS 3.2283071 3.6075984
OS 3.2247708 3.6023059
OS 3.223529 3.596063
OS 3.2247708 3.5898201
OS 3.2283071 3.5845276
OS 3.2335996 3.5809913
OS 3.2398425 3.5797495
OS 3.2460854 3.5809913
OS 3.2513779 3.5845276
OS 3.2549142 3.5898201
OS 3.256156 3.596063
OS 3.2549142 3.6023059
OS 3.2513779 3.6075984
OS 3.2460854 3.6111347
OS 3.2398425 3.6123765
OE
OB 1.5498425 3.6373765 H
OS 1.5435996 3.6361347
OS 1.5383071 3.6325984
OS 1.5347708 3.6273059
OS 1.533529 3.621063
OS 1.5347708 3.6148201
OS 1.5383071 3.6095276
OS 1.5435996 3.6059913
OS 1.5498425 3.6047495
OS 1.5560854 3.6059913
OS 1.5563282 3.6061536
OS 1.5599331 3.6025487
OS 1.5597708 3.6023059
OS 1.558529 3.596063
OS 1.5597708 3.5898201
OS 1.5633071 3.5845276
OS 1.5685996 3.5809913
OS 1.5748425 3.5797495
OS 1.5810854 3.5809913
OS 1.5863779 3.5845276
OS 1.5899142 3.5898201
OS 1.591156 3.596063
OS 1.5899142 3.6023059
OS 1.5863779 3.6075984
OS 1.5810854 3.6111347
OS 1.5748425 3.6123765
OS 1.5685996 3.6111347
OS 1.5683568 3.6109724
OS 1.5647519 3.6145773
OS 1.5649142 3.6148201
OS 1.566156 3.621063
OS 1.5649142 3.6273059
OS 1.5613779 3.6325984
OS 1.5560854 3.6361347
OS 1.5498425 3.6373765
OE
OB 2.4223425 3.6247884 H
OS 2.4133837 3.6230064
OS 2.4057888 3.6179317
OS 2.4007141 3.6103368
OS 2.3989321 3.601378
OS 2.4007141 3.5924192
OS 2.4057888 3.5848243
OS 2.4133837 3.5797496
OS 2.4223425 3.5779676
OS 2.4313013 3.5797496
OS 2.4388962 3.5848243
OS 2.4439709 3.5924192
OS 2.4457529 3.601378
OS 2.4439709 3.6103368
OS 2.4388962 3.6179317
OS 2.4313013 3.6230064
OS 2.4223425 3.6247884
OE
OB 2.7748425 3.5823765 H
OS 2.7685996 3.5811347
OS 2.7633071 3.5775984
OS 2.7597708 3.5723059
OS 2.758529 3.566063
OS 2.7597708 3.5598201
OS 2.7633071 3.5545276
OS 2.7685996 3.5509913
OS 2.7748425 3.5497495
OS 2.7810854 3.5509913
OS 2.7863779 3.5545276
OS 2.7899142 3.5598201
OS 2.791156 3.566063
OS 2.7899142 3.5723059
OS 2.7863779 3.5775984
OS 2.7810854 3.5811347
OS 2.7748425 3.5823765
OE
OB 1.4408425 3.5733765 H
OS 1.4345996 3.5721347
OS 1.4293071 3.5685984
OS 1.4257708 3.5633059
OS 1.424529 3.557063
OS 1.4257708 3.5508201
OS 1.4293071 3.5455276
OS 1.4345996 3.5419913
OS 1.4408425 3.5407495
OS 1.4470854 3.5419913
OS 1.4523779 3.5455276
OS 1.4559142 3.5508201
OS 1.457156 3.557063
OS 1.4559142 3.5633059
OS 1.4523779 3.5685984
OS 1.4470854 3.5721347
OS 1.4408425 3.5733765
OE
OB 5.9948425 3.5683765 H
OS 5.9885996 3.5671347
OS 5.9833071 3.5635984
OS 5.9797708 3.5583059
OS 5.978529 3.552063
OS 5.9797708 3.5458201
OS 5.9833071 3.5405276
OS 5.9885996 3.5369913
OS 5.9948425 3.5357495
OS 6.0010854 3.5369913
OS 6.0063779 3.5405276
OS 6.0099142 3.5458201
OS 6.011156 3.552063
OS 6.0099142 3.5583059
OS 6.0063779 3.5635984
OS 6.0010854 3.5671347
OS 5.9948425 3.5683765
OE
OB 2.4348425 3.5623765 H
OS 2.4285996 3.5611347
OS 2.4233071 3.5575984
OS 2.4197708 3.5523059
OS 2.418529 3.546063
OS 2.4197708 3.5398201
OS 2.4233071 3.5345276
OS 2.4285996 3.5309913
OS 2.4348425 3.5297495
OS 2.4410854 3.5309913
OS 2.4463779 3.5345276
OS 2.4499142 3.5398201
OS 2.451156 3.546063
OS 2.4499142 3.5523059
OS 2.4463779 3.5575984
OS 2.4410854 3.5611347
OS 2.4348425 3.5623765
OE
OB 2.2548425 3.5523765 H
OS 2.2485996 3.5511347
OS 2.2433071 3.5475984
OS 2.2397708 3.5423059
OS 2.238529 3.536063
OS 2.2397708 3.5298201
OS 2.2424883 3.5257531
OS 2.2396399 3.5214222
OS 2.2348425 3.5223765
OS 2.2285996 3.5211347
OS 2.2233071 3.5175984
OS 2.2197708 3.5123059
OS 2.218529 3.506063
OS 2.2197708 3.4998201
OS 2.2233071 3.4945276
OS 2.2285996 3.4909913
OS 2.2348425 3.4897495
OS 2.2410854 3.4909913
OS 2.2463779 3.4945276
OS 2.2499142 3.4998201
OS 2.251156 3.506063
OS 2.2499142 3.5123059
OS 2.2471967 3.5163729
OS 2.2500451 3.5207038
OS 2.2548425 3.5197495
OS 2.2610854 3.5209913
OS 2.2663779 3.5245276
OS 2.2699142 3.5298201
OS 2.271156 3.536063
OS 2.2699142 3.5423059
OS 2.2663779 3.5475984
OS 2.2610854 3.5511347
OS 2.2548425 3.5523765
OE
OB 5.2748425 3.5273765 H
OS 5.2685996 3.5261347
OS 5.2633071 3.5225984
OS 5.2597708 3.5173059
OS 5.258529 3.511063
OS 5.2597708 3.5048201
OS 5.2633071 3.4995276
OS 5.2685996 3.4959913
OS 5.2748425 3.4947495
OS 5.2810854 3.4959913
OS 5.2863779 3.4995276
OS 5.2899142 3.5048201
OS 5.291156 3.511063
OS 5.2899142 3.5173059
OS 5.2863779 3.5225984
OS 5.2810854 3.5261347
OS 5.2748425 3.5273765
OE
OB 3.6228425 3.5023765 H
OS 3.6165996 3.5011347
OS 3.6113071 3.4975984
OS 3.6077708 3.4923059
OS 3.606529 3.486063
OS 3.6077708 3.4798201
OS 3.6113071 3.4745276
OS 3.6165996 3.4709913
OS 3.6228425 3.4697495
OS 3.6290854 3.4709913
OS 3.6343779 3.4745276
OS 3.6379142 3.4798201
OS 3.639156 3.486063
OS 3.6379142 3.4923059
OS 3.6343779 3.4975984
OS 3.6290854 3.5011347
OS 3.6228425 3.5023765
OE
OB 2.5798425 3.5023765 H
OS 2.5735996 3.5011347
OS 2.5683071 3.4975984
OS 2.5647708 3.4923059
OS 2.563529 3.486063
OS 2.5647708 3.4798201
OS 2.5683071 3.4745276
OS 2.5735996 3.4709913
OS 2.5798425 3.4697495
OS 2.5860854 3.4709913
OS 2.5913779 3.4745276
OS 2.5949142 3.4798201
OS 2.596156 3.486063
OS 2.5949142 3.4923059
OS 2.5913779 3.4975984
OS 2.5860854 3.5011347
OS 2.5798425 3.5023765
OE
OB 3.5298425 3.4973765 H
OS 3.5235996 3.4961347
OS 3.5183071 3.4925984
OS 3.5147708 3.4873059
OS 3.513529 3.481063
OS 3.5147708 3.4748201
OS 3.5183071 3.4695276
OS 3.5235996 3.4659913
OS 3.5298425 3.4647495
OS 3.5360854 3.4659913
OS 3.5413779 3.4695276
OS 3.5449142 3.4748201
OS 3.546156 3.481063
OS 3.5449142 3.4873059
OS 3.5413779 3.4925984
OS 3.5360854 3.4961347
OS 3.5298425 3.4973765
OE
OB 2.3898425 3.4973765 H
OS 2.3835996 3.4961347
OS 2.3783071 3.4925984
OS 2.3747708 3.4873059
OS 2.373529 3.481063
OS 2.3747708 3.4748201
OS 2.3783071 3.4695276
OS 2.3835996 3.4659913
OS 2.3898425 3.4647495
OS 2.3960854 3.4659913
OS 2.4013779 3.4695276
OS 2.4049142 3.4748201
OS 2.406156 3.481063
OS 2.4049142 3.4873059
OS 2.4013779 3.4925984
OS 2.3960854 3.4961347
OS 2.3898425 3.4973765
OE
OB 6.5098425 3.4723765 H
OS 6.5035996 3.4711347
OS 6.4983071 3.4675984
OS 6.4947708 3.4623059
OS 6.493529 3.456063
OS 6.4947708 3.4498201
OS 6.4983071 3.4445276
OS 6.5035996 3.4409913
OS 6.5098425 3.4397495
OS 6.5160854 3.4409913
OS 6.5213779 3.4445276
OS 6.5249142 3.4498201
OS 6.526156 3.456063
OS 6.5249142 3.4623059
OS 6.5213779 3.4675984
OS 6.5160854 3.4711347
OS 6.5098425 3.4723765
OE
OB 3.4368425 3.4733765 H
OS 3.4305996 3.4721347
OS 3.4253071 3.4685984
OS 3.4217708 3.4633059
OS 3.420529 3.457063
OS 3.4217708 3.4508201
OS 3.4253071 3.4455276
OS 3.4305996 3.4419913
OS 3.4368425 3.4407495
OS 3.4430854 3.4419913
OS 3.4483779 3.4455276
OS 3.4502305 3.4483003
OS 3.4506142 3.4484287
OS 3.4560152 3.4479578
OS 3.4583071 3.4445276
OS 3.4635996 3.4409913
OS 3.4698425 3.4397495
OS 3.4760854 3.4409913
OS 3.4813779 3.4445276
OS 3.4849142 3.4498201
OS 3.486156 3.456063
OS 3.4849142 3.4623059
OS 3.4813779 3.4675984
OS 3.4760854 3.4711347
OS 3.4698425 3.4723765
OS 3.4635996 3.4711347
OS 3.4583071 3.4675984
OS 3.4564545 3.4648257
OS 3.4560708 3.4646973
OS 3.4506698 3.4651682
OS 3.4483779 3.4685984
OS 3.4430854 3.4721347
OS 3.4368425 3.4733765
OE
OB 3.3588425 3.4643765 H
OS 3.3525996 3.4631347
OS 3.3473071 3.4595984
OS 3.3437708 3.4543059
OS 3.342529 3.448063
OS 3.3437708 3.4418201
OS 3.3473071 3.4365276
OS 3.3525996 3.4329913
OS 3.3588425 3.4317495
OS 3.3650854 3.4329913
OS 3.3703779 3.4365276
OS 3.3739142 3.4418201
OS 3.3741941 3.443227
OS 3.379292 3.443227
OS 3.3797708 3.4408201
OS 3.3833071 3.4355276
OS 3.3885996 3.4319913
OS 3.3948425 3.4307495
OS 3.4010854 3.4319913
OS 3.4063779 3.4355276
OS 3.4099142 3.4408201
OS 3.411156 3.447063
OS 3.4099142 3.4533059
OS 3.4063779 3.4585984
OS 3.4010854 3.4621347
OS 3.3948425 3.4633765
OS 3.3885996 3.4621347
OS 3.3833071 3.4585984
OS 3.3797708 3.4533059
OS 3.3794909 3.451899
OS 3.374393 3.451899
OS 3.3739142 3.4543059
OS 3.3703779 3.4595984
OS 3.3650854 3.4631347
OS 3.3588425 3.4643765
OE
OB 2.4223425 3.4673081 H
OS 2.4133837 3.4655261
OS 2.4057888 3.4604514
OS 2.4007141 3.4528565
OS 2.3989321 3.4438977
OS 2.4007141 3.4349389
OS 2.4057888 3.427344
OS 2.4133837 3.4222693
OS 2.4223425 3.4204873
OS 2.4313013 3.4222693
OS 2.4388962 3.427344
OS 2.4439709 3.4349389
OS 2.4457529 3.4438977
OS 2.4439709 3.4528565
OS 2.4388962 3.4604514
OS 2.4313013 3.4655261
OS 2.4223425 3.4673081
OE
OB 6.4798425 3.4423765 H
OS 6.4735996 3.4411347
OS 6.4683071 3.4375984
OS 6.4647708 3.4323059
OS 6.463529 3.426063
OS 6.4647708 3.4198201
OS 6.4683071 3.4145276
OS 6.4735996 3.4109913
OS 6.4798425 3.4097495
OS 6.4860854 3.4109913
OS 6.4913779 3.4145276
OS 6.4949142 3.4198201
OS 6.496156 3.426063
OS 6.4949142 3.4323059
OS 6.4913779 3.4375984
OS 6.4860854 3.4411347
OS 6.4798425 3.4423765
OE
OB 2.6348425 3.4223765 H
OS 2.6285996 3.4211347
OS 2.6233071 3.4175984
OS 2.6197708 3.4123059
OS 2.618529 3.406063
OS 2.6197708 3.3998201
OS 2.6233071 3.3945276
OS 2.6285996 3.3909913
OS 2.6348425 3.3897495
OS 2.6410854 3.3909913
OS 2.6463779 3.3945276
OS 2.6499142 3.3998201
OS 2.651156 3.406063
OS 2.6499142 3.4123059
OS 2.6463779 3.4175984
OS 2.6410854 3.4211347
OS 2.6348425 3.4223765
OE
OB 6.4475772 3.4123765 H
OS 6.4413343 3.4111347
OS 6.4360418 3.4075984
OS 6.4325055 3.4023059
OS 6.4312637 3.396063
OS 6.4325055 3.3898201
OS 6.4360418 3.3845276
OS 6.4413343 3.3809913
OS 6.4475772 3.3797495
OS 6.4538201 3.3809913
OS 6.4591126 3.3845276
OS 6.4626489 3.3898201
OS 6.4638907 3.396063
OS 6.4626489 3.4023059
OS 6.4591126 3.4075984
OS 6.4538201 3.4111347
OS 6.4475772 3.4123765
OE
OB 3.0688976 3.4119828 H
OS 3.0626547 3.410741
OS 3.0573622 3.4072047
OS 3.0538259 3.4019122
OS 3.0525841 3.3956693
OS 3.0538259 3.3894264
OS 3.0573622 3.3841339
OS 3.0626547 3.3805976
OS 3.0688976 3.3793558
OS 3.0751405 3.3805976
OS 3.080433 3.3841339
OS 3.0839693 3.3894264
OS 3.0852111 3.3956693
OS 3.0839693 3.4019122
OS 3.080433 3.4072047
OS 3.0751405 3.410741
OS 3.0688976 3.4119828
OE
OB 6.4098425 3.3873765 H
OS 6.4035996 3.3861347
OS 6.3983071 3.3825984
OS 6.3947708 3.3773059
OS 6.393529 3.371063
OS 6.3947708 3.3648201
OS 6.3983071 3.3595276
OS 6.4035996 3.3559913
OS 6.4098425 3.3547495
OS 6.4160854 3.3559913
OS 6.4213779 3.3595276
OS 6.4249142 3.3648201
OS 6.426156 3.371063
OS 6.4249142 3.3773059
OS 6.4213779 3.3825984
OS 6.4160854 3.3861347
OS 6.4098425 3.3873765
OE
OB 3.3028425 3.3603765 H
OS 3.2965996 3.3591347
OS 3.2913071 3.3555984
OS 3.2877708 3.3503059
OS 3.286529 3.344063
OS 3.2877708 3.3378201
OS 3.2913071 3.3325276
OS 3.2965996 3.3289913
OS 3.3028425 3.3277495
OS 3.3090854 3.3289913
OS 3.3143779 3.3325276
OS 3.3179142 3.3378201
OS 3.319156 3.344063
OS 3.3179142 3.3503059
OS 3.3143779 3.3555984
OS 3.3090854 3.3591347
OS 3.3028425 3.3603765
OE
OB 6.3547483 3.3474519 H
OS 6.3485054 3.3462101
OS 6.3432129 3.3426738
OS 6.3396766 3.3373813
OS 6.3384348 3.3311384
OS 6.3396766 3.3248955
OS 6.3432129 3.319603
OS 6.3485054 3.3160667
OS 6.3547483 3.3148249
OS 6.3609912 3.3160667
OS 6.3662837 3.319603
OS 6.36982 3.3248955
OS 6.3710618 3.3311384
OS 6.36982 3.3373813
OS 6.3662837 3.3426738
OS 6.3609912 3.3462101
OS 6.3547483 3.3474519
OE
OB 3.542865 3.335354 H
OS 3.5366221 3.3341122
OS 3.5313296 3.3305759
OS 3.5277933 3.3252834
OS 3.5265515 3.3190405
OS 3.5277933 3.3127976
OS 3.5313296 3.3075051
OS 3.5366221 3.3039688
OS 3.542865 3.302727
OS 3.5491079 3.3039688
OS 3.5544004 3.3075051
OS 3.5579367 3.3127976
OS 3.5591785 3.3190405
OS 3.5579367 3.3252834
OS 3.5544004 3.3305759
OS 3.5491079 3.3341122
OS 3.542865 3.335354
OE
OB 3.2636972 3.3202312 H
OS 3.2574543 3.3189894
OS 3.2521618 3.3154531
OS 3.2486255 3.3101606
OS 3.2473837 3.3039177
OS 3.2486255 3.2976748
OS 3.2521618 3.2923823
OS 3.2574543 3.288846
OS 3.2636972 3.2876042
OS 3.2699401 3.288846
OS 3.2752326 3.2923823
OS 3.2787689 3.2976748
OS 3.2800107 3.3039177
OS 3.2787689 3.3101606
OS 3.2752326 3.3154531
OS 3.2699401 3.3189894
OS 3.2636972 3.3202312
OE
OB 3.4918425 3.3133765 H
OS 3.4855996 3.3121347
OS 3.4803071 3.3085984
OS 3.4767708 3.3033059
OS 3.475529 3.297063
OS 3.4767708 3.2908201
OS 3.4803071 3.2855276
OS 3.4855996 3.2819913
OS 3.4918425 3.2807495
OS 3.4980854 3.2819913
OS 3.5033779 3.2855276
OS 3.5069142 3.2908201
OS 3.508156 3.297063
OS 3.5069142 3.3033059
OS 3.5033779 3.3085984
OS 3.4980854 3.3121347
OS 3.4918425 3.3133765
OE
OB 3.6538425 3.3093765 H
OS 3.6475996 3.3081347
OS 3.6423071 3.3045984
OS 3.6387708 3.2993059
OS 3.637529 3.293063
OS 3.6387708 3.2868201
OS 3.6423071 3.2815276
OS 3.6475996 3.2779913
OS 3.6538425 3.2767495
OS 3.6600854 3.2779913
OS 3.6653779 3.2815276
OS 3.6689142 3.2868201
OS 3.670156 3.293063
OS 3.6689142 3.2993059
OS 3.6653779 3.3045984
OS 3.6600854 3.3081347
OS 3.6538425 3.3093765
OE
OB 6.4448425 3.3073765 H
OS 6.4385996 3.3061347
OS 6.4333071 3.3025984
OS 6.4297708 3.2973059
OS 6.428529 3.291063
OS 6.4297708 3.2848201
OS 6.4333071 3.2795276
OS 6.4385996 3.2759913
OS 6.4448425 3.2747495
OS 6.4510854 3.2759913
OS 6.4563779 3.2795276
OS 6.4599142 3.2848201
OS 6.461156 3.291063
OS 6.4599142 3.2973059
OS 6.4563779 3.3025984
OS 6.4510854 3.3061347
OS 6.4448425 3.3073765
OE
OB 2.5908425 3.3043765 H
OS 2.5845996 3.3031347
OS 2.5793071 3.2995984
OS 2.5757708 3.2943059
OS 2.574529 3.288063
OS 2.5757708 3.2818201
OS 2.5793071 3.2765276
OS 2.5845996 3.2729913
OS 2.5908425 3.2717495
OS 2.5970854 3.2729913
OS 2.6023779 3.2765276
OS 2.6059142 3.2818201
OS 2.607156 3.288063
OS 2.6059142 3.2943059
OS 2.6023779 3.2995984
OS 2.5970854 3.3031347
OS 2.5908425 3.3043765
OE
OB 3.3748425 3.2893765 H
OS 3.3685996 3.2881347
OS 3.3633071 3.2845984
OS 3.3597708 3.2793059
OS 3.358529 3.273063
OS 3.3597708 3.2668201
OS 3.3633071 3.2615276
OS 3.3685996 3.2579913
OS 3.3748425 3.2567495
OS 3.3810854 3.2579913
OS 3.3863779 3.2615276
OS 3.3899142 3.2668201
OS 3.391156 3.273063
OS 3.3899142 3.2793059
OS 3.3863779 3.2845984
OS 3.3810854 3.2881347
OS 3.3748425 3.2893765
OE
OB 6.3348425 3.2823765 H
OS 6.3285996 3.2811347
OS 6.3233071 3.2775984
OS 6.3197708 3.2723059
OS 6.318529 3.266063
OS 6.3197708 3.2598201
OS 6.3233071 3.2545276
OS 6.3285996 3.2509913
OS 6.3348425 3.2497495
OS 6.3410854 3.2509913
OS 6.3463779 3.2545276
OS 6.3499142 3.2598201
OS 6.351156 3.266063
OS 6.3499142 3.2723059
OS 6.3463779 3.2775984
OS 6.3410854 3.2811347
OS 6.3348425 3.2823765
OE
OB 3.7448425 3.2773765 H
OS 3.7385996 3.2761347
OS 3.7333071 3.2725984
OS 3.7297708 3.2673059
OS 3.728529 3.261063
OS 3.7297708 3.2548201
OS 3.7333071 3.2495276
OS 3.7385996 3.2459913
OS 3.7448425 3.2447495
OS 3.7510854 3.2459913
OS 3.7563779 3.2495276
OS 3.7599142 3.2548201
OS 3.761156 3.261063
OS 3.7599142 3.2673059
OS 3.7563779 3.2725984
OS 3.7510854 3.2761347
OS 3.7448425 3.2773765
OE
OB 2.2598425 3.2773765 H
OS 2.2535996 3.2761347
OS 2.2483071 3.2725984
OS 2.2447708 3.2673059
OS 2.243529 3.261063
OS 2.2447708 3.2548201
OS 2.2483071 3.2495276
OS 2.2535996 3.2459913
OS 2.2598425 3.2447495
OS 2.2660854 3.2459913
OS 2.2713779 3.2495276
OS 2.2749142 3.2548201
OS 2.276156 3.261063
OS 2.2749142 3.2673059
OS 2.2713779 3.2725984
OS 2.2660854 3.2761347
OS 2.2598425 3.2773765
OE
OB 3.2308425 3.2513765 H
OS 3.2245996 3.2501347
OS 3.2193071 3.2465984
OS 3.2157708 3.2413059
OS 3.214529 3.235063
OS 3.2157708 3.2288201
OS 3.2193071 3.2235276
OS 3.2245996 3.2199913
OS 3.2308425 3.2187495
OS 3.2370854 3.2199913
OS 3.2423779 3.2235276
OS 3.2459142 3.2288201
OS 3.247156 3.235063
OS 3.2459142 3.2413059
OS 3.2423779 3.2465984
OS 3.2370854 3.2501347
OS 3.2308425 3.2513765
OE
OB 6.2824161 3.2423765 H
OS 6.2761732 3.2411347
OS 6.2708807 3.2375984
OS 6.2673444 3.2323059
OS 6.2661026 3.226063
OS 6.2673444 3.2198201
OS 6.2708807 3.2145276
OS 6.2761732 3.2109913
OS 6.2824161 3.2097495
OS 6.288659 3.2109913
OS 6.2939515 3.2145276
OS 6.2974878 3.2198201
OS 6.2987296 3.226063
OS 6.2974878 3.2323059
OS 6.2939515 3.2375984
OS 6.288659 3.2411347
OS 6.2824161 3.2423765
OE
OB 3.8068425 3.2513765 H
OS 3.8005996 3.2501347
OS 3.7953071 3.2465984
OS 3.7917708 3.2413059
OS 3.790529 3.235063
OS 3.7917708 3.2288201
OS 3.7953071 3.2235276
OS 3.7975621 3.2220209
OS 3.7965063 3.2167129
OS 3.7935996 3.2161347
OS 3.7883071 3.2125984
OS 3.7847708 3.2073059
OS 3.783529 3.201063
OS 3.7847708 3.1948201
OS 3.7883071 3.1895276
OS 3.7935996 3.1859913
OS 3.7998425 3.1847495
OS 3.8060854 3.1859913
OS 3.8113779 3.1895276
OS 3.8149142 3.1948201
OS 3.816156 3.201063
OS 3.8149142 3.2073059
OS 3.8113779 3.2125984
OS 3.8091229 3.2141051
OS 3.8101787 3.2194131
OS 3.8130854 3.2199913
OS 3.8183779 3.2235276
OS 3.8219142 3.2288201
OS 3.823156 3.235063
OS 3.8219142 3.2413059
OS 3.8183779 3.2465984
OS 3.8130854 3.2501347
OS 3.8068425 3.2513765
OE
OB 2.2058425 3.2163765 H
OS 2.1995996 3.2151347
OS 2.1943071 3.2115984
OS 2.1907708 3.2063059
OS 2.189529 3.200063
OS 2.1907708 3.1938201
OS 2.1943071 3.1885276
OS 2.1995996 3.1849913
OS 2.2058425 3.1837495
OS 2.2120854 3.1849913
OS 2.2173779 3.1885276
OS 2.2209142 3.1938201
OS 2.222156 3.200063
OS 2.2209142 3.2063059
OS 2.2173779 3.2115984
OS 2.2120854 3.2151347
OS 2.2058425 3.2163765
OE
OB 2.4223425 3.2631033 H
OS 2.4133837 3.2613213
OS 2.4057888 3.2562466
OS 2.4007141 3.2486517
OS 2.3989321 3.2396929
OS 2.4007141 3.2307341
OS 2.4057888 3.2231392
OS 2.4098502 3.2204255
OS 2.4087944 3.2151175
OS 2.4078122 3.2149221
OS 2.4025197 3.2113858
OS 2.3989834 3.2060933
OS 2.3977416 3.1998504
OS 2.3989834 3.1936075
OS 2.4025197 3.188315
OS 2.4078122 3.1847787
OS 2.4140551 3.1835369
OS 2.420298 3.1847787
OS 2.4255905 3.188315
OS 2.4291268 3.1936075
OS 2.4303686 3.1998504
OS 2.4291268 3.2060933
OS 2.4255905 3.2113858
OS 2.4250776 3.2117285
OS 2.4261334 3.2170365
OS 2.4313013 3.2180645
OS 2.4388962 3.2231392
OS 2.4439709 3.2307341
OS 2.4457529 3.2396929
OS 2.4439709 3.2486517
OS 2.4388962 3.2562466
OS 2.4313013 3.2613213
OS 2.4223425 3.2631033
OE
OB 6.3094161 3.2153765 H
OS 6.3031732 3.2141347
OS 6.2978807 3.2105984
OS 6.2943444 3.2053059
OS 6.2931026 3.199063
OS 6.2943444 3.1928201
OS 6.2978807 3.1875276
OS 6.3031732 3.1839913
OS 6.3094161 3.1827495
OS 6.315659 3.1839913
OS 6.3209515 3.1875276
OS 6.3244878 3.1928201
OS 6.3257296 3.199063
OS 6.3244878 3.2053059
OS 6.3209515 3.2105984
OS 6.315659 3.2141347
OS 6.3094161 3.2153765
OE
OB 6.4398425 3.2073765 H
OS 6.4335996 3.2061347
OS 6.4283071 3.2025984
OS 6.4247708 3.1973059
OS 6.423529 3.191063
OS 6.4247708 3.1848201
OS 6.4283071 3.1795276
OS 6.4335996 3.1759913
OS 6.4398425 3.1747495
OS 6.4460854 3.1759913
OS 6.4513779 3.1795276
OS 6.4549142 3.1848201
OS 6.456156 3.191063
OS 6.4549142 3.1973059
OS 6.4513779 3.2025984
OS 6.4460854 3.2061347
OS 6.4398425 3.2073765
OE
OB 3.1889764 3.2033214 H
OS 3.1827335 3.2020796
OS 3.177441 3.1985433
OS 3.1739047 3.1932508
OS 3.1726629 3.1870079
OS 3.1739047 3.180765
OS 3.177441 3.1754725
OS 3.1827335 3.1719362
OS 3.1889764 3.1706944
OS 3.1952193 3.1719362
OS 3.2005118 3.1754725
OS 3.2040481 3.180765
OS 3.2052899 3.1870079
OS 3.2040481 3.1932508
OS 3.2005118 3.1985433
OS 3.1952193 3.2020796
OS 3.1889764 3.2033214
OE
OB 2.5918425 3.202534 H
OS 2.5855996 3.2012922
OS 2.5803071 3.1977559
OS 2.5767708 3.1924634
OS 2.575529 3.1862205
OS 2.5767708 3.1799776
OS 2.5803071 3.1746851
OS 2.5855996 3.1711488
OS 2.5918425 3.169907
OS 2.5980854 3.1711488
OS 2.6033779 3.1746851
OS 2.6069142 3.1799776
OS 2.608156 3.1862205
OS 2.6069142 3.1924634
OS 2.6033779 3.1977559
OS 2.5980854 3.2012922
OS 2.5918425 3.202534
OE
OB 2.462374 3.1885576 H
OS 2.4561311 3.1873158
OS 2.4508386 3.1837795
OS 2.4473023 3.178487
OS 2.4460605 3.1722441
OS 2.4473023 3.1660012
OS 2.4508386 3.1607087
OS 2.4561311 3.1571724
OS 2.462374 3.1559306
OS 2.4686169 3.1571724
OS 2.4739094 3.1607087
OS 2.4774457 3.1660012
OS 2.4786875 3.1722441
OS 2.4774457 3.178487
OS 2.4739094 3.1837795
OS 2.4686169 3.1873158
OS 2.462374 3.1885576
OE
OB 6.3398425 3.1673765 H
OS 6.3335996 3.1661347
OS 6.3283071 3.1625984
OS 6.3247708 3.1573059
OS 6.323529 3.151063
OS 6.3247708 3.1448201
OS 6.3283071 3.1395276
OS 6.3335996 3.1359913
OS 6.3398425 3.1347495
OS 6.3460854 3.1359913
OS 6.3513779 3.1395276
OS 6.3549142 3.1448201
OS 6.356156 3.151063
OS 6.3549142 3.1573059
OS 6.3513779 3.1625984
OS 6.3460854 3.1661347
OS 6.3398425 3.1673765
OE
OB 3.8298425 3.1923765 H
OS 3.8235996 3.1911347
OS 3.8183071 3.1875984
OS 3.8147708 3.1823059
OS 3.813529 3.176063
OS 3.8147708 3.1698201
OS 3.8183071 3.1645276
OS 3.8235996 3.1609913
OS 3.8298425 3.1597495
OS 3.8360854 3.1609913
OS 3.8363282 3.1611536
OS 3.8399331 3.1575487
OS 3.8397708 3.1573059
OS 3.838529 3.151063
OS 3.8397708 3.1448201
OS 3.8433071 3.1395276
OS 3.8485996 3.1359913
OS 3.8548425 3.1347495
OS 3.8610854 3.1359913
OS 3.8663779 3.1395276
OS 3.8699142 3.1448201
OS 3.871156 3.151063
OS 3.8699142 3.1573059
OS 3.8663779 3.1625984
OS 3.8610854 3.1661347
OS 3.8548425 3.1673765
OS 3.8485996 3.1661347
OS 3.8483568 3.1659724
OS 3.8447519 3.1695773
OS 3.8449142 3.1698201
OS 3.846156 3.176063
OS 3.8449142 3.1823059
OS 3.8413779 3.1875984
OS 3.8360854 3.1911347
OS 3.8298425 3.1923765
OE
OB 1.4598425 3.1633765 H
OS 1.4535996 3.1621347
OS 1.4483071 3.1585984
OS 1.4447708 3.1533059
OS 1.443529 3.147063
OS 1.4447708 3.1408201
OS 1.4483071 3.1355276
OS 1.4535996 3.1319913
OS 1.4598425 3.1307495
OS 1.4660854 3.1319913
OS 1.4713779 3.1355276
OS 1.4749142 3.1408201
OS 1.476156 3.147063
OS 1.4749142 3.1533059
OS 1.4713779 3.1585984
OS 1.4660854 3.1621347
OS 1.4598425 3.1633765
OE
OB 3.2755905 3.1580458 H
OS 3.2693476 3.156804
OS 3.2640551 3.1532677
OS 3.2605188 3.1479752
OS 3.259277 3.1417323
OS 3.2605188 3.1354894
OS 3.2640551 3.1301969
OS 3.2693476 3.1266606
OS 3.2755905 3.1254188
OS 3.2818334 3.1266606
OS 3.2871259 3.1301969
OS 3.2906622 3.1354894
OS 3.291904 3.1417323
OS 3.2906622 3.1479752
OS 3.2871259 3.1532677
OS 3.2818334 3.156804
OS 3.2755905 3.1580458
OE
OB 6.3048425 3.1373765 H
OS 6.2985996 3.1361347
OS 6.2933071 3.1325984
OS 6.2897708 3.1273059
OS 6.288529 3.121063
OS 6.2897708 3.1148201
OS 6.2933071 3.1095276
OS 6.2985996 3.1059913
OS 6.3048425 3.1047495
OS 6.3110854 3.1059913
OS 6.3163779 3.1095276
OS 6.3199142 3.1148201
OS 6.321156 3.121063
OS 6.3199142 3.1273059
OS 6.3163779 3.1325984
OS 6.3110854 3.1361347
OS 6.3048425 3.1373765
OE
OB 3.9398425 3.1373765 H
OS 3.9335996 3.1361347
OS 3.9283071 3.1325984
OS 3.9247708 3.1273059
OS 3.923529 3.121063
OS 3.9247708 3.1148201
OS 3.9283071 3.1095276
OS 3.9335996 3.1059913
OS 3.9398425 3.1047495
OS 3.9460854 3.1059913
OS 3.9513779 3.1095276
OS 3.9549142 3.1148201
OS 3.956156 3.121063
OS 3.9549142 3.1273059
OS 3.9513779 3.1325984
OS 3.9460854 3.1361347
OS 3.9398425 3.1373765
OE
OB 3.4918425 3.1193765 H
OS 3.4855996 3.1181347
OS 3.4803071 3.1145984
OS 3.4767708 3.1093059
OS 3.475529 3.103063
OS 3.4767708 3.0968201
OS 3.4803071 3.0915276
OS 3.4855996 3.0879913
OS 3.4918425 3.0867495
OS 3.4980854 3.0879913
OS 3.5033779 3.0915276
OS 3.5069142 3.0968201
OS 3.508156 3.103063
OS 3.5069142 3.1093059
OS 3.5033779 3.1145984
OS 3.4980854 3.1181347
OS 3.4918425 3.1193765
OE
OB 2.4187174 3.1348201 H
OS 2.4124745 3.1335783
OS 2.407182 3.130042
OS 2.4036457 3.1247495
OS 2.4024039 3.1185066
OS 2.4036457 3.1122637
OS 2.407182 3.1069712
OS 2.4081253 3.1063409
OS 2.4081253 3.1003275
OS 2.4057888 3.0987663
OS 2.4007141 3.0911714
OS 2.3989321 3.0822126
OS 2.4007141 3.0732538
OS 2.4057888 3.0656589
OS 2.4133837 3.0605842
OS 2.4223425 3.0588022
OS 2.4313013 3.0605842
OS 2.4388962 3.0656589
OS 2.4439709 3.0732538
OS 2.4457529 3.0822126
OS 2.4439709 3.0911714
OS 2.4388962 3.0987663
OS 2.4329346 3.1027496
OS 2.4313655 3.1052197
OS 2.4315364 3.1088922
OS 2.4337891 3.1122637
OS 2.4350309 3.1185066
OS 2.4337891 3.1247495
OS 2.4302528 3.130042
OS 2.4249603 3.1335783
OS 2.4187174 3.1348201
OE
OB 3.3688425 3.0663765 H
OS 3.3625996 3.0651347
OS 3.3573071 3.0615984
OS 3.3537708 3.0563059
OS 3.352529 3.050063
OS 3.3537708 3.0438201
OS 3.3573071 3.0385276
OS 3.3625996 3.0349913
OS 3.3688425 3.0337495
OS 3.3750854 3.0349913
OS 3.3803779 3.0385276
OS 3.3839142 3.0438201
OS 3.385156 3.050063
OS 3.3839142 3.0563059
OS 3.3803779 3.0615984
OS 3.3750854 3.0651347
OS 3.3688425 3.0663765
OE
OB 3.3448425 3.0123765 H
OS 3.3385996 3.0111347
OS 3.3333071 3.0075984
OS 3.3297708 3.0023059
OS 3.328529 2.996063
OS 3.3297708 2.9898201
OS 3.3333071 2.9845276
OS 3.3385996 2.9809913
OS 3.3448425 2.9797495
OS 3.3510854 2.9809913
OS 3.3563779 2.9845276
OS 3.3599142 2.9898201
OS 3.361156 2.996063
OS 3.3599142 3.0023059
OS 3.3563779 3.0075984
OS 3.3510854 3.0111347
OS 3.3448425 3.0123765
OE
OB 3.1978425 2.9863765 H
OS 3.1915996 2.9851347
OS 3.1863071 2.9815984
OS 3.1827708 2.9763059
OS 3.181529 2.970063
OS 3.1827708 2.9638201
OS 3.1863071 2.9585276
OS 3.1915996 2.9549913
OS 3.1978425 2.9537495
OS 3.2040854 2.9549913
OS 3.2093779 2.9585276
OS 3.2129142 2.9638201
OS 3.214156 2.970063
OS 3.2129142 2.9763059
OS 3.2093779 2.9815984
OS 3.2040854 2.9851347
OS 3.1978425 2.9863765
OE
OB 4.7942913 2.8243844 H
OS 4.7880484 2.8231426
OS 4.7827559 2.8196063
OS 4.7792196 2.8143138
OS 4.7779778 2.8080709
OS 4.7792196 2.801828
OS 4.7827559 2.7965355
OS 4.7880484 2.7929992
OS 4.7942913 2.7917574
OS 4.8005342 2.7929992
OS 4.8058267 2.7965355
OS 4.809363 2.801828
OS 4.8106048 2.8080709
OS 4.809363 2.8143138
OS 4.8058267 2.8196063
OS 4.8005342 2.8231426
OS 4.7942913 2.8243844
OE
OB 4.5036614 2.8061954 H
OS 4.4974185 2.8049536
OS 4.492126 2.8014173
OS 4.4885897 2.7961248
OS 4.4873479 2.7898819
OS 4.4885897 2.783639
OS 4.492126 2.7783465
OS 4.4974185 2.7748102
OS 4.5036614 2.7735684
OS 4.5099043 2.7748102
OS 4.5151968 2.7783465
OS 4.5187331 2.783639
OS 4.5199749 2.7898819
OS 4.5187331 2.7961248
OS 4.5151968 2.8014173
OS 4.5099043 2.8049536
OS 4.5036614 2.8061954
OE
OB 2.1468425 2.7693765 H
OS 2.1405996 2.7681347
OS 2.1353071 2.7645984
OS 2.1317708 2.7593059
OS 2.130529 2.753063
OS 2.1317708 2.7468201
OS 2.1353071 2.7415276
OS 2.1405996 2.7379913
OS 2.1468425 2.7367495
OS 2.1530854 2.7379913
OS 2.1583779 2.7415276
OS 2.1619142 2.7468201
OS 2.163156 2.753063
OS 2.1619142 2.7593059
OS 2.1583779 2.7645984
OS 2.1530854 2.7681347
OS 2.1468425 2.7693765
OE
OB 2.6929134 2.7377702 H
OS 2.6866705 2.7365284
OS 2.681378 2.7329921
OS 2.6778417 2.7276996
OS 2.6765999 2.7214567
OS 2.6778417 2.7152138
OS 2.681378 2.7099213
OS 2.6866705 2.706385
OS 2.6929134 2.7051432
OS 2.6991563 2.706385
OS 2.7044488 2.7099213
OS 2.7079851 2.7152138
OS 2.7092269 2.7214567
OS 2.7079851 2.7276996
OS 2.7044488 2.7329921
OS 2.6991563 2.7365284
OS 2.6929134 2.7377702
OE
OB 2.394685 2.7367859 H
OS 2.3884421 2.7355441
OS 2.3831496 2.7320078
OS 2.3796133 2.7267153
OS 2.3783715 2.7204724
OS 2.3796133 2.7142295
OS 2.3831496 2.708937
OS 2.3884421 2.7054007
OS 2.394685 2.7041589
OS 2.4009279 2.7054007
OS 2.4062204 2.708937
OS 2.4097567 2.7142295
OS 2.4109985 2.7204724
OS 2.4097567 2.7267153
OS 2.4062204 2.7320078
OS 2.4009279 2.7355441
OS 2.394685 2.7367859
OE
OB 2.4948425 2.7123765 H
OS 2.4885996 2.7111347
OS 2.4833071 2.7075984
OS 2.4797708 2.7023059
OS 2.478529 2.696063
OS 2.4797708 2.6898201
OS 2.4833071 2.6845276
OS 2.4883212 2.6811773
OS 2.4885995 2.6790399
OS 2.4885995 2.6780861
OS 2.4883212 2.6759487
OS 2.4833071 2.6725984
OS 2.4797708 2.6673059
OS 2.478529 2.661063
OS 2.4797708 2.6548201
OS 2.4833071 2.6495276
OS 2.4885996 2.6459913
OS 2.4948425 2.6447495
OS 2.5010854 2.6459913
OS 2.5063779 2.6495276
OS 2.5099142 2.6548201
OS 2.511156 2.661063
OS 2.5099142 2.6673059
OS 2.5063779 2.6725984
OS 2.5013638 2.6759487
OS 2.5010855 2.6780861
OS 2.5010855 2.6790399
OS 2.5013638 2.6811773
OS 2.5063779 2.6845276
OS 2.5099142 2.6898201
OS 2.511156 2.696063
OS 2.5099142 2.7023059
OS 2.5063779 2.7075984
OS 2.5010854 2.7111347
OS 2.4948425 2.7123765
OE
OB 2.9588425 2.6373765 H
OS 2.9525996 2.6361347
OS 2.9473071 2.6325984
OS 2.9437708 2.6273059
OS 2.942529 2.621063
OS 2.9437708 2.6148201
OS 2.9473071 2.6095276
OS 2.9525996 2.6059913
OS 2.9588425 2.6047495
OS 2.9650854 2.6059913
OS 2.9703779 2.6095276
OS 2.9739142 2.6148201
OS 2.975156 2.621063
OS 2.9739142 2.6273059
OS 2.9703779 2.6325984
OS 2.9650854 2.6361347
OS 2.9588425 2.6373765
OE
OB 2.4291925 2.6373765 H
OS 2.4229496 2.6361347
OS 2.4176571 2.6325984
OS 2.4141208 2.6273059
OS 2.412879 2.621063
OS 2.4141208 2.6148201
OS 2.4176571 2.6095276
OS 2.4229496 2.6059913
OS 2.4291925 2.6047495
OS 2.4354354 2.6059913
OS 2.4407279 2.6095276
OS 2.4442642 2.6148201
OS 2.445506 2.621063
OS 2.4442642 2.6273059
OS 2.4407279 2.6325984
OS 2.4354354 2.6361347
OS 2.4291925 2.6373765
OE
OB 2.2523425 2.6298765 H
OS 2.2460996 2.6286347
OS 2.2408071 2.6250984
OS 2.2372708 2.6198059
OS 2.236029 2.613563
OS 2.2372708 2.6073201
OS 2.239748 2.6036127
OS 2.2364566 2.5995388
OS 2.2317425 2.6004765
OS 2.2254996 2.5992347
OS 2.2202071 2.5956984
OS 2.2166708 2.5904059
OS 2.215429 2.584163
OS 2.2166708 2.5779201
OS 2.2202071 2.5726276
OS 2.2254996 2.5690913
OS 2.2317425 2.5678495
OS 2.2379854 2.5690913
OS 2.2432779 2.5726276
OS 2.2468142 2.5779201
OS 2.248056 2.584163
OS 2.2468142 2.5904059
OS 2.244337 2.5941133
OS 2.2476284 2.5981872
OS 2.2523425 2.5972495
OS 2.2585854 2.5984913
OS 2.2638779 2.6020276
OS 2.2674142 2.6073201
OS 2.268656 2.613563
OS 2.2674142 2.6198059
OS 2.2638779 2.6250984
OS 2.2585854 2.6286347
OS 2.2523425 2.6298765
OE
OB 2.8218425 2.6173765 H
OS 2.8155996 2.6161347
OS 2.8103071 2.6125984
OS 2.8067708 2.6073059
OS 2.805529 2.601063
OS 2.8067708 2.5948201
OS 2.8103071 2.5895276
OS 2.8155996 2.5859913
OS 2.8218425 2.5847495
OS 2.8280854 2.5859913
OS 2.8333779 2.5895276
OS 2.8369142 2.5948201
OS 2.838156 2.601063
OS 2.8369142 2.6073059
OS 2.8333779 2.6125984
OS 2.8280854 2.6161347
OS 2.8218425 2.6173765
OE
OB 3.6238425 2.6033765 H
OS 3.6175996 2.6021347
OS 3.6123071 2.5985984
OS 3.6087708 2.5933059
OS 3.607529 2.587063
OS 3.6087708 2.5808201
OS 3.6123071 2.5755276
OS 3.6175996 2.5719913
OS 3.6238425 2.5707495
OS 3.6300854 2.5719913
OS 3.6353779 2.5755276
OS 3.6389142 2.5808201
OS 3.640156 2.587063
OS 3.6389142 2.5933059
OS 3.6353779 2.5985984
OS 3.6300854 2.6021347
OS 3.6238425 2.6033765
OE
OB 4.2986248 2.6412356 H
OS 4.2867469 2.6396718
OS 4.2756785 2.6350872
OS 4.2661738 2.627794
OS 4.2588806 2.6182893
OS 4.254296 2.6072209
OS 4.2527322 2.595343
OS 4.254296 2.5834651
OS 4.2588806 2.5723967
OS 4.2661738 2.562892
OS 4.2756785 2.5555988
OS 4.2867469 2.5510142
OS 4.2986248 2.5494504
OS 4.3105027 2.5510142
OS 4.3215711 2.5555988
OS 4.3310758 2.562892
OS 4.338369 2.5723967
OS 4.3429536 2.5834651
OS 4.3445174 2.595343
OS 4.3429536 2.6072209
OS 4.338369 2.6182893
OS 4.3310758 2.627794
OS 4.3215711 2.6350872
OS 4.3105027 2.6396718
OS 4.2986248 2.6412356
OE
OB 4.1805146 2.6412356 H
OS 4.1686367 2.6396718
OS 4.1575683 2.6350872
OS 4.1480636 2.627794
OS 4.1407704 2.6182893
OS 4.1361858 2.6072209
OS 4.134622 2.595343
OS 4.1361858 2.5834651
OS 4.1407704 2.5723967
OS 4.1480636 2.562892
OS 4.1575683 2.5555988
OS 4.1686367 2.5510142
OS 4.1805146 2.5494504
OS 4.1923925 2.5510142
OS 4.2034609 2.5555988
OS 4.2129656 2.562892
OS 4.2202588 2.5723967
OS 4.2248434 2.5834651
OS 4.2264072 2.595343
OS 4.2248434 2.6072209
OS 4.2202588 2.6182893
OS 4.2129656 2.627794
OS 4.2034609 2.6350872
OS 4.1923925 2.6396718
OS 4.1805146 2.6412356
OE
OB 4.0624044 2.6412356 H
OS 4.0505265 2.6396718
OS 4.0394581 2.6350872
OS 4.0299534 2.627794
OS 4.0226602 2.6182893
OS 4.0180756 2.6072209
OS 4.0165118 2.595343
OS 4.0180756 2.5834651
OS 4.0226602 2.5723967
OS 4.0299534 2.562892
OS 4.0394581 2.5555988
OS 4.0505265 2.5510142
OS 4.0624044 2.5494504
OS 4.0742823 2.5510142
OS 4.0853507 2.5555988
OS 4.0948554 2.562892
OS 4.1021486 2.5723967
OS 4.1067332 2.5834651
OS 4.108297 2.595343
OS 4.1067332 2.6072209
OS 4.1021486 2.6182893
OS 4.0948554 2.627794
OS 4.0853507 2.6350872
OS 4.0742823 2.6396718
OS 4.0624044 2.6412356
OE
OB 6.2848425 2.5173765 H
OS 6.2785996 2.5161347
OS 6.2733071 2.5125984
OS 6.2697708 2.5073059
OS 6.268529 2.501063
OS 6.2697708 2.4948201
OS 6.2733071 2.4895276
OS 6.2785996 2.4859913
OS 6.2848425 2.4847495
OS 6.2910854 2.4859913
OS 6.2963779 2.4895276
OS 6.2999142 2.4948201
OS 6.301156 2.501063
OS 6.2999142 2.5073059
OS 6.2963779 2.5125984
OS 6.2910854 2.5161347
OS 6.2848425 2.5173765
OE
OB 1.0208425 2.4973765 H
OS 1.0145996 2.4961347
OS 1.0093071 2.4925984
OS 1.0057708 2.4873059
OS 1.004529 2.481063
OS 1.0057708 2.4748201
OS 1.0093071 2.4695276
OS 1.0145996 2.4659913
OS 1.0208425 2.4647495
OS 1.0270854 2.4659913
OS 1.0323779 2.4695276
OS 1.0359142 2.4748201
OS 1.037156 2.481063
OS 1.0359142 2.4873059
OS 1.0323779 2.4925984
OS 1.0270854 2.4961347
OS 1.0208425 2.4973765
OE
OB 2.6248425 2.4773765 H
OS 2.6185996 2.4761347
OS 2.6133071 2.4725984
OS 2.6097708 2.4673059
OS 2.608529 2.461063
OS 2.6097708 2.4548201
OS 2.6099331 2.4545773
OS 2.6063282 2.4509724
OS 2.6060854 2.4511347
OS 2.5998425 2.4523765
OS 2.5935996 2.4511347
OS 2.5883071 2.4475984
OS 2.5847708 2.4423059
OS 2.583529 2.436063
OS 2.5844621 2.4313719
OS 2.583986 2.4305231
OS 2.5813824 2.4279195
OS 2.5805336 2.4274434
OS 2.5758425 2.4283765
OS 2.5695996 2.4271347
OS 2.5643071 2.4235984
OS 2.5607708 2.4183059
OS 2.559529 2.412063
OS 2.5607708 2.4058201
OS 2.5643071 2.4005276
OS 2.5695996 2.3969913
OS 2.5758425 2.3957495
OS 2.5820854 2.3969913
OS 2.5873779 2.4005276
OS 2.5909142 2.4058201
OS 2.592156 2.412063
OS 2.5912229 2.4167541
OS 2.591699 2.4176029
OS 2.5943026 2.4202065
OS 2.5951514 2.4206826
OS 2.5998425 2.4197495
OS 2.6060854 2.4209913
OS 2.6113779 2.4245276
OS 2.6149142 2.4298201
OS 2.616156 2.436063
OS 2.6149142 2.4423059
OS 2.6147519 2.4425487
OS 2.6183568 2.4461536
OS 2.6185996 2.4459913
OS 2.6248425 2.4447495
OS 2.6310854 2.4459913
OS 2.6363779 2.4495276
OS 2.6399142 2.4548201
OS 2.641156 2.461063
OS 2.6399142 2.4673059
OS 2.6363779 2.4725984
OS 2.6310854 2.4761347
OS 2.6248425 2.4773765
OE
OB 2.2720325 2.4801865 H
OS 2.2657896 2.4789447
OS 2.2604971 2.4754084
OS 2.2569608 2.4701159
OS 2.255719 2.463873
OS 2.2569608 2.4576301
OS 2.2604971 2.4523376
OS 2.2657896 2.4488013
OS 2.2720325 2.4475595
OS 2.2782754 2.4488013
OS 2.2835679 2.4523376
OS 2.2871042 2.4576301
OS 2.288346 2.463873
OS 2.2871042 2.4701159
OS 2.2835679 2.4754084
OS 2.2782754 2.4789447
OS 2.2720325 2.4801865
OE
OB 2.5258425 2.4793765 H
OS 2.5195996 2.4781347
OS 2.5143071 2.4745984
OS 2.5107708 2.4693059
OS 2.509529 2.463063
OS 2.5107708 2.4568201
OS 2.5143071 2.4515276
OS 2.5195996 2.4479913
OS 2.5258425 2.4467495
OS 2.5320854 2.4479913
OS 2.5373779 2.4515276
OS 2.5409142 2.4568201
OS 2.542156 2.463063
OS 2.5409142 2.4693059
OS 2.5373779 2.4745984
OS 2.5320854 2.4781347
OS 2.5258425 2.4793765
OE
OB 5.5781524 2.5349364 H
OS 5.5662745 2.5333726
OS 5.5552061 2.528788
OS 5.5457014 2.5214948
OS 5.5384082 2.5119901
OS 5.5338236 2.5009217
OS 5.5322598 2.4890438
OS 5.5338236 2.4771659
OS 5.5384082 2.4660975
OS 5.5457014 2.4565928
OS 5.5552061 2.4492996
OS 5.5662745 2.444715
OS 5.5781524 2.4431512
OS 5.5900303 2.444715
OS 5.6010987 2.4492996
OS 5.6106034 2.4565928
OS 5.6178966 2.4660975
OS 5.6224812 2.4771659
OS 5.624045 2.4890438
OS 5.6224812 2.5009217
OS 5.6178966 2.5119901
OS 5.6106034 2.5214948
OS 5.6010987 2.528788
OS 5.5900303 2.5333726
OS 5.5781524 2.5349364
OE
OB 2.9488425 2.4723765 H
OS 2.9425996 2.4711347
OS 2.9373071 2.4675984
OS 2.9337708 2.4623059
OS 2.932529 2.456063
OS 2.9337708 2.4498201
OS 2.9373071 2.4445276
OS 2.9425996 2.4409913
OS 2.9488425 2.4397495
OS 2.9550854 2.4409913
OS 2.9603779 2.4445276
OS 2.9639142 2.4498201
OS 2.965156 2.456063
OS 2.9639142 2.4623059
OS 2.9603779 2.4675984
OS 2.9550854 2.4711347
OS 2.9488425 2.4723765
OE
OB 2.9905325 2.4577319 H
OS 2.9831854 2.4562705
OS 2.9769568 2.4521087
OS 2.972795 2.4458801
OS 2.9713336 2.438533
OS 2.972795 2.4311859
OS 2.9769568 2.4249573
OS 2.9831854 2.4207955
OS 2.9905325 2.4193341
OS 2.9978796 2.4207955
OS 3.0041082 2.4249573
OS 3.00827 2.4311859
OS 3.0097314 2.438533
OS 3.00827 2.4458801
OS 3.0041082 2.4521087
OS 2.9978796 2.4562705
OS 2.9905325 2.4577319
OE
OB 2.2031325 2.4577319 H
OS 2.1957854 2.4562705
OS 2.1895568 2.4521087
OS 2.185395 2.4458801
OS 2.1839336 2.438533
OS 2.185395 2.4311859
OS 2.1895568 2.4249573
OS 2.1957854 2.4207955
OS 2.2031325 2.4193341
OS 2.2104796 2.4207955
OS 2.2167082 2.4249573
OS 2.22087 2.4311859
OS 2.2223314 2.438533
OS 2.22087 2.4458801
OS 2.2167082 2.4521087
OS 2.2104796 2.4562705
OS 2.2031325 2.4577319
OE
OB 3.6179425 2.5536725 H
OS 3.6047974 2.5523778
OS 3.5921575 2.5485435
OS 3.5805085 2.542317
OS 3.570298 2.5339375
OS 3.5619185 2.523727
OS 3.555692 2.512078
OS 3.5518577 2.4994381
OS 3.550563 2.486293
OS 3.5518577 2.4731479
OS 3.555692 2.460508
OS 3.5619185 2.448859
OS 3.570298 2.4386485
OS 3.5805085 2.430269
OS 3.5921575 2.4240425
OS 3.6047974 2.4202082
OS 3.6179425 2.4189135
OS 3.6310876 2.4202082
OS 3.6437275 2.4240425
OS 3.6553765 2.430269
OS 3.665587 2.4386485
OS 3.6739665 2.448859
OS 3.680193 2.460508
OS 3.6840273 2.4731479
OS 3.685322 2.486293
OS 3.6840273 2.4994381
OS 3.680193 2.512078
OS 3.6739665 2.523727
OS 3.665587 2.5339375
OS 3.6553765 2.542317
OS 3.6437275 2.5485435
OS 3.6310876 2.5523778
OS 3.6179425 2.5536725
OE
OB 1.6519425 2.5536725 H
OS 1.6387974 2.5523778
OS 1.6261575 2.5485435
OS 1.6145085 2.542317
OS 1.604298 2.5339375
OS 1.5959185 2.523727
OS 1.589692 2.512078
OS 1.5858577 2.4994381
OS 1.584563 2.486293
OS 1.5858577 2.4731479
OS 1.589692 2.460508
OS 1.5959185 2.448859
OS 1.604298 2.4386485
OS 1.6145085 2.430269
OS 1.6261575 2.4240425
OS 1.6387974 2.4202082
OS 1.6519425 2.4189135
OS 1.6650876 2.4202082
OS 1.6777275 2.4240425
OS 1.6893765 2.430269
OS 1.699587 2.4386485
OS 1.7079665 2.448859
OS 1.714193 2.460508
OS 1.7180273 2.4731479
OS 1.719322 2.486293
OS 1.7180273 2.4994381
OS 1.714193 2.512078
OS 1.7079665 2.523727
OS 1.699587 2.5339375
OS 1.6893765 2.542317
OS 1.6777275 2.5485435
OS 1.6650876 2.5523778
OS 1.6519425 2.5536725
OE
OB 0.1998425 2.5453727 H
OS 0.1872963 2.544137
OS 0.1752322 2.5404774
OS 0.1641139 2.5345346
OS 0.1543687 2.5265368
OS 0.1463709 2.5167916
OS 0.1404281 2.5056733
OS 0.1367685 2.4936092
OS 0.1355328 2.481063
OS 0.1367685 2.4685168
OS 0.1404281 2.4564527
OS 0.1463709 2.4453344
OS 0.1543687 2.4355892
OS 0.1641139 2.4275914
OS 0.1752322 2.4216486
OS 0.1872963 2.417989
OS 0.1998425 2.4167533
OS 0.2123887 2.417989
OS 0.2244528 2.4216486
OS 0.2355711 2.4275914
OS 0.2453163 2.4355892
OS 0.2533141 2.4453344
OS 0.2592569 2.4564527
OS 0.2629165 2.4685168
OS 0.2641522 2.481063
OS 0.2629165 2.4936092
OS 0.2592569 2.5056733
OS 0.2533141 2.5167916
OS 0.2453163 2.5265368
OS 0.2355711 2.5345346
OS 0.2244528 2.5404774
OS 0.2123887 2.544137
OS 0.1998425 2.5453727
OE
OB 2.8948425 2.4473765 H
OS 2.8885996 2.4461347
OS 2.8833071 2.4425984
OS 2.8797708 2.4373059
OS 2.878529 2.431063
OS 2.8797708 2.4248201
OS 2.8833071 2.4195276
OS 2.8885996 2.4159913
OS 2.8948425 2.4147495
OS 2.9010854 2.4159913
OS 2.9063778 2.4195276
OS 2.9073026 2.4195276
OS 2.9093071 2.4165276
OS 2.9145996 2.4129913
OS 2.9208425 2.4117495
OS 2.9270854 2.4129913
OS 2.9323779 2.4165276
OS 2.9359142 2.4218201
OS 2.937156 2.428063
OS 2.9359142 2.4343059
OS 2.9323779 2.4395984
OS 2.9270854 2.4431347
OS 2.9208425 2.4443765
OS 2.9145996 2.4431347
OS 2.9093072 2.4395984
OS 2.9083824 2.4395984
OS 2.9063779 2.4425984
OS 2.9010854 2.4461347
OS 2.8948425 2.4473765
OE
OB 4.0398425 2.4223765 H
OS 4.0335996 2.4211347
OS 4.0283071 2.4175984
OS 4.0247708 2.4123059
OS 4.023529 2.406063
OS 4.0247708 2.3998201
OS 4.0283071 2.3945276
OS 4.0335996 2.3909913
OS 4.0398425 2.3897495
OS 4.0460854 2.3909913
OS 4.0513779 2.3945276
OS 4.0549142 2.3998201
OS 4.056156 2.406063
OS 4.0549142 2.4123059
OS 4.0513779 2.4175984
OS 4.0460854 2.4211347
OS 4.0398425 2.4223765
OE
OB 3.4988425 2.3573765 H
OS 3.4925996 2.3561347
OS 3.4873071 2.3525984
OS 3.4837708 2.3473059
OS 3.482529 2.341063
OS 3.4837708 2.3348201
OS 3.4873071 2.3295276
OS 3.4925996 2.3259913
OS 3.4988425 2.3247495
OS 3.5050854 2.3259913
OS 3.5103779 2.3295276
OS 3.5139142 2.3348201
OS 3.515156 2.341063
OS 3.5139142 2.3473059
OS 3.5103779 2.3525984
OS 3.5050854 2.3561347
OS 3.4988425 2.3573765
OE
OB 2.7268425 2.3093765 H
OS 2.7205996 2.3081347
OS 2.7153071 2.3045984
OS 2.7131725 2.3014038
OS 2.7090854 2.3041347
OS 2.7028425 2.3053765
OS 2.6965996 2.3041347
OS 2.6913071 2.3005984
OS 2.6877708 2.2953059
OS 2.6868962 2.2909101
OS 2.6821561 2.2910632
OS 2.6809142 2.2973059
OS 2.6773779 2.3025984
OS 2.6720854 2.3061347
OS 2.6658425 2.3073765
OS 2.6595996 2.3061347
OS 2.6543071 2.3025984
OS 2.6507708 2.2973059
OS 2.649529 2.2910631
OS 2.6483447 2.2898788
OS 2.6458425 2.2903765
OS 2.6395996 2.2891347
OS 2.6343071 2.2855984
OS 2.6307708 2.2803059
OS 2.629529 2.274063
OS 2.6307708 2.2678201
OS 2.6343071 2.2625276
OS 2.6395996 2.2589913
OS 2.6458425 2.2577495
OS 2.6520854 2.2589913
OS 2.6573779 2.2625276
OS 2.6609142 2.2678201
OS 2.662156 2.2740629
OS 2.6633403 2.2752472
OS 2.6658425 2.2747495
OS 2.6720854 2.2759913
OS 2.6773779 2.2795276
OS 2.6809142 2.2848201
OS 2.6817888 2.2892159
OS 2.6865289 2.2890628
OS 2.6877708 2.2828201
OS 2.6913071 2.2775276
OS 2.6965996 2.2739913
OS 2.7028425 2.2727495
OS 2.7090854 2.2739913
OS 2.7143779 2.2775276
OS 2.7165125 2.2807222
OS 2.7205996 2.2779913
OS 2.7268425 2.2767495
OS 2.7330854 2.2779913
OS 2.7383779 2.2815276
OS 2.7419142 2.2868201
OS 2.743156 2.293063
OS 2.7419142 2.2993059
OS 2.7383779 2.3045984
OS 2.7330854 2.3081347
OS 2.7268425 2.3093765
OE
OB 2.4758425 2.3073765 H
OS 2.4695996 2.3061347
OS 2.4643071 2.3025984
OS 2.4623321 2.2996425
OS 2.4575823 2.2973722
OS 2.4556938 2.2974115
OS 2.4508425 2.2983765
OS 2.4445996 2.2971347
OS 2.4393071 2.2935984
OS 2.4357708 2.2883059
OS 2.434529 2.282063
OS 2.4357708 2.2758201
OS 2.4393071 2.2705276
OS 2.4445996 2.2669913
OS 2.4508425 2.2657495
OS 2.4570854 2.2669913
OS 2.4623779 2.2705276
OS 2.4659142 2.27582
OS 2.4709912 2.2757145
OS 2.4758425 2.2747495
OS 2.4820854 2.2759913
OS 2.4873779 2.2795276
OS 2.4909142 2.2848201
OS 2.492156 2.291063
OS 2.4909142 2.2973059
OS 2.4873779 2.3025984
OS 2.4820854 2.3061347
OS 2.4758425 2.3073765
OE
OB 2.8038425 2.3233765 H
OS 2.7975996 2.3221347
OS 2.7923071 2.3185984
OS 2.7887708 2.3133059
OS 2.787529 2.307063
OS 2.7887708 2.3008201
OS 2.7923071 2.2955276
OS 2.7975996 2.2919913
OS 2.8038425 2.2907495
OS 2.8100854 2.2919913
OS 2.8153779 2.2955276
OS 2.8189142 2.3008201
OS 2.820156 2.307063
OS 2.8189142 2.3133059
OS 2.8153779 2.3185984
OS 2.8100854 2.3221347
OS 2.8038425 2.3233765
OE
OB 2.9858425 2.3033765 H
OS 2.9795996 2.3021347
OS 2.9743071 2.2985984
OS 2.9707708 2.2933059
OS 2.969529 2.287063
OS 2.9707708 2.2808201
OS 2.9743071 2.2755276
OS 2.9795996 2.2719913
OS 2.9858425 2.2707495
OS 2.9920854 2.2719913
OS 2.9973779 2.2755276
OS 3.0009142 2.2808201
OS 3.002156 2.287063
OS 3.0009142 2.2933059
OS 2.9973779 2.2985984
OS 2.9920854 2.3021347
OS 2.9858425 2.3033765
OE
OB 2.9428425 2.3023765 H
OS 2.9365996 2.3011347
OS 2.9313071 2.2975984
OS 2.9277708 2.2923059
OS 2.926529 2.286063
OS 2.9277708 2.2798201
OS 2.9313071 2.2745276
OS 2.9365996 2.2709913
OS 2.9428425 2.2697495
OS 2.9490854 2.2709913
OS 2.9543779 2.2745276
OS 2.9579142 2.2798201
OS 2.959156 2.286063
OS 2.9579142 2.2923059
OS 2.9543779 2.2975984
OS 2.9490854 2.3011347
OS 2.9428425 2.3023765
OE
OB 5.3277559 2.3463244 H
OS 5.3177023 2.3450008
OS 5.3083338 2.3411203
OS 5.300289 2.3349472
OS 5.2941159 2.3269023
OS 5.2902354 2.3175339
OS 5.2889118 2.3074803
OS 5.2902354 2.2974267
OS 5.2941159 2.2880583
OS 5.300289 2.2800134
OS 5.3083338 2.2738403
OS 5.3177023 2.2699598
OS 5.3277559 2.2686362
OS 5.3378095 2.2699598
OS 5.347178 2.2738403
OS 5.3552228 2.2800134
OS 5.3613959 2.2880583
OS 5.3652764 2.2974267
OS 5.3666 2.3074803
OS 5.3652764 2.3175339
OS 5.3613959 2.3269023
OS 5.3552228 2.3349472
OS 5.347178 2.3411203
OS 5.3378095 2.3450008
OS 5.3277559 2.3463244
OE
OB 4.9277559 2.3463244 H
OS 4.9177023 2.3450008
OS 4.9083338 2.3411203
OS 4.900289 2.3349472
OS 4.8941159 2.3269023
OS 4.8902354 2.3175339
OS 4.8889118 2.3074803
OS 4.8902354 2.2974267
OS 4.8941159 2.2880583
OS 4.900289 2.2800134
OS 4.9083338 2.2738403
OS 4.9177023 2.2699598
OS 4.9277559 2.2686362
OS 4.9378095 2.2699598
OS 4.947178 2.2738403
OS 4.9552228 2.2800134
OS 4.9613959 2.2880583
OS 4.9652764 2.2974267
OS 4.9666 2.3074803
OS 4.9652764 2.3175339
OS 4.9613959 2.3269023
OS 4.9552228 2.3349472
OS 4.947178 2.3411203
OS 4.9378095 2.3450008
OS 4.9277559 2.3463244
OE
OB 4.7277559 2.3463244 H
OS 4.7177023 2.3450008
OS 4.7083338 2.3411203
OS 4.700289 2.3349472
OS 4.6941159 2.3269023
OS 4.6902354 2.3175339
OS 4.6889118 2.3074803
OS 4.6902354 2.2974267
OS 4.6941159 2.2880583
OS 4.700289 2.2800134
OS 4.7083338 2.2738403
OS 4.7177023 2.2699598
OS 4.7277559 2.2686362
OS 4.7378095 2.2699598
OS 4.747178 2.2738403
OS 4.7552228 2.2800134
OS 4.7613959 2.2880583
OS 4.7652764 2.2974267
OS 4.7666 2.3074803
OS 4.7652764 2.3175339
OS 4.7613959 2.3269023
OS 4.7552228 2.3349472
OS 4.747178 2.3411203
OS 4.7378095 2.3450008
OS 4.7277559 2.3463244
OE
OB 4.3277559 2.3463244 H
OS 4.3177023 2.3450008
OS 4.3083338 2.3411203
OS 4.300289 2.3349472
OS 4.2941159 2.3269023
OS 4.2902354 2.3175339
OS 4.2889118 2.3074803
OS 4.2902354 2.2974267
OS 4.2941159 2.2880583
OS 4.300289 2.2800134
OS 4.3083338 2.2738403
OS 4.3177023 2.2699598
OS 4.3277559 2.2686362
OS 4.3378095 2.2699598
OS 4.347178 2.2738403
OS 4.3552228 2.2800134
OS 4.3613959 2.2880583
OS 4.3652764 2.2974267
OS 4.3666 2.3074803
OS 4.3652764 2.3175339
OS 4.3613959 2.3269023
OS 4.3552228 2.3349472
OS 4.347178 2.3411203
OS 4.3378095 2.3450008
OS 4.3277559 2.3463244
OE
OB 2.4098425 2.3303765 H
OS 2.4035996 2.3291347
OS 2.3983071 2.3255984
OS 2.3947708 2.3203059
OS 2.393529 2.314063
OS 2.3947708 2.3078201
OS 2.3983071 2.3025276
OS 2.3997406 2.3015697
OS 2.3997406 2.2955563
OS 2.3983071 2.2945984
OS 2.3947708 2.2893059
OS 2.393529 2.283063
OS 2.3947708 2.2768201
OS 2.3983071 2.2715276
OS 2.4035996 2.2679913
OS 2.4098425 2.2667495
OS 2.4160854 2.2679913
OS 2.4213779 2.2715276
OS 2.4249142 2.2768201
OS 2.426156 2.283063
OS 2.4249142 2.2893059
OS 2.4213779 2.2945984
OS 2.4199444 2.2955563
OS 2.4199444 2.3015697
OS 2.4213779 2.3025276
OS 2.4249142 2.3078201
OS 2.426156 2.314063
OS 2.4249142 2.3203059
OS 2.4213779 2.3255984
OS 2.4160854 2.3291347
OS 2.4098425 2.3303765
OE
OB 2.5798425 2.2973765 H
OS 2.5735996 2.2961347
OS 2.5683071 2.2925984
OS 2.5647708 2.2873059
OS 2.563529 2.281063
OS 2.5647708 2.2748201
OS 2.5683071 2.2695276
OS 2.5735996 2.2659913
OS 2.5798425 2.2647495
OS 2.5860854 2.2659913
OS 2.5913779 2.2695276
OS 2.5949142 2.2748201
OS 2.596156 2.281063
OS 2.5949142 2.2873059
OS 2.5913779 2.2925984
OS 2.5860854 2.2961347
OS 2.5798425 2.2973765
OE
OB 3.3428425 2.2793765 H
OS 3.3365996 2.2781347
OS 3.3313071 2.2745984
OS 3.3277708 2.2693059
OS 3.326529 2.263063
OS 3.3277708 2.2568201
OS 3.3313071 2.2515276
OS 3.3365996 2.2479913
OS 3.3428425 2.2467495
OS 3.3490854 2.2479913
OS 3.3543779 2.2515276
OS 3.3579142 2.2568201
OS 3.359156 2.263063
OS 3.3579142 2.2693059
OS 3.3543779 2.2745984
OS 3.3490854 2.2781347
OS 3.3428425 2.2793765
OE
OB 2.8418425 2.2793765 H
OS 2.8355996 2.2781347
OS 2.8303071 2.2745984
OS 2.8267708 2.2693059
OS 2.825529 2.263063
OS 2.8267708 2.2568201
OS 2.8303071 2.2515276
OS 2.8355996 2.2479913
OS 2.8418425 2.2467495
OS 2.8480854 2.2479913
OS 2.8533779 2.2515276
OS 2.8569142 2.2568201
OS 2.858156 2.263063
OS 2.8569142 2.2693059
OS 2.8533779 2.2745984
OS 2.8480854 2.2781347
OS 2.8418425 2.2793765
OE
OB 0.9968357 2.2723495 H
OS 0.9905928 2.2711077
OS 0.9853003 2.2675714
OS 0.981764 2.2622789
OS 0.9805222 2.256036
OS 0.981764 2.2497931
OS 0.9853003 2.2445006
OS 0.9905928 2.2409643
OS 0.9968357 2.2397225
OS 1.0030786 2.2409643
OS 1.0083711 2.2445006
OS 1.0119074 2.2497931
OS 1.0131492 2.256036
OS 1.0119074 2.2622789
OS 1.0083711 2.2675714
OS 1.0030786 2.2711077
OS 0.9968357 2.2723495
OE
OB 5.6348425 2.2523765 H
OS 5.6285996 2.2511347
OS 5.6233071 2.2475984
OS 5.6197708 2.2423059
OS 5.618529 2.236063
OS 5.6197708 2.2298201
OS 5.6233071 2.2245276
OS 5.6285996 2.2209913
OS 5.6348425 2.2197495
OS 5.6410854 2.2209913
OS 5.6463779 2.2245276
OS 5.6499142 2.2298201
OS 5.651156 2.236063
OS 5.6499142 2.2423059
OS 5.6463779 2.2475984
OS 5.6410854 2.2511347
OS 5.6348425 2.2523765
OE
OB 2.4998425 2.2523765 H
OS 2.4935996 2.2511347
OS 2.4883071 2.2475984
OS 2.4847708 2.2423059
OS 2.483529 2.236063
OS 2.4847708 2.2298201
OS 2.4883071 2.2245276
OS 2.4935996 2.2209913
OS 2.4998425 2.2197495
OS 2.5060854 2.2209913
OS 2.5113779 2.2245276
OS 2.5149142 2.2298201
OS 2.516156 2.236063
OS 2.5149142 2.2423059
OS 2.5113779 2.2475984
OS 2.5060854 2.2511347
OS 2.4998425 2.2523765
OE
OB 2.3308425 2.2313765 H
OS 2.3245996 2.2301347
OS 2.3193071 2.2265984
OS 2.3157708 2.2213059
OS 2.314529 2.215063
OS 2.3157708 2.2088201
OS 2.3193071 2.2035276
OS 2.3245996 2.1999913
OS 2.3308425 2.1987495
OS 2.3370854 2.1999913
OS 2.3423779 2.2035276
OS 2.3459142 2.2088201
OS 2.347156 2.215063
OS 2.3459142 2.2213059
OS 2.3423779 2.2265984
OS 2.3370854 2.2301347
OS 2.3308425 2.2313765
OE
OB 5.5778425 2.2303765 H
OS 5.5715996 2.2291347
OS 5.5663071 2.2255984
OS 5.5627708 2.2203059
OS 5.561529 2.214063
OS 5.5627708 2.2078201
OS 5.5663071 2.2025276
OS 5.5715996 2.1989913
OS 5.5778425 2.1977495
OS 5.5840854 2.1989913
OS 5.5893779 2.2025276
OS 5.5929142 2.2078201
OS 5.594156 2.214063
OS 5.5929142 2.2203059
OS 5.5893779 2.2255984
OS 5.5840854 2.2291347
OS 5.5778425 2.2303765
OE
OB 6.4248425 2.1973765 H
OS 6.4185996 2.1961347
OS 6.4133071 2.1925984
OS 6.4097708 2.1873059
OS 6.408529 2.181063
OS 6.4097708 2.1748201
OS 6.4133071 2.1695276
OS 6.4185996 2.1659913
OS 6.4248425 2.1647495
OS 6.4310854 2.1659913
OS 6.4363779 2.1695276
OS 6.4399142 2.1748201
OS 6.441156 2.181063
OS 6.4399142 2.1873059
OS 6.4363779 2.1925984
OS 6.4310854 2.1961347
OS 6.4248425 2.1973765
OE
OB 1.7548425 2.1423765 H
OS 1.7485996 2.1411347
OS 1.7433071 2.1375984
OS 1.7397708 2.1323059
OS 1.738529 2.126063
OS 1.7397708 2.1198201
OS 1.7433071 2.1145276
OS 1.7485996 2.1109913
OS 1.7548425 2.1097495
OS 1.7610854 2.1109913
OS 1.7663779 2.1145276
OS 1.7699142 2.1198201
OS 1.771156 2.126063
OS 1.7699142 2.1323059
OS 1.7663779 2.1375984
OS 1.7610854 2.1411347
OS 1.7548425 2.1423765
OE
OB 1.6198425 2.1373765 H
OS 1.6135996 2.1361347
OS 1.6083071 2.1325984
OS 1.6047708 2.1273059
OS 1.603529 2.121063
OS 1.6047708 2.1148201
OS 1.6083071 2.1095276
OS 1.6135996 2.1059913
OS 1.6198425 2.1047495
OS 1.6260854 2.1059913
OS 1.6313779 2.1095276
OS 1.6349142 2.1148201
OS 1.636156 2.121063
OS 1.6349142 2.1273059
OS 1.6313779 2.1325984
OS 1.6260854 2.1361347
OS 1.6198425 2.1373765
OE
OB 1.6968325 2.1164319 H
OS 1.6894854 2.1149705
OS 1.6832568 2.1108087
OS 1.679095 2.1045801
OS 1.6776336 2.097233
OS 1.679095 2.0898859
OS 1.6832568 2.0836573
OS 1.6894854 2.0794955
OS 1.6968325 2.0780341
OS 1.7041796 2.0794955
OS 1.7104082 2.0836573
OS 1.71457 2.0898859
OS 1.7160314 2.097233
OS 1.71457 2.1045801
OS 1.7104082 2.1108087
OS 1.7041796 2.1149705
OS 1.6968325 2.1164319
OE
OB 1.8848425 2.0873765 H
OS 1.8785996 2.0861347
OS 1.8733071 2.0825984
OS 1.8697708 2.0773059
OS 1.868529 2.071063
OS 1.8697708 2.0648201
OS 1.8733071 2.0595276
OS 1.8785996 2.0559913
OS 1.8848425 2.0547495
OS 1.8910854 2.0559913
OS 1.8963779 2.0595276
OS 1.8999142 2.0648201
OS 1.901156 2.071063
OS 1.8999142 2.0773059
OS 1.8963779 2.0825984
OS 1.8910854 2.0861347
OS 1.8848425 2.0873765
OE
OB 1.5682025 2.0840165 H
OS 1.5619596 2.0827747
OS 1.5566671 2.0792384
OS 1.5531308 2.0739459
OS 1.551889 2.067703
OS 1.5531308 2.0614601
OS 1.5566671 2.0561676
OS 1.5619596 2.0526313
OS 1.5682025 2.0513895
OS 1.5744454 2.0526313
OS 1.5797379 2.0561676
OS 1.5832742 2.0614601
OS 1.584516 2.067703
OS 1.5832742 2.0739459
OS 1.5797379 2.0792384
OS 1.5744454 2.0827747
OS 1.5682025 2.0840165
OE
OB 3.5717425 2.1163919 H
OS 3.5643954 2.1149305
OS 3.5581668 2.1107687
OS 3.554005 2.1045401
OS 3.5525436 2.097193
OS 3.554005 2.0898459
OS 3.5581668 2.0836173
OS 3.5643954 2.0794555
OS 3.5680713 2.0787243
OS 3.5680713 2.0736264
OS 3.5655996 2.0731347
OS 3.5603071 2.0695984
OS 3.5567708 2.0643059
OS 3.555529 2.058063
OS 3.5567708 2.0518201
OS 3.5584204 2.0493513
OS 3.5599241 2.045563
OS 3.5584204 2.0417747
OS 3.5567708 2.0393059
OS 3.555529 2.033063
OS 3.5567708 2.0268201
OS 3.5603071 2.0215276
OS 3.5655996 2.0179913
OS 3.5718425 2.0167495
OS 3.5780854 2.0179913
OS 3.5833779 2.0215276
OS 3.5869142 2.0268201
OS 3.588156 2.033063
OS 3.5869142 2.0393059
OS 3.5852646 2.0417747
OS 3.5837609 2.045563
OS 3.5852646 2.0493513
OS 3.5869142 2.0518201
OS 3.588156 2.058063
OS 3.5869142 2.0643059
OS 3.5833779 2.0695984
OS 3.5780854 2.0731347
OS 3.5755137 2.0736462
OS 3.5755137 2.0787442
OS 3.5790896 2.0794555
OS 3.5853182 2.0836173
OS 3.58948 2.0898459
OS 3.5909414 2.097193
OS 3.58948 2.1045401
OS 3.5853182 2.1107687
OS 3.5790896 2.1149305
OS 3.5717425 2.1163919
OE
OB 2.4098425 1.9833765 H
OS 2.4035996 1.9821347
OS 2.3983071 1.9785984
OS 2.3947708 1.9733059
OS 2.393529 1.967063
OS 2.3947708 1.9608201
OS 2.3961401 1.9587707
OS 2.3925353 1.9551659
OS 2.3910854 1.9561347
OS 2.3848425 1.9573765
OS 2.3785996 1.9561347
OS 2.3733071 1.9525984
OS 2.3697708 1.9473059
OS 2.368529 1.941063
OS 2.3697708 1.9348201
OS 2.3733071 1.9295276
OS 2.3785996 1.9259913
OS 2.3848425 1.9247495
OS 2.3910854 1.9259913
OS 2.3963779 1.9295276
OS 2.3999142 1.9348201
OS 2.401156 1.941063
OS 2.3999142 1.9473059
OS 2.3985449 1.9493553
OS 2.4021497 1.9529601
OS 2.4035996 1.9519913
OS 2.4098425 1.9507495
OS 2.4160854 1.9519913
OS 2.4213779 1.9555276
OS 2.4249142 1.9608201
OS 2.426156 1.967063
OS 2.4249142 1.9733059
OS 2.4213779 1.9785984
OS 2.4160854 1.9821347
OS 2.4098425 1.9833765
OE
OB 3.2988425 1.9873765 H
OS 3.2925996 1.9861347
OS 3.2873071 1.9825984
OS 3.2837708 1.9773059
OS 3.282529 1.971063
OS 3.2837708 1.9648201
OS 3.2873071 1.9595276
OS 3.2925996 1.9559913
OS 3.2988425 1.9547495
OS 3.3050854 1.9559913
OS 3.3103779 1.9595276
OS 3.3139142 1.9648201
OS 3.315156 1.971063
OS 3.3139142 1.9773059
OS 3.3103779 1.9825984
OS 3.3050854 1.9861347
OS 3.2988425 1.9873765
OE
OB 1.0098425 1.9723765 H
OS 1.0035996 1.9711347
OS 0.9983071 1.9675984
OS 0.9947708 1.9623059
OS 0.993529 1.956063
OS 0.9947708 1.9498201
OS 0.9983071 1.9445276
OS 1.0035996 1.9409913
OS 1.0098425 1.9397495
OS 1.0160854 1.9409913
OS 1.0213779 1.9445276
OS 1.0249142 1.9498201
OS 1.026156 1.956063
OS 1.0249142 1.9623059
OS 1.0213779 1.9675984
OS 1.0160854 1.9711347
OS 1.0098425 1.9723765
OE
OB 2.2998425 1.9323765 H
OS 2.2935996 1.9311347
OS 2.2883071 1.9275984
OS 2.2847708 1.9223059
OS 2.283529 1.916063
OS 2.2847708 1.9098201
OS 2.2883071 1.9045276
OS 2.2935996 1.9009913
OS 2.2998425 1.8997495
OS 2.3060854 1.9009913
OS 2.3113779 1.9045276
OS 2.3149142 1.9098201
OS 2.316156 1.916063
OS 2.3149142 1.9223059
OS 2.3113779 1.9275984
OS 2.3060854 1.9311347
OS 2.2998425 1.9323765
OE
OB 0.1998425 2.0203727 H
OS 0.1872963 2.019137
OS 0.1752322 2.0154774
OS 0.1641139 2.0095346
OS 0.1543687 2.0015368
OS 0.1463709 1.9917916
OS 0.1404281 1.9806733
OS 0.1367685 1.9686092
OS 0.1355328 1.956063
OS 0.1367685 1.9435168
OS 0.1404281 1.9314527
OS 0.1463709 1.9203344
OS 0.1543687 1.9105892
OS 0.1641139 1.9025914
OS 0.1752322 1.8966486
OS 0.1872963 1.892989
OS 0.1998425 1.8917533
OS 0.2123887 1.892989
OS 0.2244528 1.8966486
OS 0.2355711 1.9025914
OS 0.2453163 1.9105892
OS 0.2533141 1.9203344
OS 0.2592569 1.9314527
OS 0.2629165 1.9435168
OS 0.2641522 1.956063
OS 0.2629165 1.9686092
OS 0.2592569 1.9806733
OS 0.2533141 1.9917916
OS 0.2453163 2.0015368
OS 0.2355711 2.0095346
OS 0.2244528 2.0154774
OS 0.2123887 2.019137
OS 0.1998425 2.0203727
OE
OB 3.5548425 1.9073765 H
OS 3.5485996 1.9061347
OS 3.5433071 1.9025984
OS 3.5397708 1.8973059
OS 3.538529 1.891063
OS 3.5397708 1.8848201
OS 3.5433071 1.8795276
OS 3.5485996 1.8759913
OS 3.5548425 1.8747495
OS 3.5610854 1.8759913
OS 3.5663779 1.8795276
OS 3.5699142 1.8848201
OS 3.571156 1.891063
OS 3.5699142 1.8973059
OS 3.5663779 1.9025984
OS 3.5610854 1.9061347
OS 3.5548425 1.9073765
OE
OB 3.3928425 1.8873765 H
OS 3.3865996 1.8861347
OS 3.3813071 1.8825984
OS 3.3777708 1.8773059
OS 3.376529 1.871063
OS 3.3777708 1.8648201
OS 3.3813071 1.8595276
OS 3.3865996 1.8559913
OS 3.3928425 1.8547495
OS 3.3990854 1.8559913
OS 3.4043779 1.8595276
OS 3.4079142 1.8648201
OS 3.409156 1.871063
OS 3.4079142 1.8773059
OS 3.4043779 1.8825984
OS 3.3990854 1.8861347
OS 3.3928425 1.8873765
OE
OB 3.4392507 1.8872515 H
OS 3.4330078 1.8860097
OS 3.4277153 1.8824734
OS 3.424179 1.8771809
OS 3.4229372 1.870938
OS 3.424179 1.8646951
OS 3.4277153 1.8594026
OS 3.4330078 1.8558663
OS 3.4392507 1.8546245
OS 3.4454936 1.8558663
OS 3.4507861 1.8594026
OS 3.4543224 1.8646951
OS 3.4555642 1.870938
OS 3.4543224 1.8771809
OS 3.4507861 1.8824734
OS 3.4454936 1.8860097
OS 3.4392507 1.8872515
OE
OB 3.8048425 1.8563765 H
OS 3.7985996 1.8551347
OS 3.7933071 1.8515984
OS 3.7897708 1.8463059
OS 3.788529 1.840063
OS 3.7897708 1.8338201
OS 3.7933071 1.8285276
OS 3.7985996 1.8249913
OS 3.8048425 1.8237495
OS 3.8110854 1.8249913
OS 3.8163779 1.8285276
OS 3.8199142 1.8338201
OS 3.821156 1.840063
OS 3.8199142 1.8463059
OS 3.8163779 1.8515984
OS 3.8110854 1.8551347
OS 3.8048425 1.8563765
OE
OB 3.3291721 1.8423765 H
OS 3.3229292 1.8411347
OS 3.3176367 1.8375984
OS 3.3141004 1.8323059
OS 3.3128586 1.826063
OS 3.3141004 1.8198201
OS 3.3176367 1.8145276
OS 3.3229292 1.8109913
OS 3.3291721 1.8097495
OS 3.335415 1.8109913
OS 3.3407075 1.8145276
OS 3.3442438 1.8198201
OS 3.3454856 1.826063
OS 3.3442438 1.8323059
OS 3.3407075 1.8375984
OS 3.335415 1.8411347
OS 3.3291721 1.8423765
OE
OB 1.3937008 1.8332426 H
OS 1.3874579 1.8320008
OS 1.3821654 1.8284645
OS 1.3786291 1.823172
OS 1.3773873 1.8169291
OS 1.3786291 1.8106862
OS 1.3821654 1.8053937
OS 1.3874579 1.8018574
OS 1.3937008 1.8006156
OS 1.3999437 1.8018574
OS 1.4052362 1.8053937
OS 1.4087725 1.8106862
OS 1.4100143 1.8169291
OS 1.4087725 1.823172
OS 1.4052362 1.8284645
OS 1.3999437 1.8320008
OS 1.3937008 1.8332426
OE
OB 3.9448425 1.8323765 H
OS 3.9385996 1.8311347
OS 3.9333071 1.8275984
OS 3.9297708 1.8223059
OS 3.928529 1.816063
OS 3.9297708 1.8098201
OS 3.9333071 1.8045276
OS 3.9385996 1.8009913
OS 3.9448425 1.7997495
OS 3.9510854 1.8009913
OS 3.9563779 1.8045276
OS 3.9599142 1.8098201
OS 3.961156 1.816063
OS 3.9599142 1.8223059
OS 3.9563779 1.8275984
OS 3.9510854 1.8311347
OS 3.9448425 1.8323765
OE
OB 3.0568817 1.8281165 H
OS 3.0506388 1.8268747
OS 3.0453463 1.8233384
OS 3.04181 1.8180459
OS 3.0405682 1.811803
OS 3.04181 1.8055601
OS 3.0453463 1.8002676
OS 3.0506388 1.7967313
OS 3.0568817 1.7954895
OS 3.0631246 1.7967313
OS 3.0684171 1.8002676
OS 3.0719534 1.8055601
OS 3.0731952 1.811803
OS 3.0719534 1.8180459
OS 3.0684171 1.8233384
OS 3.0631246 1.8268747
OS 3.0568817 1.8281165
OE
OB 1.8799377 1.8281165 H
OS 1.8736948 1.8268747
OS 1.8684023 1.8233384
OS 1.864866 1.8180459
OS 1.8636242 1.811803
OS 1.864866 1.8055601
OS 1.8684023 1.8002676
OS 1.8736948 1.7967313
OS 1.8799377 1.7954895
OS 1.8861806 1.7967313
OS 1.8914731 1.8002676
OS 1.8950094 1.8055601
OS 1.8962512 1.811803
OS 1.8950094 1.8180459
OS 1.8914731 1.8233384
OS 1.8861806 1.8268747
OS 1.8799377 1.8281165
OE
OB 4.0648425 1.8123765 H
OS 4.0585996 1.8111347
OS 4.0533071 1.8075984
OS 4.0497708 1.8023059
OS 4.048529 1.796063
OS 4.0497708 1.7898201
OS 4.0533071 1.7845276
OS 4.0585996 1.7809913
OS 4.0648425 1.7797495
OS 4.0710854 1.7809913
OS 4.0763779 1.7845276
OS 4.0799142 1.7898201
OS 4.081156 1.796063
OS 4.0799142 1.8023059
OS 4.0763779 1.8075984
OS 4.0710854 1.8111347
OS 4.0648425 1.8123765
OE
OB 2.5798425 1.8063765 H
OS 2.5735996 1.8051347
OS 2.5683071 1.8015984
OS 2.5647708 1.7963059
OS 2.563529 1.790063
OS 2.5647708 1.7838201
OS 2.5683071 1.7785276
OS 2.5735996 1.7749913
OS 2.5798425 1.7737495
OS 2.5860854 1.7749913
OS 2.5913779 1.7785276
OS 2.5949142 1.7838201
OS 2.596156 1.790063
OS 2.5949142 1.7963059
OS 2.5913779 1.8015984
OS 2.5860854 1.8051347
OS 2.5798425 1.8063765
OE
OB 2.6268425 1.7863765 H
OS 2.6205996 1.7851347
OS 2.6153071 1.7815984
OS 2.6117708 1.7763059
OS 2.610529 1.770063
OS 2.6117708 1.7638201
OS 2.6153071 1.7585276
OS 2.6205996 1.7549913
OS 2.6268425 1.7537495
OS 2.6330854 1.7549913
OS 2.6383779 1.7585276
OS 2.6419142 1.7638201
OS 2.643156 1.770063
OS 2.6419142 1.7763059
OS 2.6383779 1.7815984
OS 2.6330854 1.7851347
OS 2.6268425 1.7863765
OE
OB 3.7198425 1.7823765 H
OS 3.7135996 1.7811347
OS 3.7083071 1.7775984
OS 3.7047708 1.7723059
OS 3.703529 1.766063
OS 3.7047708 1.7598201
OS 3.7083071 1.7545276
OS 3.7135996 1.7509913
OS 3.7198425 1.7497495
OS 3.7260854 1.7509913
OS 3.7313779 1.7545276
OS 3.7349142 1.7598201
OS 3.736156 1.766063
OS 3.7349142 1.7723059
OS 3.7313779 1.7775984
OS 3.7260854 1.7811347
OS 3.7198425 1.7823765
OE
OB 2.5498425 1.7713765 H
OS 2.5435996 1.7701347
OS 2.5383071 1.7665984
OS 2.5347708 1.7613059
OS 2.533529 1.755063
OS 2.5347708 1.7488201
OS 2.5383071 1.7435276
OS 2.5435996 1.7399913
OS 2.5498425 1.7387495
OS 2.5560854 1.7399913
OS 2.5613779 1.7435276
OS 2.5649142 1.7488201
OS 2.566156 1.755063
OS 2.5649142 1.7613059
OS 2.5613779 1.7665984
OS 2.5560854 1.7701347
OS 2.5498425 1.7713765
OE
OB 4.1348425 1.7673765 H
OS 4.1285996 1.7661347
OS 4.1233071 1.7625984
OS 4.1197708 1.7573059
OS 4.118529 1.751063
OS 4.1197708 1.7448201
OS 4.1233071 1.7395276
OS 4.1285996 1.7359913
OS 4.1348425 1.7347495
OS 4.1410854 1.7359913
OS 4.1463779 1.7395276
OS 4.1499142 1.7448201
OS 4.151156 1.751063
OS 4.1499142 1.7573059
OS 4.1463779 1.7625984
OS 4.1410854 1.7661347
OS 4.1348425 1.7673765
OE
OB 2.6048425 1.7503765 H
OS 2.5985996 1.7491347
OS 2.5933071 1.7455984
OS 2.5897708 1.7403059
OS 2.588529 1.734063
OS 2.5897708 1.7278201
OS 2.5933071 1.7225276
OS 2.5985996 1.7189913
OS 2.6048425 1.7177495
OS 2.6110854 1.7189913
OS 2.6163779 1.7225276
OS 2.6199142 1.7278201
OS 2.621156 1.734063
OS 2.6199142 1.7403059
OS 2.6163779 1.7455984
OS 2.6110854 1.7491347
OS 2.6048425 1.7503765
OE
OB 0.988189 1.7338332 H
OS 0.9819461 1.7325914
OS 0.9766536 1.7290551
OS 0.9731173 1.7237626
OS 0.9718755 1.7175197
OS 0.9731173 1.7112768
OS 0.9766536 1.7059843
OS 0.9819461 1.702448
OS 0.988189 1.7012062
OS 0.9944319 1.702448
OS 0.9997244 1.7059843
OS 1.0032607 1.7112768
OS 1.0045025 1.7175197
OS 1.0032607 1.7237626
OS 0.9997244 1.7290551
OS 0.9944319 1.7325914
OS 0.988189 1.7338332
OE
OB 3.1972633 1.7303765 H
OS 3.1910204 1.7291347
OS 3.1857279 1.7255984
OS 3.1821916 1.7203059
OS 3.1809498 1.714063
OS 3.1821916 1.7078201
OS 3.1857279 1.7025276
OS 3.1910204 1.6989913
OS 3.1972633 1.6977495
OS 3.2035062 1.6989913
OS 3.2087987 1.7025276
OS 3.212335 1.7078201
OS 3.2135768 1.714063
OS 3.212335 1.7203059
OS 3.2087987 1.7255984
OS 3.2035062 1.7291347
OS 3.1972633 1.7303765
OE
OB 3.5898425 1.7273765 H
OS 3.5835996 1.7261347
OS 3.5783071 1.7225984
OS 3.5747708 1.7173059
OS 3.573529 1.711063
OS 3.5747708 1.7048201
OS 3.5783071 1.6995276
OS 3.5835996 1.6959913
OS 3.5898425 1.6947495
OS 3.5960854 1.6959913
OS 3.6013779 1.6995276
OS 3.6049142 1.7048201
OS 3.606156 1.711063
OS 3.6049142 1.7173059
OS 3.6013779 1.7225984
OS 3.5960854 1.7261347
OS 3.5898425 1.7273765
OE
OB 1.8938425 1.7093765 H
OS 1.8875996 1.7081347
OS 1.8823071 1.7045984
OS 1.8787708 1.6993059
OS 1.877529 1.693063
OS 1.8787708 1.6868201
OS 1.8823071 1.6815276
OS 1.8875996 1.6779913
OS 1.8938425 1.6767495
OS 1.9000854 1.6779913
OS 1.9053779 1.6815276
OS 1.9089142 1.6868201
OS 1.910156 1.693063
OS 1.9089142 1.6993059
OS 1.9053779 1.7045984
OS 1.9000854 1.7081347
OS 1.8938425 1.7093765
OE
OB 3.8038425 1.7073765 H
OS 3.7975996 1.7061347
OS 3.7923071 1.7025984
OS 3.7887708 1.6973059
OS 3.787529 1.691063
OS 3.7887708 1.6848201
OS 3.7923071 1.6795276
OS 3.7975996 1.6759913
OS 3.8038425 1.6747495
OS 3.8100854 1.6759913
OS 3.8153779 1.6795276
OS 3.8189142 1.6848201
OS 3.820156 1.691063
OS 3.8189142 1.6973059
OS 3.8153779 1.7025984
OS 3.8100854 1.7061347
OS 3.8038425 1.7073765
OE
OB 3.7248425 1.6913765 H
OS 3.7185996 1.6901347
OS 3.7133071 1.6865984
OS 3.7097708 1.6813059
OS 3.708529 1.675063
OS 3.7097708 1.6688201
OS 3.7133071 1.6635276
OS 3.7185996 1.6599913
OS 3.7248425 1.6587495
OS 3.7310854 1.6599913
OS 3.7363779 1.6635276
OS 3.7399142 1.6688201
OS 3.741156 1.675063
OS 3.7399142 1.6813059
OS 3.7363779 1.6865984
OS 3.7310854 1.6901347
OS 3.7248425 1.6913765
OE
OB 1.8227825 1.6903165 H
OS 1.8165396 1.6890747
OS 1.8112471 1.6855384
OS 1.8077108 1.6802459
OS 1.806469 1.674003
OS 1.8077108 1.6677601
OS 1.8112471 1.6624676
OS 1.8165396 1.6589313
OS 1.8227825 1.6576895
OS 1.8290254 1.6589313
OS 1.8343179 1.6624676
OS 1.8378542 1.6677601
OS 1.839096 1.674003
OS 1.8378542 1.6802459
OS 1.8343179 1.6855384
OS 1.8290254 1.6890747
OS 1.8227825 1.6903165
OE
OB 3.7738632 1.6824156 H
OS 3.7676203 1.6811738
OS 3.7623278 1.6776375
OS 3.7587915 1.672345
OS 3.7575497 1.6661021
OS 3.7587915 1.6598592
OS 3.7623278 1.6545667
OS 3.7676203 1.6510304
OS 3.7738632 1.6497886
OS 3.7801061 1.6510304
OS 3.7853986 1.6545667
OS 3.7889349 1.6598592
OS 3.7901767 1.6661021
OS 3.7889349 1.672345
OS 3.7853986 1.6776375
OS 3.7801061 1.6811738
OS 3.7738632 1.6824156
OE
OB 6.8448425 1.6773765 H
OS 6.8385996 1.6761347
OS 6.8333071 1.6725984
OS 6.8297708 1.6673059
OS 6.828529 1.661063
OS 6.8297708 1.6548201
OS 6.8333071 1.6495276
OS 6.8385996 1.6459913
OS 6.8448425 1.6447495
OS 6.8510854 1.6459913
OS 6.8563779 1.6495276
OS 6.8599142 1.6548201
OS 6.861156 1.661063
OS 6.8599142 1.6673059
OS 6.8563779 1.6725984
OS 6.8510854 1.6761347
OS 6.8448425 1.6773765
OE
OB 3.2248425 1.6776607 H
OS 3.2185996 1.6764189
OS 3.2133071 1.6728826
OS 3.2097708 1.6675901
OS 3.208529 1.6613472
OS 3.2097708 1.6551043
OS 3.2133071 1.6498118
OS 3.2185996 1.6462755
OS 3.2248425 1.6450337
OS 3.2310854 1.6462755
OS 3.235497 1.6492232
OS 3.2395781 1.6496996
OS 3.2419254 1.6491144
OS 3.2465996 1.6459913
OS 3.2528425 1.6447495
OS 3.2590854 1.6459913
OS 3.2643779 1.6495276
OS 3.2679142 1.6548201
OS 3.269156 1.661063
OS 3.2679142 1.6673059
OS 3.2643779 1.6725984
OS 3.2590854 1.6761347
OS 3.2528425 1.6773765
OS 3.2465996 1.6761347
OS 3.242188 1.673187
OS 3.2381069 1.6727106
OS 3.2357596 1.6732958
OS 3.2310854 1.6764189
OS 3.2248425 1.6776607
OE
OB 2.6668425 1.6563765 H
OS 2.6605996 1.6551347
OS 2.6553071 1.6515984
OS 2.6517708 1.6463059
OS 2.650529 1.640063
OS 2.6513707 1.6358317
OS 2.6479104 1.6318625
OS 2.6474924 1.6316505
OS 2.6438425 1.6323765
OS 2.6375996 1.6311347
OS 2.6323071 1.6275984
OS 2.6287708 1.6223059
OS 2.627529 1.616063
OS 2.6287708 1.6098201
OS 2.6323071 1.6045276
OS 2.6375996 1.6009913
OS 2.6438425 1.5997495
OS 2.6500854 1.6009913
OS 2.6553779 1.6045276
OS 2.6589142 1.6098201
OS 2.660156 1.616063
OS 2.6593143 1.6202943
OS 2.6627746 1.6242635
OS 2.6631926 1.6244755
OS 2.6668425 1.6237495
OS 2.6730854 1.6249913
OS 2.6783779 1.6285276
OS 2.6819142 1.6338201
OS 2.683156 1.640063
OS 2.6819142 1.6463059
OS 2.6783779 1.6515984
OS 2.6730854 1.6551347
OS 2.6668425 1.6563765
OE
OB 4.1348425 1.6673765 H
OS 4.1285996 1.6661347
OS 4.1233071 1.6625984
OS 4.1197708 1.6573059
OS 4.118529 1.651063
OS 4.1197708 1.6448201
OS 4.1233071 1.6395276
OS 4.1285996 1.6359913
OS 4.1336434 1.634988
OS 4.1357664 1.6316625
OS 4.1362826 1.629938
OS 4.1362346 1.6298661
OS 4.1349928 1.6236232
OS 4.1362346 1.6173803
OS 4.1397709 1.6120878
OS 4.1450634 1.6085515
OS 4.1513063 1.6073097
OS 4.1575492 1.6085515
OS 4.1612353 1.6110144
OS 4.1648401 1.6074096
OS 4.1647708 1.6073059
OS 4.163529 1.601063
OS 4.1647708 1.5948201
OS 4.1683071 1.5895276
OS 4.1735996 1.5859913
OS 4.1798425 1.5847495
OS 4.1860854 1.5859913
OS 4.1913779 1.5895276
OS 4.1949142 1.5948201
OS 4.196156 1.601063
OS 4.1949142 1.6073059
OS 4.1913779 1.6125984
OS 4.1860854 1.6161347
OS 4.1798425 1.6173765
OS 4.1735996 1.6161347
OS 4.1699135 1.6136718
OS 4.1663087 1.6172766
OS 4.166378 1.6173803
OS 4.1676198 1.6236232
OS 4.166378 1.6298661
OS 4.1628417 1.6351586
OS 4.1575492 1.6386949
OS 4.1525054 1.6396982
OS 4.1503824 1.6430237
OS 4.1498662 1.6447482
OS 4.1499142 1.6448201
OS 4.151156 1.651063
OS 4.1499142 1.6573059
OS 4.1463779 1.6625984
OS 4.1410854 1.6661347
OS 4.1348425 1.6673765
OE
OB 2.7198425 1.6073765 H
OS 2.7135996 1.6061347
OS 2.7083071 1.6025984
OS 2.7047708 1.5973059
OS 2.703529 1.591063
OS 2.7047708 1.5848201
OS 2.7083071 1.5795276
OS 2.7135996 1.5759913
OS 2.7198425 1.5747495
OS 2.7260854 1.5759913
OS 2.7313779 1.5795276
OS 2.7349142 1.5848201
OS 2.736156 1.591063
OS 2.7349142 1.5973059
OS 2.7313779 1.6025984
OS 2.7260854 1.6061347
OS 2.7198425 1.6073765
OE
OB 3.8948425 1.5823765 H
OS 3.8885996 1.5811347
OS 3.8833071 1.5775984
OS 3.8797708 1.5723059
OS 3.878529 1.566063
OS 3.8797708 1.5598201
OS 3.8833071 1.5545276
OS 3.8885996 1.5509913
OS 3.8948425 1.5497495
OS 3.9010854 1.5509913
OS 3.9063779 1.5545276
OS 3.9099142 1.5598201
OS 3.911156 1.566063
OS 3.9099142 1.5723059
OS 3.9063779 1.5775984
OS 3.9010854 1.5811347
OS 3.8948425 1.5823765
OE
OB 3.9698425 1.5683765 H
OS 3.9635996 1.5671347
OS 3.9583071 1.5635984
OS 3.9547708 1.5583059
OS 3.953529 1.552063
OS 3.9547708 1.5458201
OS 3.9583071 1.5405276
OS 3.9635996 1.5369913
OS 3.9698425 1.5357495
OS 3.9760854 1.5369913
OS 3.9780923 1.5383323
OS 3.9831154 1.5394836
OS 3.9856688 1.5379496
OS 3.9885996 1.5359913
OS 3.9948425 1.5347495
OS 4.0010854 1.5359913
OS 4.0063779 1.5395276
OS 4.0099142 1.5448201
OS 4.011156 1.551063
OS 4.0099142 1.5573059
OS 4.0063779 1.5625984
OS 4.0010854 1.5661347
OS 3.9948425 1.5673765
OS 3.9885996 1.5661347
OS 3.9833072 1.5625984
OS 3.982046 1.5625984
OS 3.9813779 1.5635984
OS 3.9760854 1.5671347
OS 3.9698425 1.5683765
OE
OB 4.0348425 1.5623765 H
OS 4.0285996 1.5611347
OS 4.0233071 1.5575984
OS 4.0197708 1.5523059
OS 4.018529 1.546063
OS 4.0197708 1.5398201
OS 4.0233071 1.5345276
OS 4.0285996 1.5309913
OS 4.0348425 1.5297495
OS 4.0410854 1.5309913
OS 4.0463779 1.5345276
OS 4.0499142 1.5398201
OS 4.051156 1.546063
OS 4.0499142 1.5523059
OS 4.0463779 1.5575984
OS 4.0410854 1.5611347
OS 4.0348425 1.5623765
OE
OB 3.9248425 1.5523765 H
OS 3.9185996 1.5511347
OS 3.9133071 1.5475984
OS 3.9097708 1.5423059
OS 3.908529 1.536063
OS 3.9097708 1.5298201
OS 3.9133071 1.5245276
OS 3.9185996 1.5209913
OS 3.9248425 1.5197495
OS 3.9310854 1.5209913
OS 3.9363779 1.5245276
OS 3.9399142 1.5298201
OS 3.941156 1.536063
OS 3.9399142 1.5423059
OS 3.9363779 1.5475984
OS 3.9310854 1.5511347
OS 3.9248425 1.5523765
OE
OB 2.8948425 1.5773765 H
OS 2.8885996 1.5761347
OS 2.8833071 1.5725984
OS 2.8797708 1.5673059
OS 2.878529 1.561063
OS 2.8797708 1.5548201
OS 2.8833071 1.5495276
OS 2.8885996 1.5459913
OS 2.8948425 1.5447495
OS 2.9010854 1.5459913
OS 2.9013282 1.5461536
OS 2.9049331 1.5425487
OS 2.9047708 1.5423059
OS 2.903529 1.536063
OS 2.9047708 1.5298201
OS 2.9083071 1.5245276
OS 2.9135996 1.5209913
OS 2.9198425 1.5197495
OS 2.9260854 1.5209913
OS 2.9313779 1.5245276
OS 2.9349142 1.5298201
OS 2.936156 1.536063
OS 2.9349142 1.5423059
OS 2.9313779 1.5475984
OS 2.9260854 1.5511347
OS 2.9198425 1.5523765
OS 2.9135996 1.5511347
OS 2.9133568 1.5509724
OS 2.9097519 1.5545773
OS 2.9099142 1.5548201
OS 2.911156 1.561063
OS 2.9099142 1.5673059
OS 2.9063779 1.5725984
OS 2.9010854 1.5761347
OS 2.8948425 1.5773765
OE
OB 1.7198425 1.5523765 H
OS 1.7135996 1.5511347
OS 1.7083071 1.5475984
OS 1.7047708 1.5423059
OS 1.703529 1.536063
OS 1.7047708 1.5298201
OS 1.7083071 1.5245276
OS 1.7135996 1.5209913
OS 1.7198425 1.5197495
OS 1.7260854 1.5209913
OS 1.7313779 1.5245276
OS 1.7349142 1.5298201
OS 1.736156 1.536063
OS 1.7349142 1.5423059
OS 1.7313779 1.5475984
OS 1.7260854 1.5511347
OS 1.7198425 1.5523765
OE
OB 1.8973025 1.5328365 H
OS 1.8910596 1.5315947
OS 1.8857671 1.5280584
OS 1.8822308 1.5227659
OS 1.880989 1.516523
OS 1.8822308 1.5102801
OS 1.8857671 1.5049876
OS 1.8910596 1.5014513
OS 1.8973025 1.5002095
OS 1.9035454 1.5014513
OS 1.9088379 1.5049876
OS 1.9123742 1.5102801
OS 1.913616 1.516523
OS 1.9123742 1.5227659
OS 1.9088379 1.5280584
OS 1.9035454 1.5315947
OS 1.8973025 1.5328365
OE
OB 4.0648425 1.5273765 H
OS 4.0585996 1.5261347
OS 4.0533071 1.5225984
OS 4.0497708 1.5173059
OS 4.048529 1.511063
OS 4.0497708 1.5048201
OS 4.0533071 1.4995276
OS 4.0585996 1.4959913
OS 4.0648425 1.4947495
OS 4.0710854 1.4959913
OS 4.0763779 1.4995276
OS 4.0799142 1.5048201
OS 4.081156 1.511063
OS 4.0799142 1.5173059
OS 4.0763779 1.5225984
OS 4.0710854 1.5261347
OS 4.0648425 1.5273765
OE
OB 3.8648425 1.5273765 H
OS 3.8585996 1.5261347
OS 3.8533071 1.5225984
OS 3.8497708 1.5173059
OS 3.848529 1.511063
OS 3.8497708 1.5048201
OS 3.8533071 1.4995276
OS 3.8585996 1.4959913
OS 3.8648425 1.4947495
OS 3.8710854 1.4959913
OS 3.8763779 1.4995276
OS 3.8799142 1.5048201
OS 3.881156 1.511063
OS 3.8799142 1.5173059
OS 3.8763779 1.5225984
OS 3.8710854 1.5261347
OS 3.8648425 1.5273765
OE
OB 2.2748425 1.5223765 H
OS 2.2685996 1.5211347
OS 2.2633071 1.5175984
OS 2.2597708 1.5123059
OS 2.258529 1.506063
OS 2.2597708 1.4998201
OS 2.2633071 1.4945276
OS 2.2685996 1.4909913
OS 2.2748425 1.4897495
OS 2.2810854 1.4909913
OS 2.2863779 1.4945276
OS 2.2899142 1.4998201
OS 2.291156 1.506063
OS 2.2899142 1.5123059
OS 2.2863779 1.5175984
OS 2.2810854 1.5211347
OS 2.2748425 1.5223765
OE
OB 3.8348425 1.4973765 H
OS 3.8285996 1.4961347
OS 3.8233071 1.4925984
OS 3.8197708 1.4873059
OS 3.818529 1.481063
OS 3.8197708 1.4748201
OS 3.8233071 1.4695276
OS 3.8285996 1.4659913
OS 3.8348425 1.4647495
OS 3.8410854 1.4659913
OS 3.8463779 1.4695276
OS 3.8499142 1.4748201
OS 3.851156 1.481063
OS 3.8499142 1.4873059
OS 3.8463779 1.4925984
OS 3.8410854 1.4961347
OS 3.8348425 1.4973765
OE
OB 2.6948425 1.4973765 H
OS 2.6885996 1.4961347
OS 2.6833071 1.4925984
OS 2.6797708 1.4873059
OS 2.678529 1.481063
OS 2.6797708 1.4748201
OS 2.6833071 1.4695276
OS 2.6885996 1.4659913
OS 2.6948425 1.4647495
OS 2.7010854 1.4659913
OS 2.7063779 1.4695276
OS 2.7099142 1.4748201
OS 2.711156 1.481063
OS 2.7099142 1.4873059
OS 2.7063779 1.4925984
OS 2.7010854 1.4961347
OS 2.6948425 1.4973765
OE
OB 3.5498425 1.4573765 H
OS 3.5435996 1.4561347
OS 3.5383071 1.4525984
OS 3.5347708 1.4473059
OS 3.533529 1.441063
OS 3.5347708 1.4348201
OS 3.5383071 1.4295276
OS 3.5435996 1.4259913
OS 3.5498425 1.4247495
OS 3.5560854 1.4259913
OS 3.5613779 1.4295276
OS 3.5649142 1.4348201
OS 3.566156 1.441063
OS 3.5649142 1.4473059
OS 3.5613779 1.4525984
OS 3.5560854 1.4561347
OS 3.5498425 1.4573765
OE
OB 2.4468425 1.4533765 H
OS 2.4405996 1.4521347
OS 2.4353071 1.4485984
OS 2.4317708 1.4433059
OS 2.430529 1.437063
OS 2.4317708 1.4308201
OS 2.4353071 1.4255276
OS 2.4405996 1.4219913
OS 2.4468425 1.4207495
OS 2.4530854 1.4219913
OS 2.4583779 1.4255276
OS 2.4619142 1.4308201
OS 2.463156 1.437063
OS 2.4619142 1.4433059
OS 2.4583779 1.4485984
OS 2.4530854 1.4521347
OS 2.4468425 1.4533765
OE
OB 1.0088425 1.4463765 H
OS 1.0025996 1.4451347
OS 0.9973071 1.4415984
OS 0.9937708 1.4363059
OS 0.992529 1.430063
OS 0.9937708 1.4238201
OS 0.9973071 1.4185276
OS 1.0025996 1.4149913
OS 1.0088425 1.4137495
OS 1.0150854 1.4149913
OS 1.0203779 1.4185276
OS 1.0239142 1.4238201
OS 1.025156 1.430063
OS 1.0239142 1.4363059
OS 1.0203779 1.4415984
OS 1.0150854 1.4451347
OS 1.0088425 1.4463765
OE
OB 2.0838425 1.4279765 H
OS 2.0775996 1.4267347
OS 2.0723071 1.4231984
OS 2.0687708 1.4179059
OS 2.067529 1.411663
OS 2.0687708 1.4054201
OS 2.0688553 1.4052937
OS 2.0669242 1.4023943
OS 2.0655495 1.4012413
OS 2.0598425 1.4023765
OS 2.0535996 1.4011347
OS 2.0483071 1.3975984
OS 2.0447708 1.3923059
OS 2.043529 1.386063
OS 2.0447708 1.3798201
OS 2.0483071 1.3745276
OS 2.0535996 1.3709913
OS 2.0598425 1.3697495
OS 2.0660854 1.3709913
OS 2.0713779 1.3745276
OS 2.0749142 1.3798201
OS 2.076156 1.386063
OS 2.0749142 1.3923059
OS 2.0748297 1.3924323
OS 2.0767608 1.3953317
OS 2.0781355 1.3964847
OS 2.0838425 1.3953495
OS 2.0900854 1.3965913
OS 2.0953779 1.4001276
OS 2.0989142 1.4054201
OS 2.100156 1.411663
OS 2.0989142 1.4179059
OS 2.0953779 1.4231984
OS 2.0900854 1.4267347
OS 2.0838425 1.4279765
OE
OB 3.4072822 1.4276365 H
OS 3.4010393 1.4263947
OS 3.3957468 1.4228584
OS 3.3922105 1.4175659
OS 3.3909687 1.411323
OS 3.3922105 1.4050801
OS 3.3952066 1.4005957
OS 3.3913778 1.3975986
OS 3.3860854 1.4011347
OS 3.3798425 1.4023765
OS 3.3735996 1.4011347
OS 3.3683071 1.3975984
OS 3.3647708 1.3923059
OS 3.363529 1.386063
OS 3.3647708 1.3798201
OS 3.3683071 1.3745276
OS 3.3735996 1.3709913
OS 3.3798425 1.3697495
OS 3.3850268 1.3707807
OS 3.3880585 1.3685992
OS 3.3892832 1.3671145
OS 3.388529 1.363323
OS 3.3897708 1.3570801
OS 3.3920261 1.3537048
OS 3.3926608 1.3527545
OS 3.3890562 1.3491499
OS 3.3882815 1.3496673
OS 3.3860854 1.3511347
OS 3.3798425 1.3523765
OS 3.3735996 1.3511347
OS 3.3683071 1.3475984
OS 3.3647708 1.3423059
OS 3.363529 1.336063
OS 3.3647708 1.3298201
OS 3.3683071 1.3245276
OS 3.3735996 1.3209913
OS 3.3798425 1.3197495
OS 3.3860854 1.3209913
OS 3.3913779 1.3245276
OS 3.3949142 1.3298201
OS 3.396156 1.336063
OS 3.3949142 1.3423059
OS 3.3926589 1.3456812
OS 3.3920242 1.3466315
OS 3.3956288 1.3502361
OS 3.3964035 1.3497187
OS 3.3985996 1.3482513
OS 3.4048425 1.3470095
OS 3.4110854 1.3482513
OS 3.4163779 1.3517876
OS 3.4199142 1.3570801
OS 3.421156 1.363323
OS 3.4199142 1.3695659
OS 3.4163779 1.3748584
OS 3.4110854 1.3783947
OS 3.4048425 1.3796365
OS 3.3996582 1.3786053
OS 3.3966265 1.3807868
OS 3.3954018 1.3822715
OS 3.396156 1.386063
OS 3.3949142 1.3923059
OS 3.3919181 1.3967903
OS 3.3957469 1.3997874
OS 3.4010393 1.3962513
OS 3.4072822 1.3950095
OS 3.4135251 1.3962513
OS 3.4188176 1.3997876
OS 3.4223539 1.4050801
OS 3.4235957 1.411323
OS 3.4223539 1.4175659
OS 3.4188176 1.4228584
OS 3.4135251 1.4263947
OS 3.4072822 1.4276365
OE
OB 0.1998425 1.4953727 H
OS 0.1872963 1.494137
OS 0.1752322 1.4904774
OS 0.1641139 1.4845346
OS 0.1543687 1.4765368
OS 0.1463709 1.4667916
OS 0.1404281 1.4556733
OS 0.1367685 1.4436092
OS 0.1355328 1.431063
OS 0.1367685 1.4185168
OS 0.1404281 1.4064527
OS 0.1463709 1.3953344
OS 0.1543687 1.3855892
OS 0.1641139 1.3775914
OS 0.1752322 1.3716486
OS 0.1872963 1.367989
OS 0.1998425 1.3667533
OS 0.2123887 1.367989
OS 0.2244528 1.3716486
OS 0.2355711 1.3775914
OS 0.2453163 1.3855892
OS 0.2533141 1.3953344
OS 0.2592569 1.4064527
OS 0.2629165 1.4185168
OS 0.2641522 1.431063
OS 0.2629165 1.4436092
OS 0.2592569 1.4556733
OS 0.2533141 1.4667916
OS 0.2453163 1.4765368
OS 0.2355711 1.4845346
OS 0.2244528 1.4904774
OS 0.2123887 1.494137
OS 0.1998425 1.4953727
OE
OB 2.0288425 1.3779765 H
OS 2.0225996 1.3767347
OS 2.0173071 1.3731984
OS 2.0137708 1.3679059
OS 2.012529 1.361663
OS 2.0137708 1.3554201
OS 2.0138553 1.3552937
OS 2.0119242 1.3523943
OS 2.0105495 1.3512413
OS 2.0048425 1.3523765
OS 1.9985996 1.3511347
OS 1.9933071 1.3475984
OS 1.9897708 1.3423059
OS 1.988529 1.336063
OS 1.9897708 1.3298201
OS 1.9933071 1.3245276
OS 1.9985996 1.3209913
OS 2.0048425 1.3197495
OS 2.0110854 1.3209913
OS 2.0163779 1.3245276
OS 2.0199142 1.3298201
OS 2.021156 1.336063
OS 2.0199142 1.3423059
OS 2.0198297 1.3424323
OS 2.0217608 1.3453317
OS 2.0231355 1.3464847
OS 2.0288425 1.3453495
OS 2.0350854 1.3465913
OS 2.0403779 1.3501276
OS 2.0439142 1.3554201
OS 2.045156 1.361663
OS 2.0439142 1.3679059
OS 2.0403779 1.3731984
OS 2.0350854 1.3767347
OS 2.0288425 1.3779765
OE
OB 2.5028425 1.3323765 H
OS 2.4965996 1.3311347
OS 2.4913071 1.3275984
OS 2.4877708 1.3223059
OS 2.486529 1.316063
OS 2.4877708 1.3098201
OS 2.4913071 1.3045276
OS 2.4965996 1.3009913
OS 2.5028425 1.2997495
OS 2.5090854 1.3009913
OS 2.5143779 1.3045276
OS 2.5179142 1.3098201
OS 2.519156 1.316063
OS 2.5179142 1.3223059
OS 2.5143779 1.3275984
OS 2.5090854 1.3311347
OS 2.5028425 1.3323765
OE
OB 1.6968325 1.3290319 H
OS 1.6894854 1.3275705
OS 1.6832568 1.3234087
OS 1.679095 1.3171801
OS 1.6776336 1.309833
OS 1.679095 1.3024859
OS 1.6832568 1.2962573
OS 1.6894854 1.2920955
OS 1.6968325 1.2906341
OS 1.7041796 1.2920955
OS 1.7104082 1.2962573
OS 1.71457 1.3024859
OS 1.7160314 1.309833
OS 1.71457 1.3171801
OS 1.7104082 1.3234087
OS 1.7041796 1.3275705
OS 1.6968325 1.3290319
OE
OB 3.5717425 1.3289919 H
OS 3.5643954 1.3275305
OS 3.5581668 1.3233687
OS 3.554005 1.3171401
OS 3.5525436 1.309793
OS 3.554005 1.3024459
OS 3.5581668 1.2962173
OS 3.5643954 1.2920555
OS 3.5717425 1.2905941
OS 3.5790896 1.2920555
OS 3.5853182 1.2962173
OS 3.58948 1.3024459
OS 3.5909414 1.309793
OS 3.58948 1.3171401
OS 3.5853182 1.3233687
OS 3.5790896 1.3275305
OS 3.5717425 1.3289919
OE
OB 1.7982283 1.3204474 H
OS 1.7919854 1.3192056
OS 1.7866929 1.3156693
OS 1.7831566 1.3103768
OS 1.7819148 1.3041339
OS 1.7831566 1.297891
OS 1.7866929 1.2925985
OS 1.7919854 1.2890622
OS 1.7982283 1.2878204
OS 1.8044712 1.2890622
OS 1.8097637 1.2925985
OS 1.8133 1.297891
OS 1.8145418 1.3041339
OS 1.8133 1.3103768
OS 1.8097637 1.3156693
OS 1.8044712 1.3192056
OS 1.7982283 1.3204474
OE
OB 2.2068425 1.3143765 H
OS 2.2005996 1.3131347
OS 2.1953071 1.3095984
OS 2.1917708 1.3043059
OS 2.190529 1.298063
OS 2.1917708 1.2918201
OS 2.1953071 1.2865276
OS 2.2005996 1.2829913
OS 2.2068425 1.2817495
OS 2.2130854 1.2829913
OS 2.2183779 1.2865276
OS 2.2219142 1.2918201
OS 2.223156 1.298063
OS 2.2219142 1.3043059
OS 2.2183779 1.3095984
OS 2.2130854 1.3131347
OS 2.2068425 1.3143765
OE
OB 1.5679134 1.3017466 H
OS 1.5616705 1.3005048
OS 1.556378 1.2969685
OS 1.5528417 1.291676
OS 1.5515999 1.2854331
OS 1.5528417 1.2791902
OS 1.556378 1.2738977
OS 1.5616705 1.2703614
OS 1.5679134 1.2691196
OS 1.5741563 1.2703614
OS 1.5794488 1.2738977
OS 1.5829851 1.2791902
OS 1.5842269 1.2854331
OS 1.5829851 1.291676
OS 1.5794488 1.2969685
OS 1.5741563 1.3005048
OS 1.5679134 1.3017466
OE
OB 0.996063 1.2033214 H
OS 0.9898201 1.2020796
OS 0.9845276 1.1985433
OS 0.9809913 1.1932508
OS 0.9797495 1.1870079
OS 0.9809913 1.180765
OS 0.9845276 1.1754725
OS 0.9898201 1.1719362
OS 0.996063 1.1706944
OS 1.0023059 1.1719362
OS 1.0075984 1.1754725
OS 1.0111347 1.180765
OS 1.0123765 1.1870079
OS 1.0111347 1.1932508
OS 1.0075984 1.1985433
OS 1.0023059 1.2020796
OS 0.996063 1.2033214
OE
OB 2.8267717 0.9926915 H
OS 2.8205288 0.9914497
OS 2.8152364 0.9879134
OS 2.8107479 0.9879134
OS 2.8054555 0.9914497
OS 2.7992126 0.9926915
OS 2.7929697 0.9914497
OS 2.7876772 0.9879134
OS 2.7864713 0.9861086
OS 2.7804578 0.9861086
OS 2.7792519 0.9879134
OS 2.7739594 0.9914497
OS 2.7677165 0.9926915
OS 2.7614736 0.9914497
OS 2.7561812 0.9879134
OS 2.7516928 0.9879134
OS 2.7464004 0.9914497
OS 2.7401575 0.9926915
OS 2.7339146 0.9914497
OS 2.7286221 0.9879134
OS 2.7274162 0.9861086
OS 2.7214027 0.9861086
OS 2.7201968 0.9879134
OS 2.7149043 0.9914497
OS 2.7086614 0.9926915
OS 2.7024185 0.9914497
OS 2.6971261 0.9879134
OS 2.6926377 0.9879134
OS 2.6873453 0.9914497
OS 2.6811024 0.9926915
OS 2.6748595 0.9914497
OS 2.669567 0.9879134
OS 2.6683611 0.9861086
OS 2.6623476 0.9861086
OS 2.6611417 0.9879134
OS 2.6558492 0.9914497
OS 2.6496063 0.9926915
OS 2.6433634 0.9914497
OS 2.638071 0.9879134
OS 2.6335825 0.9879134
OS 2.6282901 0.9914497
OS 2.6220472 0.9926915
OS 2.6158043 0.9914497
OS 2.6105118 0.9879134
OS 2.6069755 0.9826209
OS 2.6057337 0.976378
OS 2.6069755 0.9701351
OS 2.6105118 0.9648426
OS 2.6158043 0.9613063
OS 2.6220472 0.9600645
OS 2.6282901 0.9613063
OS 2.6335825 0.9648426
OS 2.638071 0.9648426
OS 2.6433634 0.9613063
OS 2.6496063 0.9600645
OS 2.6558492 0.9613063
OS 2.6611417 0.9648426
OS 2.6623476 0.9666474
OS 2.6683611 0.9666474
OS 2.669567 0.9648426
OS 2.6748595 0.9613063
OS 2.6811024 0.9600645
OS 2.6873453 0.9613063
OS 2.6926377 0.9648426
OS 2.6971261 0.9648426
OS 2.7024185 0.9613063
OS 2.7086614 0.9600645
OS 2.7149043 0.9613063
OS 2.7201968 0.9648426
OS 2.7214027 0.9666474
OS 2.7274162 0.9666474
OS 2.7286221 0.9648426
OS 2.7339146 0.9613063
OS 2.7401575 0.9600645
OS 2.7464004 0.9613063
OS 2.7516928 0.9648426
OS 2.7561812 0.9648426
OS 2.7614736 0.9613063
OS 2.7677165 0.9600645
OS 2.7739594 0.9613063
OS 2.7792519 0.9648426
OS 2.7804578 0.9666474
OS 2.7864713 0.9666474
OS 2.7876772 0.9648426
OS 2.7929697 0.9613063
OS 2.7992126 0.9600645
OS 2.8054555 0.9613063
OS 2.8107479 0.9648426
OS 2.8152364 0.9648426
OS 2.8205288 0.9613063
OS 2.8267717 0.9600645
OS 2.8330146 0.9613063
OS 2.8383071 0.9648426
OS 2.8418434 0.9701351
OS 2.8430852 0.976378
OS 2.8418434 0.9826209
OS 2.8383071 0.9879134
OS 2.8330146 0.9914497
OS 2.8267717 0.9926915
OE
OB 4.3662677 1.0459921 H
OS 4.2892441 1.0459921
OS 4.2892441 0.9689685
OS 4.3662677 0.9689685
OS 4.3662677 1.0459921
OE
OB 5.3277559 1.0463244 H
OS 5.3177023 1.0450008
OS 5.3083338 1.0411203
OS 5.300289 1.0349472
OS 5.2941159 1.0269023
OS 5.2902354 1.0175339
OS 5.2889118 1.0074803
OS 5.2902354 0.9974267
OS 5.2941159 0.9880583
OS 5.300289 0.9800134
OS 5.3083338 0.9738403
OS 5.3177023 0.9699598
OS 5.3277559 0.9686362
OS 5.3378095 0.9699598
OS 5.347178 0.9738403
OS 5.3552228 0.9800134
OS 5.3613959 0.9880583
OS 5.3652764 0.9974267
OS 5.3666 1.0074803
OS 5.3652764 1.0175339
OS 5.3613959 1.0269023
OS 5.3552228 1.0349472
OS 5.347178 1.0411203
OS 5.3378095 1.0450008
OS 5.3277559 1.0463244
OE
OB 5.1277559 1.0463244 H
OS 5.1177023 1.0450008
OS 5.1083338 1.0411203
OS 5.100289 1.0349472
OS 5.0941159 1.0269023
OS 5.0902354 1.0175339
OS 5.0889118 1.0074803
OS 5.0902354 0.9974267
OS 5.0941159 0.9880583
OS 5.100289 0.9800134
OS 5.1083338 0.9738403
OS 5.1177023 0.9699598
OS 5.1277559 0.9686362
OS 5.1378095 0.9699598
OS 5.147178 0.9738403
OS 5.1552228 0.9800134
OS 5.1613959 0.9880583
OS 5.1652764 0.9974267
OS 5.1666 1.0074803
OS 5.1652764 1.0175339
OS 5.1613959 1.0269023
OS 5.1552228 1.0349472
OS 5.147178 1.0411203
OS 5.1378095 1.0450008
OS 5.1277559 1.0463244
OE
OB 4.9277559 1.0463244 H
OS 4.9177023 1.0450008
OS 4.9083338 1.0411203
OS 4.900289 1.0349472
OS 4.8941159 1.0269023
OS 4.8902354 1.0175339
OS 4.8889118 1.0074803
OS 4.8902354 0.9974267
OS 4.8941159 0.9880583
OS 4.900289 0.9800134
OS 4.9083338 0.9738403
OS 4.9177023 0.9699598
OS 4.9277559 0.9686362
OS 4.9378095 0.9699598
OS 4.947178 0.9738403
OS 4.9552228 0.9800134
OS 4.9613959 0.9880583
OS 4.9652764 0.9974267
OS 4.9666 1.0074803
OS 4.9652764 1.0175339
OS 4.9613959 1.0269023
OS 4.9552228 1.0349472
OS 4.947178 1.0411203
OS 4.9378095 1.0450008
OS 4.9277559 1.0463244
OE
OB 2.9905425 0.9777919 H
OS 2.9831954 0.9763305
OS 2.9769668 0.9721687
OS 2.972805 0.9659401
OS 2.9713436 0.958593
OS 2.972805 0.9512459
OS 2.9769668 0.9450173
OS 2.9831954 0.9408555
OS 2.9905425 0.9393941
OS 2.9978896 0.9408555
OS 3.0041182 0.9450173
OS 3.00828 0.9512459
OS 3.0097414 0.958593
OS 3.00828 0.9659401
OS 3.0041182 0.9721687
OS 2.9978896 0.9763305
OS 2.9905425 0.9777919
OE
OB 2.2031425 0.9777919 H
OS 2.1957954 0.9763305
OS 2.1895668 0.9721687
OS 2.185405 0.9659401
OS 2.1839436 0.958593
OS 2.185405 0.9512459
OS 2.1895668 0.9450173
OS 2.1957954 0.9408555
OS 2.2031425 0.9393941
OS 2.2104896 0.9408555
OS 2.2167182 0.9450173
OS 2.22088 0.9512459
OS 2.2223414 0.958593
OS 2.22088 0.9659401
OS 2.2167182 0.9721687
OS 2.2104896 0.9763305
OS 2.2031425 0.9777919
OE
OB 2.4788425 0.9533765 H
OS 2.4725996 0.9521347
OS 2.4673071 0.9485984
OS 2.4637708 0.9433059
OS 2.462529 0.937063
OS 2.4637708 0.9308201
OS 2.4673071 0.9255276
OS 2.4725996 0.9219913
OS 2.4788425 0.9207495
OS 2.4850854 0.9219913
OS 2.4903779 0.9255276
OS 2.4939142 0.9308201
OS 2.495156 0.937063
OS 2.4939142 0.9433059
OS 2.4903779 0.9485984
OS 2.4850854 0.9521347
OS 2.4788425 0.9533765
OE
OB 1.0048425 0.9223765 H
OS 0.9985996 0.9211347
OS 0.9933071 0.9175984
OS 0.9897708 0.9123059
OS 0.988529 0.906063
OS 0.9897708 0.8998201
OS 0.9933071 0.8945276
OS 0.9985996 0.8909913
OS 1.0048425 0.8897495
OS 1.0110854 0.8909913
OS 1.0163779 0.8945276
OS 1.0199142 0.8998201
OS 1.021156 0.906063
OS 1.0199142 0.9123059
OS 1.0163779 0.9175984
OS 1.0110854 0.9211347
OS 1.0048425 0.9223765
OE
OB 3.6179425 0.9836725 H
OS 3.6047974 0.9823778
OS 3.5921575 0.9785435
OS 3.5805085 0.972317
OS 3.570298 0.9639375
OS 3.5619185 0.953727
OS 3.555692 0.942078
OS 3.5518577 0.9294381
OS 3.550563 0.916293
OS 3.5518577 0.9031479
OS 3.555692 0.890508
OS 3.5619185 0.878859
OS 3.570298 0.8686485
OS 3.5805085 0.860269
OS 3.5921575 0.8540425
OS 3.6047974 0.8502082
OS 3.6179425 0.8489135
OS 3.6310876 0.8502082
OS 3.6437275 0.8540425
OS 3.6553765 0.860269
OS 3.665587 0.8686485
OS 3.6739665 0.878859
OS 3.680193 0.890508
OS 3.6840273 0.9031479
OS 3.685322 0.916293
OS 3.6840273 0.9294381
OS 3.680193 0.942078
OS 3.6739665 0.953727
OS 3.665587 0.9639375
OS 3.6553765 0.972317
OS 3.6437275 0.9785435
OS 3.6310876 0.9823778
OS 3.6179425 0.9836725
OE
OB 1.6529425 0.9836725 H
OS 1.6397974 0.9823778
OS 1.6271575 0.9785435
OS 1.6155085 0.972317
OS 1.605298 0.9639375
OS 1.5969185 0.953727
OS 1.590692 0.942078
OS 1.5868577 0.9294381
OS 1.585563 0.916293
OS 1.5868577 0.9031479
OS 1.590692 0.890508
OS 1.5969185 0.878859
OS 1.605298 0.8686485
OS 1.6155085 0.860269
OS 1.6271575 0.8540425
OS 1.6397974 0.8502082
OS 1.6529425 0.8489135
OS 1.6660876 0.8502082
OS 1.6787275 0.8540425
OS 1.6903765 0.860269
OS 1.700587 0.8686485
OS 1.7089665 0.878859
OS 1.715193 0.890508
OS 1.7190273 0.9031479
OS 1.720322 0.916293
OS 1.7190273 0.9294381
OS 1.715193 0.942078
OS 1.7089665 0.953727
OS 1.700587 0.9639375
OS 1.6903765 0.972317
OS 1.6787275 0.9785435
OS 1.6660876 0.9823778
OS 1.6529425 0.9836725
OE
OB 5.5781524 0.9365112 H
OS 5.5662745 0.9349474
OS 5.5552061 0.9303628
OS 5.5457014 0.9230696
OS 5.5384082 0.9135649
OS 5.5338236 0.9024965
OS 5.5322598 0.8906186
OS 5.5338236 0.8787407
OS 5.5384082 0.8676723
OS 5.5457014 0.8581676
OS 5.5552061 0.8508744
OS 5.5662745 0.8462898
OS 5.5781524 0.844726
OS 5.5900303 0.8462898
OS 5.6010987 0.8508744
OS 5.6106034 0.8581676
OS 5.6178966 0.8676723
OS 5.6224812 0.8787407
OS 5.624045 0.8906186
OS 5.6224812 0.9024965
OS 5.6178966 0.9135649
OS 5.6106034 0.9230696
OS 5.6010987 0.9303628
OS 5.5900303 0.9349474
OS 5.5781524 0.9365112
OE
OB 3.9797272 0.9365112 H
OS 3.9678493 0.9349474
OS 3.9567809 0.9303628
OS 3.9472762 0.9230696
OS 3.939983 0.9135649
OS 3.9353984 0.9024965
OS 3.9338346 0.8906186
OS 3.9353984 0.8787407
OS 3.939983 0.8676723
OS 3.9472762 0.8581676
OS 3.9567809 0.8508744
OS 3.9678493 0.8462898
OS 3.9797272 0.844726
OS 3.9916051 0.8462898
OS 4.0026735 0.8508744
OS 4.0121782 0.8581676
OS 4.0194714 0.8676723
OS 4.024056 0.8787407
OS 4.0256198 0.8906186
OS 4.024056 0.9024965
OS 4.0194714 0.9135649
OS 4.0121782 0.9230696
OS 4.0026735 0.9303628
OS 3.9916051 0.9349474
OS 3.9797272 0.9365112
OE
OB 0.1998425 0.9703727 H
OS 0.1872963 0.969137
OS 0.1752322 0.9654774
OS 0.1641139 0.9595346
OS 0.1543687 0.9515368
OS 0.1463709 0.9417916
OS 0.1404281 0.9306733
OS 0.1367685 0.9186092
OS 0.1355328 0.906063
OS 0.1367685 0.8935168
OS 0.1404281 0.8814527
OS 0.1463709 0.8703344
OS 0.1543687 0.8605892
OS 0.1641139 0.8525914
OS 0.1752322 0.8466486
OS 0.1872963 0.842989
OS 0.1998425 0.8417533
OS 0.2123887 0.842989
OS 0.2244528 0.8466486
OS 0.2355711 0.8525914
OS 0.2453163 0.8605892
OS 0.2533141 0.8703344
OS 0.2592569 0.8814527
OS 0.2629165 0.8935168
OS 0.2641522 0.906063
OS 0.2629165 0.9186092
OS 0.2592569 0.9306733
OS 0.2533141 0.9417916
OS 0.2453163 0.9515368
OS 0.2355711 0.9595346
OS 0.2244528 0.9654774
OS 0.2123887 0.969137
OS 0.1998425 0.9703727
OE
OB 2.7598425 0.8115891 H
OS 2.7535996 0.8103473
OS 2.7483072 0.806811
OS 2.7438188 0.806811
OS 2.7385264 0.8103473
OS 2.7322835 0.8115891
OS 2.7260406 0.8103473
OS 2.7207481 0.806811
OS 2.7172118 0.8015185
OS 2.71597 0.7952756
OS 2.7172118 0.7890327
OS 2.7207481 0.7837402
OS 2.7260406 0.7802039
OS 2.7322835 0.7789621
OS 2.7385264 0.7802039
OS 2.7438188 0.7837402
OS 2.7483072 0.7837402
OS 2.7535996 0.7802039
OS 2.7598425 0.7789621
OS 2.7660854 0.7802039
OS 2.7713779 0.7837402
OS 2.7749142 0.7890327
OS 2.776156 0.7952756
OS 2.7749142 0.8015185
OS 2.7713779 0.806811
OS 2.7660854 0.8103473
OS 2.7598425 0.8115891
OE
OB 2.6929134 0.8115891 H
OS 2.6866705 0.8103473
OS 2.6813781 0.806811
OS 2.6768896 0.806811
OS 2.6715972 0.8103473
OS 2.6653543 0.8115891
OS 2.6591114 0.8103473
OS 2.6538189 0.806811
OS 2.6502826 0.8015185
OS 2.6490408 0.7952756
OS 2.6502826 0.7890327
OS 2.6538189 0.7837402
OS 2.6591114 0.7802039
OS 2.6653543 0.7789621
OS 2.6715972 0.7802039
OS 2.6768896 0.7837402
OS 2.6813781 0.7837402
OS 2.6866705 0.7802039
OS 2.6929134 0.7789621
OS 2.6991563 0.7802039
OS 2.7044488 0.7837402
OS 2.7079851 0.7890327
OS 2.7092269 0.7952756
OS 2.7079851 0.8015185
OS 2.7044488 0.806811
OS 2.6991563 0.8103473
OS 2.6929134 0.8115891
OE
OB 2.6259843 0.8115891 H
OS 2.6197414 0.8103473
OS 2.614449 0.806811
OS 2.6099605 0.806811
OS 2.6046681 0.8103473
OS 2.5984252 0.8115891
OS 2.5921823 0.8103473
OS 2.5868898 0.806811
OS 2.5833535 0.8015185
OS 2.5821117 0.7952756
OS 2.5833535 0.7890327
OS 2.5868898 0.7837402
OS 2.5921823 0.7802039
OS 2.5984252 0.7789621
OS 2.6046681 0.7802039
OS 2.6099605 0.7837402
OS 2.614449 0.7837402
OS 2.6197414 0.7802039
OS 2.6259843 0.7789621
OS 2.6322272 0.7802039
OS 2.6375197 0.7837402
OS 2.641056 0.7890327
OS 2.6422978 0.7952756
OS 2.641056 0.8015185
OS 2.6375197 0.806811
OS 2.6322272 0.8103473
OS 2.6259843 0.8115891
OE
OB 2.8937008 0.8115891 H
OS 2.8874579 0.8103473
OS 2.8821654 0.806811
OS 2.8809595 0.8050062
OS 2.874946 0.8050062
OS 2.8737401 0.806811
OS 2.8684476 0.8103473
OS 2.8622047 0.8115891
OS 2.8559618 0.8103473
OS 2.8506693 0.806811
OS 2.847133 0.8015185
OS 2.8470372 0.8010368
OS 2.8419392 0.8010368
OS 2.8418434 0.8015185
OS 2.8383071 0.806811
OS 2.8330146 0.8103473
OS 2.8267717 0.8115891
OS 2.8205288 0.8103473
OS 2.8152364 0.806811
OS 2.8107479 0.806811
OS 2.8054555 0.8103473
OS 2.7992126 0.8115891
OS 2.7929697 0.8103473
OS 2.7876772 0.806811
OS 2.7841409 0.8015185
OS 2.7828991 0.7952756
OS 2.7841409 0.7890327
OS 2.7876772 0.7837402
OS 2.7929697 0.7802039
OS 2.7992126 0.7789621
OS 2.8054555 0.7802039
OS 2.8107479 0.7837402
OS 2.8152364 0.7837402
OS 2.8205288 0.7802039
OS 2.8267717 0.7789621
OS 2.8330146 0.7802039
OS 2.8383071 0.7837402
OS 2.8418434 0.7890327
OS 2.8419392 0.7895144
OS 2.8470372 0.7895144
OS 2.847133 0.7890327
OS 2.8506693 0.7837402
OS 2.8559618 0.7802039
OS 2.8622047 0.7789621
OS 2.8684476 0.7802039
OS 2.8737401 0.7837402
OS 2.874946 0.785545
OS 2.8809595 0.785545
OS 2.8821654 0.7837402
OS 2.8874579 0.7802039
OS 2.8937008 0.7789621
OS 2.8999437 0.7802039
OS 2.9052362 0.7837402
OS 2.9087725 0.7890327
OS 2.9100143 0.7952756
OS 2.9087725 0.8015185
OS 2.9052362 0.806811
OS 2.8999437 0.8103473
OS 2.8937008 0.8115891
OE
OB 0.9901575 0.7033214 H
OS 0.9839146 0.7020796
OS 0.9786221 0.6985433
OS 0.9750858 0.6932508
OS 0.973844 0.6870079
OS 0.9750858 0.680765
OS 0.9786221 0.6754725
OS 0.9839146 0.6719362
OS 0.9901575 0.6706944
OS 0.9964004 0.6719362
OS 1.0016929 0.6754725
OS 1.0052292 0.680765
OS 1.006471 0.6870079
OS 1.0052292 0.6932508
OS 1.0016929 0.6985433
OS 0.9964004 0.7020796
OS 0.9901575 0.7033214
OE
OB 2.4698827 0.4273018 H
OS 2.4636398 0.42606
OS 2.4583473 0.4225237
OS 2.454811 0.4172312
OS 2.4535692 0.4109883
OS 2.454811 0.4047454
OS 2.4583473 0.3994529
OS 2.4636398 0.3959166
OS 2.4698827 0.3946748
OS 2.4761256 0.3959166
OS 2.4814181 0.3994529
OS 2.4849544 0.4047454
OS 2.4861962 0.4109883
OS 2.4849544 0.4172312
OS 2.4814181 0.4225237
OS 2.4761256 0.42606
OS 2.4698827 0.4273018
OE
OB 2.980457 0.4254674 H
OS 2.9742141 0.4242256
OS 2.9689216 0.4206893
OS 2.9653853 0.4153968
OS 2.9641435 0.4091539
OS 2.9653853 0.402911
OS 2.9689216 0.3976185
OS 2.9742141 0.3940822
OS 2.980457 0.3928404
OS 2.9866999 0.3940822
OS 2.9919924 0.3976185
OS 2.9955287 0.402911
OS 2.9967705 0.4091539
OS 2.9955287 0.4153968
OS 2.9919924 0.4206893
OS 2.9866999 0.4242256
OS 2.980457 0.4254674
OE
OB 3.019685 0.4218253 H
OS 3.0134421 0.4205835
OS 3.0081496 0.4170472
OS 3.0046133 0.4117547
OS 3.0033715 0.4055118
OS 3.0046133 0.3992689
OS 3.0081496 0.3939764
OS 3.0134421 0.3904401
OS 3.019685 0.3891983
OS 3.0259279 0.3904401
OS 3.0312204 0.3939764
OS 3.0347567 0.3992689
OS 3.0359985 0.4055118
OS 3.0347567 0.4117547
OS 3.0312204 0.4170472
OS 3.0259279 0.4205835
OS 3.019685 0.4218253
OE
OB 2.8219832 0.4241654 H
OS 2.8157403 0.4229236
OS 2.8104478 0.4193873
OS 2.8069115 0.4140948
OS 2.8056697 0.4078519
OS 2.8069115 0.401609
OS 2.8104478 0.3963165
OS 2.8157403 0.3927802
OS 2.8219832 0.3915384
OS 2.8282261 0.3927802
OS 2.8335186 0.3963165
OS 2.8345973 0.3979309
OS 2.8352825 0.3981275
OS 2.8403819 0.3975883
OS 2.8427953 0.3939764
OS 2.8480878 0.3904401
OS 2.8543307 0.3891983
OS 2.8605736 0.3904401
OS 2.8658661 0.3939764
OS 2.8694024 0.3992689
OS 2.8706442 0.4055118
OS 2.8694024 0.4117547
OS 2.8658661 0.4170472
OS 2.8605736 0.4205835
OS 2.8543307 0.4218253
OS 2.8480878 0.4205835
OS 2.8427953 0.4170472
OS 2.8417166 0.4154328
OS 2.8410314 0.4152362
OS 2.835932 0.4157754
OS 2.8335186 0.4193873
OS 2.8282261 0.4229236
OS 2.8219832 0.4241654
OE
OB 2.7047244 0.4218253 H
OS 2.6984815 0.4205835
OS 2.693189 0.4170472
OS 2.6896527 0.4117547
OS 2.6884109 0.4055118
OS 2.6896527 0.3992689
OS 2.693189 0.3939764
OS 2.6984815 0.3904401
OS 2.7047244 0.3891983
OS 2.7109673 0.3904401
OS 2.7162598 0.3939764
OS 2.7197961 0.3992689
OS 2.7210379 0.4055118
OS 2.7197961 0.4117547
OS 2.7162598 0.4170472
OS 2.7109673 0.4205835
OS 2.7047244 0.4218253
OE
OB 2.6653543 0.4218253 H
OS 2.6591114 0.4205835
OS 2.6538189 0.4170472
OS 2.6502826 0.4117547
OS 2.6490408 0.4055118
OS 2.6502826 0.3992689
OS 2.6538189 0.3939764
OS 2.6591114 0.3904401
OS 2.6653543 0.3891983
OS 2.6715972 0.3904401
OS 2.6768897 0.3939764
OS 2.680426 0.3992689
OS 2.6816678 0.4055118
OS 2.680426 0.4117547
OS 2.6768897 0.4170472
OS 2.6715972 0.4205835
OS 2.6653543 0.4218253
OE
OB 2.511811 0.4218253 H
OS 2.5055681 0.4205835
OS 2.5002756 0.4170472
OS 2.4967393 0.4117547
OS 2.4954975 0.4055118
OS 2.4967393 0.3992689
OS 2.5002756 0.3939764
OS 2.5055681 0.3904401
OS 2.511811 0.3891983
OS 2.5180539 0.3904401
OS 2.5233464 0.3939764
OS 2.5268827 0.3992689
OS 2.5281245 0.4055118
OS 2.5268827 0.4117547
OS 2.5233464 0.4170472
OS 2.5180539 0.4205835
OS 2.511811 0.4218253
OE
OB 2.3897638 0.4218253 H
OS 2.3835209 0.4205835
OS 2.3782284 0.4170472
OS 2.3746921 0.4117547
OS 2.3734503 0.4055118
OS 2.3746921 0.3992689
OS 2.3782284 0.3939764
OS 2.3835209 0.3904401
OS 2.3897638 0.3891983
OS 2.3960067 0.3904401
OS 2.4012992 0.3939764
OS 2.4048355 0.3992689
OS 2.4060773 0.4055118
OS 2.4048355 0.4117547
OS 2.4012992 0.4170472
OS 2.3960067 0.4205835
OS 2.3897638 0.4218253
OE
OB 2.3503937 0.4218253 H
OS 2.3441508 0.4205835
OS 2.3388583 0.4170472
OS 2.335322 0.4117547
OS 2.3340802 0.4055118
OS 2.335322 0.3992689
OS 2.3388583 0.3939764
OS 2.3441508 0.3904401
OS 2.3503937 0.3891983
OS 2.3566366 0.3904401
OS 2.3619291 0.3939764
OS 2.3654654 0.3992689
OS 2.3667072 0.4055118
OS 2.3654654 0.4117547
OS 2.3619291 0.4170472
OS 2.3566366 0.4205835
OS 2.3503937 0.4218253
OE
OB 1.8720472 0.3037151 H
OS 1.8658043 0.3024733
OS 1.8622047 0.3000681
OS 1.8586051 0.3024733
OS 1.8523622 0.3037151
OS 1.8461193 0.3024733
OS 1.8425197 0.3000681
OS 1.83892 0.3024733
OS 1.8326771 0.3037151
OS 1.8264342 0.3024733
OS 1.8211417 0.298937
OS 1.8176054 0.2936445
OS 1.8163636 0.2874016
OS 1.8176054 0.2811587
OS 1.8211417 0.2758662
OS 1.8229465 0.2746603
OS 1.8229465 0.2686468
OS 1.8211417 0.2674409
OS 1.8176054 0.2621484
OS 1.8163636 0.2559055
OS 1.8176054 0.2496626
OS 1.8211417 0.2443701
OS 1.8264342 0.2408338
OS 1.8326771 0.239592
OS 1.83892 0.2408338
OS 1.8425197 0.243239
OS 1.8461193 0.2408338
OS 1.8523622 0.239592
OS 1.8586051 0.2408338
OS 1.8622047 0.243239
OS 1.8658043 0.2408338
OS 1.8720472 0.239592
OS 1.8782901 0.2408338
OS 1.8835826 0.2443701
OS 1.8871189 0.2496626
OS 1.8883607 0.2559055
OS 1.8871189 0.2621484
OS 1.8835826 0.2674409
OS 1.8817778 0.2686468
OS 1.8817778 0.2746603
OS 1.8835826 0.2758662
OS 1.8871189 0.2811587
OS 1.8883607 0.2874016
OS 1.8871189 0.2936445
OS 1.8835826 0.298937
OS 1.8782901 0.3024733
OS 1.8720472 0.3037151
OE
OB 2.1122047 0.3037151 H
OS 2.1059618 0.3024733
OS 2.1006693 0.298937
OS 2.097133 0.2936445
OS 2.0970371 0.2931626
OS 2.0919392 0.2931626
OS 2.0918433 0.2936445
OS 2.088307 0.298937
OS 2.0830145 0.3024733
OS 2.0767716 0.3037151
OS 2.0705287 0.3024733
OS 2.0652362 0.298937
OS 2.0616999 0.2936445
OS 2.0604581 0.2874016
OS 2.0616999 0.2811587
OS 2.0652362 0.2758662
OS 2.067041 0.2746603
OS 2.067041 0.2686468
OS 2.0652362 0.2674409
OS 2.0616999 0.2621484
OS 2.0604581 0.2559055
OS 2.0616999 0.2496626
OS 2.0652362 0.2443701
OS 2.0705287 0.2408338
OS 2.0767716 0.239592
OS 2.0830145 0.2408338
OS 2.088307 0.2443701
OS 2.0918433 0.2496626
OS 2.0919392 0.2501445
OS 2.0970371 0.2501445
OS 2.097133 0.2496626
OS 2.1006693 0.2443701
OS 2.1059618 0.2408338
OS 2.1122047 0.239592
OS 2.1184476 0.2408338
OS 2.1237401 0.2443701
OS 2.1272764 0.2496626
OS 2.1285182 0.2559055
OS 2.1272764 0.2621484
OS 2.1237401 0.2674409
OS 2.1219353 0.2686468
OS 2.1219353 0.2746603
OS 2.1237401 0.2758662
OS 2.1272764 0.2811587
OS 2.1285182 0.2874016
OS 2.1272764 0.2936445
OS 2.1237401 0.298937
OS 2.1184476 0.3024733
OS 2.1122047 0.3037151
OE
OB 2.6102362 0.2958411 H
OS 2.6039933 0.2945993
OS 2.5987008 0.291063
OS 2.5974949 0.2892583
OS 2.5914815 0.2892583
OS 2.5902756 0.291063
OS 2.5849831 0.2945993
OS 2.5787402 0.2958411
OS 2.5724973 0.2945993
OS 2.5672048 0.291063
OS 2.5636685 0.2857705
OS 2.5624267 0.2795276
OS 2.5636685 0.2732847
OS 2.5672048 0.2679922
OS 2.5724973 0.2644559
OS 2.5787402 0.2632141
OS 2.5849831 0.2644559
OS 2.5902756 0.2679922
OS 2.5914815 0.2697969
OS 2.5974949 0.2697969
OS 2.5987008 0.2679922
OS 2.6039933 0.2644559
OS 2.6102362 0.2632141
OS 2.6164791 0.2644559
OS 2.6217716 0.2679922
OS 2.6253079 0.2732847
OS 2.6265497 0.2795276
OS 2.6253079 0.2857705
OS 2.6217716 0.291063
OS 2.6164791 0.2945993
OS 2.6102362 0.2958411
OE
OB 2.4448819 0.2958411 H
OS 2.438639 0.2945993
OS 2.4333465 0.291063
OS 2.4321406 0.2892582
OS 2.4261271 0.2892582
OS 2.4249212 0.291063
OS 2.4196287 0.2945993
OS 2.4133858 0.2958411
OS 2.4071429 0.2945993
OS 2.4018504 0.291063
OS 2.3983141 0.2857705
OS 2.3970723 0.2795276
OS 2.3983141 0.2732847
OS 2.4018504 0.2679922
OS 2.4071429 0.2644559
OS 2.4133858 0.2632141
OS 2.4196287 0.2644559
OS 2.4249212 0.2679922
OS 2.4261271 0.269797
OS 2.4321406 0.269797
OS 2.4333465 0.2679922
OS 2.438639 0.2644559
OS 2.4448819 0.2632141
OS 2.4511248 0.2644559
OS 2.4564173 0.2679922
OS 2.4599536 0.2732847
OS 2.4611954 0.2795276
OS 2.4599536 0.2857705
OS 2.4564173 0.291063
OS 2.4511248 0.2945993
OS 2.4448819 0.2958411
OE
OB 2.9370079 0.2958411 H
OS 2.930765 0.2945993
OS 2.9254725 0.291063
OS 2.9242523 0.2892367
OS 2.9182388 0.2892367
OS 2.91703 0.2910458
OS 2.9117375 0.2945821
OS 2.9054946 0.2958239
OS 2.8992517 0.2945821
OS 2.8939592 0.2910458
OS 2.8904229 0.2857533
OS 2.8891811 0.2795104
OS 2.8904229 0.2732675
OS 2.8939592 0.267975
OS 2.8992517 0.2644387
OS 2.9054946 0.2631969
OS 2.9117375 0.2644387
OS 2.91703 0.267975
OS 2.9182502 0.2698013
OS 2.9242637 0.2698013
OS 2.9254725 0.2679922
OS 2.930765 0.2644559
OS 2.9370079 0.2632141
OS 2.9432508 0.2644559
OS 2.9485433 0.2679922
OS 2.9520796 0.2732847
OS 2.9533214 0.2795276
OS 2.9520796 0.2857705
OS 2.9485433 0.291063
OS 2.9432508 0.2945993
OS 2.9370079 0.2958411
OE
OB 2.74882 0.2986255 H
OS 2.7425771 0.2973837
OS 2.7372846 0.2938474
OS 2.7337483 0.2885549
OS 2.7325065 0.282312
OS 2.7337483 0.2760691
OS 2.7372846 0.2707766
OS 2.7425771 0.2672403
OS 2.74882 0.2659985
OS 2.7550629 0.2672403
OS 2.7603553 0.2707766
OS 2.7662503 0.2705991
OS 2.7679922 0.2679922
OS 2.7732847 0.2644559
OS 2.7795276 0.2632141
OS 2.7857705 0.2644559
OS 2.791063 0.2679922
OS 2.7945993 0.2732847
OS 2.7958411 0.2795276
OS 2.7945993 0.2857705
OS 2.791063 0.291063
OS 2.7857705 0.2945993
OS 2.7795276 0.2958411
OS 2.7732847 0.2945993
OS 2.7679923 0.291063
OS 2.7620973 0.2912405
OS 2.7603554 0.2938474
OS 2.7550629 0.2973837
OS 2.74882 0.2986255
OE
OB 2.1515748 0.3037151 H
OS 2.1453319 0.3024733
OS 2.1400394 0.298937
OS 2.1365031 0.2936445
OS 2.1352613 0.2874016
OS 2.1365031 0.2811587
OS 2.1400394 0.2758662
OS 2.1418442 0.2746603
OS 2.1418442 0.2686468
OS 2.1400394 0.2674409
OS 2.1365031 0.2621484
OS 2.1352613 0.2559055
OS 2.1365031 0.2496626
OS 2.1400394 0.2443701
OS 2.1453319 0.2408338
OS 2.1515748 0.239592
OS 2.1578177 0.2408338
OS 2.1631102 0.2443701
OS 2.1666465 0.2496626
OS 2.1678883 0.2559055
OS 2.1666465 0.2621484
OS 2.1631102 0.2674409
OS 2.1613054 0.2686468
OS 2.1613054 0.2746603
OS 2.1631102 0.2758662
OS 2.1666465 0.2811587
OS 2.1678883 0.2874016
OS 2.1666465 0.2936445
OS 2.1631102 0.298937
OS 2.1578177 0.3024733
OS 2.1515748 0.3037151
OE
OB 0.2854331 0.5015215 H
OS 0.264563 0.499879
OS 0.2442067 0.4949919
OS 0.2248656 0.4869805
OS 0.2070159 0.4760422
OS 0.1910971 0.4624462
OS 0.1775011 0.4465274
OS 0.1665628 0.4286777
OS 0.1585514 0.4093366
OS 0.1536643 0.3889803
OS 0.1520218 0.3681102
OS 0.1536643 0.3472401
OS 0.1585514 0.3268838
OS 0.1665628 0.3075427
OS 0.1775011 0.289693
OS 0.1910971 0.2737742
OS 0.2070159 0.2601782
OS 0.2248656 0.2492399
OS 0.2442067 0.2412285
OS 0.264563 0.2363414
OS 0.2854331 0.2346989
OS 0.3063032 0.2363414
OS 0.3266595 0.2412285
OS 0.3460006 0.2492399
OS 0.3638503 0.2601782
OS 0.3797691 0.2737742
OS 0.3933651 0.289693
OS 0.4043034 0.3075427
OS 0.4123148 0.3268838
OS 0.4172019 0.3472401
OS 0.4188444 0.3681102
OS 0.4172019 0.3889803
OS 0.4123148 0.4093366
OS 0.4043034 0.4286777
OS 0.3933651 0.4465274
OS 0.3797691 0.4624462
OS 0.3638503 0.4760422
OS 0.3460006 0.4869805
OS 0.3266595 0.4949919
OS 0.3063032 0.499879
OS 0.2854331 0.5015215
OE
SE
P 0.149508 2.830047 9 P 0 0 ;0=7,1=1
P 0.149508 3.853669 9 P 0 0 ;0=7,1=1
P 0.6538425 1.551063 8 P 0 0 ;0=6,1=1
P 0.6539669 2.5938902 8 P 0 0 ;0=6,1=1
P 0.6548425 0.790063 8 P 0 0 ;0=6,1=1
P 0.6548425 1.314063 8 P 0 0 ;0=6,1=1
P 0.6548425 1.839063 8 P 0 0 ;0=6,1=1
P 0.6548425 2.073063 8 P 0 0 ;0=6,1=1
P 0.6548425 2.365063 8 P 0 0 ;0=6,1=1
P 0.6558425 1.028063 8 P 0 0 ;0=6,1=1
P 0.9370078 2.3179133 8 P 0 0 ;0=6,1=1
P 1.2428425 1.472063 8 P 0 0 ;0=6,1=1
P 1.2488425 2.000063 8 P 0 0 ;0=6,1=1
P 1.2568425 0.942063 8 P 0 0 ;0=6,1=1
P 1.2618425 2.482063 8 P 0 0 ;0=6,1=1
P 1.6708425 1.595063 8 P 0 0 ;0=6,1=1
P 1.6708425 1.694063 8 P 0 0 ;0=6,1=1
P 1.6718425 1.399063 8 P 0 0 ;0=6,1=1
P 1.6718425 1.497063 8 P 0 0 ;0=6,1=1
P 1.6718425 1.792063 8 P 0 0 ;0=6,1=1
P 1.6748425 1.989063 8 P 0 0 ;0=6,1=1
P 1.6758425 1.891063 8 P 0 0 ;0=6,1=1
P 1.6918425 4.079063 8 P 0 0 ;0=6,1=1
P 1.7148425 1.595063 8 P 0 0 ;0=6,1=1
P 1.7168425 1.399063 8 P 0 0 ;0=6,1=1
P 1.7188425 1.497063 8 P 0 0 ;0=6,1=1
P 1.7188425 1.792063 8 P 0 0 ;0=6,1=1
P 1.7218425 1.694063 8 P 0 0 ;0=6,1=1
P 1.7218425 1.890063 8 P 0 0 ;0=6,1=1
P 1.7218425 1.989063 8 P 0 0 ;0=6,1=1
P 1.7268425 4.329374 8 P 0 0 ;0=6,1=1
P 1.7498425 4.110063 8 P 0 0 ;0=6,1=1
P 1.7888425 4.329374 8 P 0 0 ;0=6,1=1
P 1.9161425 0.244763 8 P 0 0 ;0=6,1=1
P 2.0348425 0.246063 8 P 0 0 ;0=6,1=1
P 2.1398425 3.738063 8 P 0 0 ;0=6,1=1
P 2.2538425 2.279063 8 P 0 0 ;0=6,1=1
P 2.2588425 3.741063 8 P 0 0 ;0=6,1=1
P 2.2908425 4.217063 8 P 0 0 ;0=6,1=1
P 2.3098425 0.246063 8 P 0 0 ;0=6,1=1
P 2.3114125 1.0900094 8 P 0 0 ;0=6,1=1
P 2.3118425 0.934063 8 P 0 0 ;0=6,1=1
P 2.3215354 2.586063 8 P 0 0 ;0=6,1=1
P 2.3215354 3.361063 8 P 0 0 ;0=6,1=1
P 2.4048425 2.412063 8 P 0 0 ;0=6,1=1
P 2.4098325 0.932053 8 P 0 0 ;0=6,1=1
P 2.4098325 1.088053 8 P 0 0 ;0=6,1=1
P 2.4098425 2.579063 8 P 0 0 ;0=6,1=1
P 2.4138425 3.295063 8 P 0 0 ;0=6,1=1
P 2.4192759 2.7886295 8 P 0 0 ;0=6,1=1
P 2.4470546 0.2425914 8 P 0 0 ;0=6,1=1
P 2.4738425 2.980063 8 P 0 0 ;0=6,1=1
P 2.4758425 2.456063 8 P 0 0 ;0=6,1=1
P 2.4888425 2.413063 8 P 0 0 ;0=6,1=1
P 2.5082625 0.931483 8 P 0 0 ;0=6,1=1
P 2.5088425 1.090063 8 P 0 0 ;0=6,1=1
P 2.531398 2.830047 9 P 0 0 ;0=7,1=1
P 2.531398 3.853669 9 P 0 0 ;0=7,1=1
P 2.5460625 0.244843 8 P 0 0 ;0=6,1=1
P 2.5818425 2.308063 8 P 0 0 ;0=6,1=1
P 2.5868425 2.569063 8 P 0 0 ;0=6,1=1
P 2.6066825 0.931903 8 P 0 0 ;0=6,1=1
P 2.6068425 1.091063 8 P 0 0 ;0=6,1=1
P 2.6318425 2.876063 8 P 0 0 ;0=6,1=1
P 2.636874 0.2479055 8 P 0 0 ;0=6,1=1
P 2.6658425 1.092063 8 P 0 0 ;0=6,1=1
P 2.6748425 3.501063 8 P 0 0 ;0=6,1=1
P 2.6858425 2.311063 8 P 0 0 ;0=6,1=1
P 2.6858425 2.568063 8 P 0 0 ;0=6,1=1
P 2.7244825 1.093063 8 P 0 0 ;0=6,1=1
P 2.7248425 3.521063 8 P 0 0 ;0=6,1=1
P 2.7248425 3.729063 8 P 0 0 ;0=6,1=1
P 2.7838425 2.429063 8 P 0 0 ;0=6,1=1
P 2.7838425 2.568063 8 P 0 0 ;0=6,1=1
P 2.7841625 1.094063 8 P 0 0 ;0=6,1=1
P 2.7999951 0.2519685 8 P 0 0 ;0=6,1=1
P 2.8428425 1.095063 8 P 0 0 ;0=6,1=1
P 2.8608425 3.787063 8 P 0 0 ;0=6,1=1
P 2.8718425 2.297063 8 P 0 0 ;0=6,1=1
P 2.8782843 0.2495967 8 P 0 0 ;0=6,1=1
P 2.8818425 2.566063 8 P 0 0 ;0=6,1=1
P 2.8888425 4.221063 8 P 0 0 ;0=6,1=1
P 2.9018425 1.095063 8 P 0 0 ;0=6,1=1
P 2.9338425 0.953063 8 P 0 0 ;0=6,1=1
P 2.9574751 0.2519685 8 P 0 0 ;0=6,1=1
P 3.0974409 0.2519685 8 P 0 0 ;0=6,1=1
P 3.1830708 3.1358268 8 P 0 0 ;0=6,1=1
P 3.2698425 3.788063 8 P 0 0 ;0=6,1=1
P 3.277559 2.9635827 8 P 0 0 ;0=6,1=1
P 3.3308425 3.301063 8 P 0 0 ;0=6,1=1
P 3.3708425 2.888063 8 P 0 0 ;0=6,1=1
P 3.3958425 4.222063 8 P 0 0 ;0=6,1=1
P 3.4068425 1.461063 8 P 0 0 ;0=6,1=1
P 3.4108425 1.7136509 8 P 0 0 ;0=6,1=1
P 3.4138425 1.573063 8 P 0 0 ;0=6,1=1
P 3.4144661 1.805063 8 P 0 0 ;0=6,1=1
P 3.5318425 3.660063 8 P 0 0 ;0=6,1=1
P 3.5498425 1.413063 8 P 0 0 ;0=6,1=1
P 3.5548425 1.841063 8 P 0 0 ;0=6,1=1
P 3.5548425 1.941063 8 P 0 0 ;0=6,1=1
P 3.5548425 1.991063 8 P 0 0 ;0=6,1=1
P 3.5908425 1.662063 8 P 0 0 ;0=6,1=1
P 3.5948425 1.514063 8 P 0 0 ;0=6,1=1
P 3.6038425 0.682063 8 P 0 0 ;0=6,1=1
P 3.6428425 0.636063 8 P 0 0 ;0=6,1=1
P 3.7178425 3.072063 8 P 0 0 ;0=6,1=1
P 3.7188425 1.713063 8 P 0 0 ;0=6,1=1
P 3.7198425 1.921063 8 P 0 0 ;0=6,1=1
P 3.7198425 1.996063 8 P 0 0 ;0=6,1=1
P 3.7328425 1.418063 8 P 0 0 ;0=6,1=1
P 3.7448425 3.342063 8 P 0 0 ;0=6,1=1
P 3.7778425 4.023063 8 P 0 0 ;0=6,1=1
P 3.8308425 3.762063 8 P 0 0 ;0=6,1=1
P 3.8808425 3.109063 8 P 0 0 ;0=6,1=1
P 3.9608425 2.724063 8 P 0 0 ;0=6,1=1
P 3.9688425 1.671063 8 P 0 0 ;0=6,1=1
P 3.9968425 1.711063 8 P 0 0 ;0=6,1=1
P 4.0398425 3.784063 8 P 0 0 ;0=6,1=1
P 4.0648425 2.722063 8 P 0 0 ;0=6,1=1
P 4.0688425 3.135063 8 P 0 0 ;0=6,1=1
P 4.0858425 3.892063 8 P 0 0 ;0=6,1=1
P 4.1148425 3.135063 8 P 0 0 ;0=6,1=1
P 4.1203866 3.5941508 8 P 0 0 ;0=6,1=1
P 4.1318425 1.686063 8 P 0 0 ;0=6,1=1
P 4.1528425 3.135063 8 P 0 0 ;0=6,1=1
P 4.1948425 3.884063 8 P 0 0 ;0=6,1=1
P 4.2088425 3.135063 8 P 0 0 ;0=6,1=1
P 4.2348425 2.725063 8 P 0 0 ;0=6,1=1
P 4.2728425 3.135063 8 P 0 0 ;0=6,1=1
P 4.3338425 3.135063 8 P 0 0 ;0=6,1=1
P 4.3398425 2.725063 8 P 0 0 ;0=6,1=1
P 4.3878425 4.206063 8 P 0 0 ;0=6,1=1
P 4.4318425 3.135063 8 P 0 0 ;0=6,1=1
P 4.4778425 3.135063 8 P 0 0 ;0=6,1=1
P 4.9108425 4.203063 8 P 0 0 ;0=6,1=1
P 5.6768425 3.546063 8 P 0 0 ;0=6,1=1
P 5.7338425 3.556063 8 P 0 0 ;0=6,1=1
P 6.0048425 2.434063 8 P 0 0 ;0=6,1=1
P 6.0488425 2.171063 8 P 0 0 ;0=6,1=1
P 6.253937 2.9094488 8 P 0 0 ;0=6,1=1
P 6.2748425 2.391063 8 P 0 0 ;0=6,1=1
P 6.3720472 2.9094488 8 P 0 0 ;0=6,1=1
P 6.3958425 2.111063 8 P 0 0 ;0=6,1=1
P 6.3968425 2.556063 8 P 0 0 ;0=6,1=1
P 6.3978425 2.501063 8 P 0 0 ;0=6,1=1
P 6.3978425 2.610063 8 P 0 0 ;0=6,1=1
P 6.3988425 2.453063 8 P 0 0 ;0=6,1=1
P 6.3988425 2.657063 8 P 0 0 ;0=6,1=1
P 6.4568425 3.009063 8 P 0 0 ;0=6,1=1
P 6.4768425 3.231063 8 P 0 0 ;0=6,1=1
P 6.5488425 1.531063 8 P 0 0 ;0=6,1=1
P 6.6018425 1.777063 8 P 0 0 ;0=6,1=1
P 6.6028425 1.612063 8 P 0 0 ;0=6,1=1
P 6.6028425 1.672063 8 P 0 0 ;0=6,1=1
P 6.6028425 1.722063 8 P 0 0 ;0=6,1=1
P 6.6078425 2.176063 8 P 0 0 ;0=6,1=1
P 6.6268425 3.032063 8 P 0 0 ;0=6,1=1
P 6.6288425 1.372063 8 P 0 0 ;0=6,1=1
P 6.6476378 3.1299213 8 P 0 0 ;0=6,1=1
P 6.6488425 3.341063 8 P 0 0 ;0=6,1=1
P 6.6858425 1.828063 8 P 0 0 ;0=6,1=1
P 6.6998425 1.881063 8 P 0 0 ;0=6,1=1
P 6.9498425 2.095063 8 P 0 0 ;0=6,1=1
P 6.9744094 1.9399606 8 P 0 0 ;0=6,1=1

### steps/pcb/layers/top/features
#Layer_Physical_Order=1
#Layer_Color=255
#
#Feature symbol names
#
$0 r8
$1 r5
$2 r20
$3 oval78.7402x23.622
$4 rect39.3701x74.8031
$5 rect70.8661x74.8031
$6 rect55.9055x61.0236
$7 rect17.7165x54.3307
$8 rect64.9606x51.1811
$9 rect78.7402x98.4252
$10 rect19.685x90.5512
$11 rect41.3386x39.3701
$12 rect86.6142x41.3386
$13 rect19.685x35.4331
$14 oval57.0866x17.7165
$15 rect77.5591x22.4409
$16 rect25.5906x41.3386
$17 rect51.1811x74.8031
$18 rect39.3701x70.8661
$19 rect39.3701x90.5512
$20 rect41.3386x45.2756
$21 rect27.5591x45.2756
$22 rect53.1496x27.5591
$23 rect50x200
$24 rect57.0866x37.4016
$25 rect28.3465x39.3701
$26 rect25.5906x23.622
$27 rect28x165
$28 rect28x126
$29 rect31.4961x66.9291
$30 rect70.8661x9.8425
$31 rect26.5748x9.8425
$32 rect9.8425x22.6378
$33 rect27.5591x35.4331
$34 rect38.5827x34.252
$35 rect212.5984x114.1732
$36 rect165.3543x125.9843
$37 rect96.4567x124.0157
$38 rect33.4646x39.3701
$39 rect57.0866x45.2756
$40 rect37.4016x39.3701
$41 rect25.1969x26.7717
$42 rect10.8268x9.8425
$43 rect9.8425x10.8268
$44 rect61.02x9.84
$45 rect66.93x53.15
$46 rect9.84x61.02
$47 rect53.15x66.93
$48 rect45.2756x57.0866
$49 rect26.7717x25.1969
$50 rect39.3701x37.4016
$51 rect39.3701x33.4646
$52 rect39.3701x28.3465
$53 rect23.622x25.5906
$54 rect82.874x44.0945
$55 rect35.4331x27.5591
$56 r10
$57 r6
$58 r9
$59 rect110.4323x66.9291
$60 rect105.315x67.9134
$61 r3.937
$62 r1
$63 r31.4961
$64 r65.9843
$65 r61.0236
$66 s61.0236
$67 r75
$68 r98.4252
$69 oval88.5827x177.1654
$70 oval177.1654x88.5827
$71 oval196.8504x98.4252
$72 r112
$73 r120
$74 r21.66
$75 r55
$76 s55
$77 r50
$78 r250
$79 r16
$80 r200

#
#Feature attribute names
#
@0 .geometry
@1 .pad_usage
@2 .smd

#
#Feature attribute text strings
#
&0 SMD_OvalX78.7402Y23.6220
&1 SMD_RectX39.3701Y74.8031
&2 SMD_RectX70.8661Y74.8031
&3 SMD_RectX55.9055Y61.0236
&4 SMD_RectX17.7165Y54.3307
&5 SMD_RectX64.9606Y51.1811
&6 SMD_RectX78.7402Y98.4252
&7 SMD_RectX19.6850Y90.5512
&8 SMD_RectX41.3386Y39.3701
&9 SMD_RectX86.6142Y41.3386
&10 SMD_RectX19.6850Y35.4331
&11 SMD_OvalX57.0866Y17.7165
&12 SMD_RectX77.5591Y22.4409
&13 SMD_RectX25.5906Y41.3386
&14 SMD_RectX51.1811Y74.8031
&15 SMD_RectX39.3701Y70.8661
&16 SMD_RectX39.3701Y90.5512
&17 SMD_RectX41.3386Y45.2756
&18 SMD_RectX27.5591Y45.2756
&19 SMD_RectX53.1496Y27.5591
&20 SMD_RectX50.0000Y200.0000
&21 SMD_RectX57.0866Y37.4016
&22 SMD_RectX28.3465Y39.3701
&23 SMD_RectX25.5906Y23.6220
&24 SMD_RectX28.0000Y165.0000
&25 SMD_RectX28.0000Y126.0000
&26 SMD_RectX31.4961Y66.9291
&27 SMD_RectX70.8661Y9.8425
&28 SMD_RectX26.5748Y9.8425
&29 SMD_RectX9.8425Y22.6378
&30 SMD_RectX27.5591Y35.4331
&31 SMD_RectX38.5827Y34.2520
&32 SMD_RectX212.5984Y114.1732
&33 SMD_RectX165.3543Y125.9843
&34 SMD_RectX96.4567Y124.0157
&35 SMD_RectX33.4646Y39.3701
&36 SMD_RectX57.0866Y45.2756
&37 SMD_RectX37.4016Y39.3701
&38 SMD_RectX25.1969Y26.7717
&39 SMD_RectX10.8268Y9.8425
&40 SMD_RectX9.8425Y10.8268
&41 SMD_RectX61.0200Y9.8400
&42 SMD_RectX66.9300Y53.1500
&43 SMD_RectX9.8400Y61.0200
&44 SMD_RectX53.1500Y66.9300
&45 SMD_RectX45.2756Y57.0866
&46 SMD_RectX26.7717Y25.1969
&47 SMD_RectX39.3701Y37.4016
&48 SMD_RectX39.3701Y33.4646
&49 SMD_RectX39.3701Y28.3465
&50 SMD_RectX23.6220Y25.5906
&51 SMD_RectX82.8740Y44.0945
&52 SMD_RectX35.4331Y27.5591
&53 Pad_Simple_X31.4961Y31.4961H35.4331C75.4331
&54 Pad_Simple_X65.9843Y65.9843H65.9843C105.9843
&55 Pad_Simple_X61.0236Y61.0236H41.3386C81.3386
&56 Pad_Simple_X75.0000Y75.0000H50.0000C90.0000
&57 Pad_Simple_X98.4252Y98.4252H64.9606C104.9606
&58 Pad_Simple_X88.5827Y177.1654H39.3701C79.3701
&59 Pad_Simple_X177.1654Y88.5827H39.3701C79.3701
&60 Pad_Simple_X196.8504Y98.4252H39.3701C79.3701
&61 Pad_Simple_X112.0000Y112.0000H60.0000C100.0000
&62 Pad_Simple_X120.0000Y120.0000H68.0000C108.0000
&63 Pad_Simple_X21.6600Y21.6600H21.6600C61.6600
&64 Pad_Simple_X55.0000Y55.0000H30.0000C70.0000
&65 Pad_Simple_X50.0000Y50.0000H118.1102C158.1102
&66 Pad_Simple_X98.4252Y98.4252H70.8661C110.8661
&67 Pad_Complex_X50.0000Y50.0000H118.1102C158.1102
&68 Pad_Simple_X250.0000Y250.0000H125.1969C165.1969
&69 VIA_RoundD16.0000H8.0000C48.0000
&70 VIA_RoundD200.0000H125.9843C165.9843

#
#Layer features
#
A 1.7712204 0.4310709 1.6275196 0.4310709 1.69937 0.4310709 61 P 0 N
A 2.4133858 0.2795276 2.3877951 0.2177462 2.4751672 0.2177462 1 P 0 N
A 2.4188425 0.1330565 2.4279525 0.111063 2.449946 0.1330565 1 P 0 N
A 2.4448819 0.2795276 2.4271651 0.2367555 2.487654 0.2367555 1 P 0 N
A 2.4494285 2.7188785 2.4550854 2.7165354 2.4550854 2.7245354 0 P 0 N
A 2.4673225 0.2173067 2.4593435 0.2332909 2.4473222 0.2173066 2 P 0 N
A 2.5758425 0.1342153 2.5854325 0.111063 2.6085848 0.1342153 1 P 0 N
A 2.5846451 0.2652719 2.5787402 0.2795276 2.5644845 0.2652719 1 P 0 N
A 2.6067769 0.8154384 2.5984252 0.7952756 2.6269397 0.7952756 1 P 0 N
A 2.6102362 0.259167 2.6181102 0.2401575 2.6371197 0.259167 1 P 0 N
A 2.6128425 0.139937 2.6248025 0.111063 2.6536765 0.139937 1 P 0 N
A 2.6181102 0.8267717 2.6263725 0.8467187 2.5981632 0.8467187 1 P 0 N
A 2.6220472 0.976378 2.6263725 0.9807033 2.6220472 0.9807033 1 P 0 N
A 2.6240151 0.2259018 2.6181102 0.2401575 2.6038545 0.2259018 1 P 0 N
A 2.6299213 0.8188976 2.6259843 0.8093928 2.6394261 0.8093928 1 P 0 N
A 2.6299213 0.8188976 2.6460525 0.8578418 2.5909771 0.8578418 1 P 0 N
A 2.6460525 0.9799318 2.6496063 0.976378 2.6496063 0.9799318 1 P 0 N
A 2.6792645 0.8288708 2.6653543 0.7952756 2.7128781 0.7952756 1 P 0 N
A 2.6792737 0.82888 2.6792645 0.8288708 2.7128781 0.7952756 1 P 0 N
A 2.6811024 0.8307087 2.6854225 0.8411383 2.6706728 0.8411383 1 P 0 N
A 2.6811024 0.976378 2.6854225 0.9806981 2.6811024 0.9806981 1 P 0 N
A 2.6846784 2.7165354 2.6903352 2.7188785 2.6846783 2.7245357 0 P 0 N
A 2.7007874 0.8307087 2.6929134 0.8116992 2.7197969 0.8116992 1 P 0 N
A 2.7007874 0.8307087 2.7051125 0.8411504 2.6903457 0.8411504 1 P 0 N
A 2.7051125 0.9799269 2.7086614 0.976378 2.7086614 0.9799269 1 P 0 N
A 2.7401575 0.976378 2.7444825 0.980703 2.7401575 0.980703 1 P 0 N
A 2.7402781 0.8190182 2.7322834 0.7997175 2.7595787 0.7997175 1 P 0 N
A 2.7402781 0.8190182 2.7444825 0.8291685 2.7301278 0.8291685 1 P 0 N
A 2.7468579 0.2782484 2.7421251 0.2652683 2.7622908 0.2652683 1 P 0 N
A 2.7468769 0.2782709 2.7477008 0.2796783 2.7430315 0.2814668 1 P 0 N
A 2.7487121 0.2821354 2.7483623 0.2814053 2.7530315 0.2796169 1 P 0 N
A 2.7598425 0.7952756 2.7641625 0.805705 2.7494131 0.805705 1 P 0 N
A 2.7641625 0.979932 2.7677165 0.976378 2.7677165 0.979932 1 P 0 N
A 2.7728425 0.1338532 2.7822825 0.111063 2.8050727 0.1338532 1 P 0 N
A 2.7814951 0.2747776 2.7795276 0.2795276 2.7747776 0.2747776 1 P 0 N
A 2.7818425 0.1121253 2.7822825 0.111063 2.7833448 0.1121253 1 P 0 N
A 2.7992126 0.7952756 2.8035325 0.8057048 2.7887834 0.8057048 1 P 0 N
A 2.7992126 0.976378 2.8035325 0.9806979 2.7992126 0.9806979 1 P 0 N
A 2.8232225 0.8038441 2.8267717 0.7952756 2.8353402 0.8038441 1 P 0 N
A 2.8232225 0.9799272 2.8267717 0.976378 2.8267717 0.9799272 1 P 0 N
A 2.8622047 0.7952756 2.8625925 0.7962118 2.8612685 0.7962118 1 P 0 N
A 2.8822725 0.822866 2.8937008 0.7952756 2.9212912 0.822866 1 P 0 N
A 2.9054946 0.2795104 2.8996051 0.2652676 2.9197718 0.2652676 1 P 0 N
A 2.9055118 0.2795276 2.9054946 0.2795104 2.9197718 0.2652676 1 P 0 N
A 2.9289751 0.1619374 2.9389751 0.1377953 2.9631172 0.1619374 0 P 0 N
A 2.9389751 0.2747784 2.9370079 0.2795276 2.9322587 0.2747784 1 P 0 N
A 2.9746503 0.2247425 2.9697144 0.2378982 2.95465 0.2247424 2 P 0 N
L -0.0001175 0.177913 0.5908825 0.177913 62 P 0
L -0.0004331 0.1781182 0.5901181 0.1781182 61 P 0
L 0.1998425 0.906063 0.5948031 0.906063 0 P 0
L 0.1998425 1.431063 0.5948031 1.431063 0 P 0
L 0.1998425 1.956063 0.5948031 1.956063 0 P 0
L 0.1998425 2.481063 0.5948031 2.481063 0 P 0
L 0.5901181 0.1781182 0.5901181 0.5029213 61 P 0
L 0.5901181 0.5029213 1.312559 0.5029213 61 P 0
L 0.5908825 0.177913 0.5908825 0.502913 62 P 0
L 0.5948031 0.906063 0.9326378 0.906063 0 P 0
L 0.5948031 1.431063 0.9326378 1.431063 0 P 0
L 0.5948031 1.956063 0.9326378 1.956063 0 P 0
L 0.5948031 2.481063 0.9326378 2.481063 0 P 0
L 0.6389685 4.012937 0.6389685 4.0388976 0 P 0
L 0.6389685 4.012937 0.8358425 3.816063 0 P 0
L 0.6389685 4.0932283 0.6448425 4.0991023 0 P 0
L 0.6448425 4.0991023 0.6448425 4.1975197 0 P 0
L 0.6448425 4.2546063 0.8465091 4.2546063 2 P 0
L 0.6538425 1.551063 0.6548425 1.550063 56 P 0
L 0.6539669 2.5938902 0.6548425 2.5930146 56 P 0
L 0.6548425 0.790063 0.6548425 0.8479921 56 P 0
L 0.6548425 0.9641339 0.6548425 1.027063 56 P 0
L 0.6548425 1.027063 0.6558425 1.028063 56 P 0
L 0.6548425 1.314063 0.6548425 1.3729921 56 P 0
L 0.6548425 1.4891339 0.6548425 1.550063 56 P 0
L 0.6548425 1.839063 0.6548425 1.8979921 56 P 0
L 0.6548425 2.0141339 0.6548425 2.073063 56 P 0
L 0.6548425 2.365063 0.6548425 2.4229921 56 P 0
L 0.6548425 2.5391339 0.6548425 2.5930146 56 P 0
L 0.8358425 3.816063 2.0048425 3.816063 0 P 0
L 0.8406351 4.0132704 0.8406351 4.0388976 0 P 0
L 0.8406351 4.0132704 1.0178425 3.836063 0 P 0
L 0.8406351 4.0932283 0.8465091 4.0991023 0 P 0
L 0.8465091 4.0991023 0.8465091 4.1925197 0 P 0
L 0.8465091 4.2546063 1.0481757 4.2546063 2 P 0
L 0.9005905 1.7470472 0.9005905 1.9240157 0 P 0
L 0.9005905 1.9240157 0.9326378 1.956063 0 P 0
L 0.9015747 0.7185038 0.9015747 0.8749999 0 P 0
L 0.9015747 0.8749999 0.9326378 0.906063 0 P 0
L 0.9045275 1.2244094 0.9045275 1.4029527 0 P 0
L 0.9045275 1.4029527 0.9326378 1.431063 0 P 0
L 0.9084645 2.2844487 0.9084645 2.4568897 0 P 0
L 0.9084645 2.4568897 0.9326378 2.481063 0 P 0
L 0.9326378 0.906063 1.0048425 0.906063 0 P 0
L 0.9326378 1.431063 1.0078425 1.431063 0 P 0
L 0.9326378 1.956063 1.0098425 1.956063 0 P 0
L 0.9326378 2.481063 1.0208425 2.481063 0 P 0
L 0.9596456 1.7431102 0.9596456 1.7470472 0 P 0
L 0.9596456 1.7431102 0.9837054 1.7190504 0 P 0
L 0.9606298 0.7145668 0.9606298 0.7185038 0 P 0
L 0.9606298 0.7145668 0.9881887 0.6870079 0 P 0
L 0.9635826 1.2204724 0.9635826 1.2244094 0 P 0
L 0.9635826 1.2204724 0.996063 1.187992 0 P 0
L 0.9675196 2.2805117 0.9675196 2.2844487 0 P 0
L 0.9675196 2.2805117 0.9904646 2.2575667 0 P 0
L 0.9837054 1.7190504 0.9866583 1.7190504 0 P 0
L 0.9866583 1.7190504 0.988189 1.7175197 0 P 0
L 0.9881887 0.6870079 0.9901575 0.6870079 0 P 0
L 0.9904646 2.2575667 0.995305 2.2575667 0 P 0
L 0.995305 2.2575667 0.9968357 2.256036 0 P 0
L 0.996063 1.1870079 0.996063 1.187992 0 P 0
L 1.0078425 1.431063 1.0088425 1.430063 0 P 0
L 1.0178425 3.836063 2.0298425 3.836063 0 P 0
L 1.0423017 4.0146038 1.0423017 4.0388976 0 P 0
L 1.0423017 4.0146038 1.1858425 3.871063 0 P 0
L 1.0423017 4.0932283 1.0481757 4.0991023 0 P 0
L 1.0481757 4.0991023 1.0481757 4.1925197 0 P 0
L 1.0481757 4.2546063 1.2498423 4.2546063 2 P 0
L 1.1570472 0.906063 1.1930472 0.942063 56 P 0
L 1.1570472 1.431063 1.1980472 1.472063 56 P 0
L 1.1570472 1.956063 1.1570472 1.9568346 56 P 0
L 1.1570472 1.9568346 1.2002756 2.000063 56 P 0
L 1.1570472 2.481063 1.2608425 2.481063 56 P 0
L 1.1858425 3.871063 2.0598425 3.871063 0 P 0
L 1.1930472 0.942063 1.2568425 0.942063 56 P 0
L 1.1980472 1.472063 1.2428425 1.472063 56 P 0
L 1.2002756 2.000063 1.2488425 2.000063 56 P 0
L 1.2439683 4.0159372 1.2439683 4.0388976 0 P 0
L 1.2439683 4.0159372 1.3638425 3.896063 0 P 0
L 1.2439683 4.0932283 1.2498423 4.0991023 0 P 0
L 1.2498423 4.0991023 1.2498423 4.1925197 0 P 0
L 1.2498423 4.2546063 1.2933858 4.2546063 2 P 0
L 1.2608425 2.481063 1.2618425 2.482063 56 P 0
L 1.2933858 4.2546063 1.2948425 4.256063 2 P 0
L 1.312559 0.313945 1.312559 0.5029213 61 P 0
L 1.312559 0.313945 1.6275197 0.313945 61 P 0
L 1.3454724 4.1427166 1.3454724 4.1751969 0 P 0
L 1.3454724 4.1427166 1.3464567 4.1417323 0 P 0
L 1.3464567 3.9783465 1.3484252 3.980315 0 P 0
L 1.3464567 4.0374016 1.3464567 4.0826772 0 P 0
L 1.3464567 4.0374016 1.3562363 4.0471812 0 P 0
L 1.3484252 3.980315 1.4084645 3.980315 0 P 0
L 1.3562363 4.0471812 1.4509213 4.0471812 0 P 0
L 1.3638425 3.896063 2.0848425 3.896063 0 P 0
L 1.4509213 4.0471812 1.4576771 4.053937 0 P 0
L 1.4576771 4.153937 1.4870511 4.124563 0 P 0
L 1.4870511 4.124563 1.631559 4.124563 0 P 0
L 1.5578425 4.229063 1.6018425 4.273063 56 P 0
L 1.5679134 1.2854331 1.5679134 1.3100394 0 P 0
L 1.5679134 1.3100394 1.577547 1.319673 0 P 0
L 1.5682025 2.067703 1.6171125 2.067703 0 P 0
L 1.5698819 4.1712599 1.5698819 4.1732284 0 P 0
L 1.5698819 4.1712599 1.569882 4.1712599 0 P 0
L 1.5698819 4.1732284 1.5943574 4.1977039 0 P 0
L 1.577547 1.319673 1.6171125 1.319673 0 P 0
L 1.5943574 4.1977039 1.6296999 4.1977039 0 P 0
L 1.6018425 4.273063 1.6643465 4.273063 56 P 0
L 1.6171125 1.398413 1.6711925 1.398413 56 P 0
L 1.6171125 1.496843 1.6171925 1.496923 56 P 0
L 1.6171125 1.595263 1.6706425 1.595263 56 P 0
L 1.6171125 1.693693 1.6704725 1.693693 56 P 0
L 1.6171125 1.792113 1.6171625 1.792063 56 P 0
L 1.6171125 1.890543 1.6753225 1.890543 56 P 0
L 1.6171125 1.988963 1.6747425 1.988963 56 P 0
L 1.6171125 2.087393 1.6171125 2.118333 0 P 0
L 1.6171125 2.118333 1.6198425 2.121063 0 P 0
L 1.6171625 1.792063 1.6718425 1.792063 56 P 0
L 1.6171925 1.496923 1.6456646 1.496923 56 P 0
L 1.6275197 0.313945 1.6275197 0.4310709 61 P 0
L 1.6296999 4.1977039 1.631559 4.199563 0 P 0
L 1.631559 4.024563 1.6538733 4.024563 0 P 0
L 1.631559 4.099563 1.6713425 4.099563 56 P 0
L 1.631559 4.149563 1.6334181 4.1477039 0 P 0
L 1.6334181 4.1477039 1.6762016 4.1477039 0 P 0
L 1.6456646 1.496923 1.6458046 1.497063 56 P 0
L 1.6458046 1.497063 1.6718425 1.497063 56 P 0
L 1.6538733 4.024563 1.6587316 4.0197047 0 P 0
L 1.6587316 4.0197047 1.6592008 4.0197047 0 P 0
L 1.6592008 4.0197047 1.7153228 3.9635827 0 P 0
L 1.6643465 4.248559 1.6643465 4.273063 56 P 0
L 1.6643465 4.248559 1.6878425 4.225063 56 P 0
L 1.6704725 1.693693 1.6708425 1.694063 56 P 0
L 1.6706425 1.595263 1.6708425 1.595063 56 P 0
L 1.6711925 1.398413 1.6718425 1.399063 56 P 0
L 1.6713425 4.099563 1.6918425 4.079063 56 P 0
L 1.6747425 1.988963 1.6748425 1.989063 56 P 0
L 1.6753225 1.890543 1.6758425 1.891063 56 P 0
L 1.6762016 4.1477039 1.7743425 4.049563 0 P 0
L 1.6878425 4.225063 1.8538425 4.225063 56 P 0
L 1.7148425 1.595063 1.7150425 1.595263 56 P 0
L 1.7150425 1.595263 1.7765525 1.595263 56 P 0
L 1.7153228 3.9635827 2.2450787 3.9635827 0 P 0
L 1.7168425 1.399063 1.7174925 1.398413 56 P 0
L 1.7174925 1.398413 1.7765525 1.398413 56 P 0
L 1.7188425 1.497063 1.7190625 1.496843 56 P 0
L 1.7188425 1.792063 1.7188925 1.792113 56 P 0
L 1.7188925 1.792113 1.7765525 1.792113 56 P 0
L 1.7190625 1.496843 1.7765525 1.496843 56 P 0
L 1.7198425 1.536063 1.7199175 1.536138 0 P 0
L 1.7199175 1.536138 1.7764775 1.536138 0 P 0
L 1.7218425 1.694063 1.7222125 1.693693 56 P 0
L 1.7218425 1.890063 1.7223225 1.890543 56 P 0
L 1.7218425 1.989063 1.7219425 1.988963 56 P 0
L 1.7219425 1.988963 1.7765525 1.988963 56 P 0
L 1.7222125 1.693693 1.7765525 1.693693 56 P 0
L 1.7223225 1.890543 1.7765525 1.890543 56 P 0
L 1.7268425 4.329374 1.7273386 4.3288779 56 P 0
L 1.7273386 4.273063 1.7273386 4.3288779 56 P 0
L 1.7498425 4.110063 1.7643425 4.124563 56 P 0
L 1.7548425 2.088313 1.7548425 2.126063 0 P 0
L 1.7548425 2.088313 1.7557625 2.087393 0 P 0
L 1.7557625 2.087393 1.7765525 2.087393 0 P 0
L 1.7643425 4.124563 1.8461259 4.124563 56 P 0
L 1.7743425 4.049563 1.8461259 4.049563 0 P 0
L 1.7764775 1.536138 1.7765525 1.536213 0 P 0
L 1.7765525 1.319673 1.7973083 1.319673 0 P 0
L 1.7765525 1.516523 1.8973025 1.516523 0 P 0
L 1.7765525 1.614953 1.8157325 1.614953 0 P 0
L 1.7765525 1.674003 1.8227825 1.674003 0 P 0
L 1.7765525 1.811803 1.8799377 1.811803 0 P 0
L 1.7765525 2.008653 1.7768125 2.008393 57 P 0
L 1.7765525 2.028333 1.7766125 2.028393 57 P 0
L 1.7765525 2.067703 1.8814825 2.067703 0 P 0
L 1.7888425 4.2896299 1.7888425 4.329374 56 P 0
L 1.7888425 4.2896299 1.8024094 4.276063 56 P 0
L 1.7973083 1.319673 1.7982283 1.318753 0 P 0
L 1.7978425 0.355063 2.050063 0.6072835 0 P 0
L 1.7980325 0.111063 1.7980325 0.2399617 2 P 0
L 1.7980325 0.2399617 1.8150702 0.2569994 2 P 0
L 1.7982283 1.3041339 1.7982283 1.318753 0 P 0
L 1.8150702 0.2569994 1.8357789 0.2569994 2 P 0
L 1.8157325 1.614953 1.8938425 1.693063 0 P 0
L 1.8357789 0.2569994 1.8465953 0.2678158 2 P 0
L 1.8374025 0.111063 1.8374025 0.2553758 2 P 0
L 1.8374025 0.2553758 1.8498425 0.2678158 2 P 0
L 1.8461259 4.024563 1.8868543 4.024563 0 P 0
L 1.8461259 4.074563 1.9335078 4.074563 0 P 0
L 1.8461259 4.099563 1.8783425 4.099563 56 P 0
L 1.8465953 0.2678158 1.8498425 0.2678158 2 P 0
L 1.8538425 4.225063 1.8732756 4.2444961 56 P 0
L 1.8732756 4.2444961 1.8732756 4.2701575 56 P 0
L 1.8732756 4.2701575 1.8732756 4.276063 56 P 0
L 1.8732756 4.2701575 1.8732756 4.2816695 56 P 0
L 1.8732756 4.2816695 1.8909134 4.2993073 56 P 0
L 1.8767725 0.111063 1.8767725 0.2408858 2 P 0
L 1.8783425 4.099563 1.9080079 4.1292284 56 P 0
L 1.8791811 4.276063 1.9148425 4.276063 56 P 0
L 1.8799377 1.811803 1.8826777 1.809063 0 P 0
L 1.8814825 2.067703 1.8848425 2.071063 0 P 0
L 1.8868543 4.024563 1.8933543 4.018063 0 P 0
L 1.8933543 4.018063 1.9038425 4.018063 0 P 0
L 1.8973025 1.516523 2.1088425 1.728063 0 P 0
L 1.9080079 4.1292284 1.9338425 4.1292284 56 P 0
L 1.9148425 4.276063 1.9338425 4.257063 56 P 0
L 1.9154925 0.111713 1.9154925 0.244763 2 P 0
L 1.9154925 0.111713 1.9161425 0.111063 2 P 0
L 1.9335078 4.074563 1.9338425 4.0748977 0 P 0
L 1.9338424 4.2570629 1.9338425 4.2570628 56 P 0
L 1.9338425 4.1292284 1.9338425 4.2570628 56 P 0
L 2.0342525 0.111063 2.0342525 0.245473 2 P 0
L 2.0342525 0.245473 2.0348425 0.246063 2 P 0
L 2.0433071 4.057874 2.0864173 4.0147638 0 P 0
L 2.050063 0.6072835 2.503937 0.6072835 0 P 0
L 2.0728351 0.1377953 2.0728351 0.2598431 2 P 0
L 2.0728351 0.2598431 2.0846456 0.2716536 2 P 0
L 2.0736225 0.111063 2.0766957 0.1141362 2 P 0
L 2.0846456 0.2716536 2.1122047 0.2716536 2 P 0
L 2.0864173 4.0147638 2.1515748 4.0147638 0 P 0
L 2.1088425 1.728063 2.1088425 2.540063 0 P 0
L 2.1088425 2.540063 2.1468425 2.578063 0 P 0
L 2.1398425 3.611063 2.1398425 3.6633465 2 P 0
L 2.1398425 3.6633465 2.1398425 3.6641339 2 P 0
L 2.1398425 3.6633465 2.1575591 3.6456299 2 P 0
L 2.1398425 3.6641339 2.1423149 3.6666063 2 P 0
L 2.1398425 3.6979922 2.1398425 3.738063 56 P 0
L 2.1413307 2.6248976 2.1468425 2.6248976 0 P 0
L 2.1460663 4.0763747 2.1460663 4.1037909 0 P 0
L 2.1460663 4.0763747 2.1476378 4.0748032 0 P 0
L 2.1468425 2.578063 2.1468425 2.6248976 0 P 0
L 2.1468425 2.6792283 2.1468425 2.753063 0 P 0
L 2.1476378 4.0748032 2.1515748 4.0748032 0 P 0
L 2.1515748 4.0147638 2.2106299 4.0147638 0 P 0
L 2.1575591 3.6456299 2.2098425 3.6456299 2 P 0
L 2.2098425 3.6456299 2.2115158 3.6439566 2 P 0
L 2.2098425 3.7164961 2.215748 3.7164961 56 P 0
L 2.2115158 3.6439566 2.3281693 3.6439566 2 P 0
L 2.2125984 4.0748032 2.242126 4.0748032 0 P 0
L 2.215748 3.7164961 2.2333858 3.7341339 56 P 0
L 2.2298425 2.586063 2.2326625 2.583243 0 P 0
L 2.2326625 2.518253 2.2326625 2.583243 0 P 0
L 2.2333858 3.7341339 2.2333858 3.7352051 56 P 0
L 2.2333858 3.7352051 2.2392437 3.741063 56 P 0
L 2.2392437 3.741063 2.2588425 3.741063 56 P 0
L 2.242126 4.0748032 2.253937 4.0866142 0 P 0
L 2.2450787 3.9635827 2.3325669 4.0510709 0 P 0
L 2.2523425 2.518253 2.2523425 2.613563 0 P 0
L 2.2538425 2.279063 2.2917125 2.316933 56 P 0
L 2.2548425 3.536063 2.2642755 3.545496 0 P 0
L 2.2642755 3.545496 2.3117952 3.545496 0 P 0
L 2.2720325 2.463873 2.2720325 2.518253 0 P 0
L 2.2813858 4.1703386 2.2813858 4.2076063 56 P 0
L 2.2813858 4.2076063 2.2908425 4.217063 56 P 0
L 2.2917125 2.316933 2.2917125 2.358813 56 P 0
L 2.2917125 2.518253 2.2917925 2.518333 56 P 0
L 2.2917925 2.518333 2.2917925 2.5563201 56 P 0
L 2.2917925 2.5563201 2.3215354 2.586063 56 P 0
L 2.3098425 0.246063 2.3385827 0.246063 2 P 0
L 2.3114025 2.358813 2.3310825 2.358813 0 P 0
L 2.3114125 0.878873 2.3114125 0.933633 56 P 0
L 2.3114125 0.933633 2.3118425 0.934063 56 P 0
L 2.3114125 1.038313 2.3114125 1.0900094 56 P 0
L 2.3114125 1.0900094 2.3128425 1.0914394 56 P 0
L 2.3117952 3.545496 2.3298425 3.5635433 0 P 0
L 2.3215354 3.361063 2.3215354 3.3977559 2 P 0
L 2.3215354 3.3977559 2.3298425 3.406063 2 P 0
L 2.3281693 3.6439566 2.3298425 3.6422834 2 P 0
L 2.3298425 3.4848031 2.3335826 3.481063 0 P 0
L 2.3308425 2.215063 2.3310825 2.215303 0 P 0
L 2.3310825 2.215303 2.3310825 2.358813 0 P 0
L 2.3325669 4.0510709 2.3325669 4.1703386 0 P 0
L 2.3335826 3.481063 2.3898425 3.481063 0 P 0
L 2.3385827 0.246063 2.3475643 0.2370814 2 P 0
L 2.3475643 0.1127112 2.3475643 0.2370814 2 P 0
L 2.3475643 0.1127112 2.3492125 0.111063 2 P 0
L 2.3507725 2.518253 2.3507725 2.6765599 0 P 0
L 2.3507725 2.6765599 2.394685 2.7204724 0 P 0
L 2.3533464 4.0177165 2.3581575 4.0225276 0 P 0
L 2.3581575 4.0225276 2.3581575 4.1703386 0 P 0
L 2.378937 2.7893701 2.378937 2.8907479 0 P 0
L 2.378937 2.7893701 2.4494285 2.7188785 0 P 0
L 2.378937 2.8907479 2.3877954 2.8996063 0 P 0
L 2.3877951 0.1377953 2.3877951 0.2177462 1 P 0
L 2.3877954 2.9586614 2.3898425 2.9607085 0 P 0
L 2.3898425 2.9607085 2.3898425 3.481063 0 P 0
L 2.3901425 2.358813 2.3901425 2.397363 56 P 0
L 2.3901425 2.397363 2.4048425 2.412063 56 P 0
L 2.3901425 2.518253 2.3901425 2.560363 56 P 0
L 2.3901425 2.560363 2.4088425 2.579063 56 P 0
L 2.4088425 2.579063 2.4098425 2.579063 56 P 0
L 2.4098225 2.314083 2.4098225 2.358813 0 P 0
L 2.4098225 2.314083 2.4098425 2.314063 0 P 0
L 2.4098325 0.878873 2.4098325 0.932053 56 P 0
L 2.4098325 1.038313 2.4098325 1.088053 56 P 0
L 2.4098425 2.283063 2.4298425 2.303063 0 P 0
L 2.4271651 0.1377953 2.4271651 0.2367555 1 P 0
L 2.4295125 2.358813 2.4296449 2.3586806 0 P 0
L 2.4296449 2.3225448 2.4296449 2.3586806 0 P 0
L 2.4296449 2.3225448 2.4298425 2.3223472 0 P 0
L 2.4298425 2.303063 2.4298425 2.3223472 0 P 0
L 2.4348425 3.546063 2.4523228 3.5635433 0 P 0
L 2.4470546 0.2425914 2.4593435 0.2332909 2 P 0
L 2.4491925 2.2858778 2.4491925 2.358813 0 P 0
L 2.4491925 2.2858778 2.4508425 2.2842278 0 P 0
L 2.4491925 2.518253 2.4491925 2.5978146 0 P 0
L 2.4491925 2.5978146 2.4635827 2.6122048 0 P 0
L 2.4508425 2.282063 2.4508425 2.2842278 0 P 0
L 2.4523228 3.5635433 2.5048425 3.5635433 0 P 0
L 2.4550854 2.7165354 2.6846784 2.7165354 0 P 0
L 2.4635827 2.6122048 2.4635827 2.6742127 0 P 0
L 2.4635827 2.6742127 2.4839956 2.6946256 0 P 0
L 2.4673224 0.2173067 2.4673225 0.2173067 2 P 0
L 2.4673225 0.111063 2.4673225 0.2173067 2 P 0
L 2.4688825 2.2997493 2.4688825 2.358813 0 P 0
L 2.4688825 2.2997493 2.4758425 2.2927893 0 P 0
L 2.4688825 2.518253 2.4688825 2.5888506 0 P 0
L 2.4688825 2.5888506 2.4948425 2.6148106 0 P 0
L 2.4758425 2.291063 2.4758425 2.2927893 0 P 0
L 2.4758425 2.456063 2.4885625 2.468783 56 P 0
L 2.4839956 2.6946256 2.4934051 2.6946256 0 P 0
L 2.4885625 2.358813 2.4885625 2.412783 56 P 0
L 2.4885625 2.412783 2.4888425 2.413063 56 P 0
L 2.4885625 2.468783 2.4885625 2.518253 56 P 0
L 2.4934051 2.6946256 2.4948425 2.696063 0 P 0
L 2.4948425 2.6148106 2.4948425 2.661063 0 P 0
L 2.4998425 2.236063 2.5279325 2.264153 0 P 0
L 2.503937 0.464567 2.503937 0.5738189 0 P 0
L 2.503937 0.464567 2.5393701 0.4291339 0 P 0
L 2.503937 0.6072835 3.0551181 0.6072835 0 P 0
L 2.5048425 3.406063 2.6348425 3.406063 0 P 0
L 2.5048425 3.4848031 2.5785826 3.4848031 0 P 0
L 2.5048425 3.6422834 2.5981497 3.6422834 2 P 0
L 2.5059051 0.1377953 2.507874 0.1397642 0 P 0
L 2.507874 0.1397642 2.507874 0.2716535 0 P 0
L 2.507874 0.2716535 2.5393701 0.3031496 0 P 0
L 2.5082625 0.878873 2.5082625 0.931483 56 P 0
L 2.5082625 1.038313 2.5082625 1.089483 56 P 0
L 2.5082625 1.089483 2.5088425 1.090063 56 P 0
L 2.5279325 2.264153 2.5279325 2.358813 0 P 0
L 2.5279325 2.518253 2.5279325 2.5820664 0 P 0
L 2.5279325 2.5820664 2.6122047 2.6663386 0 P 0
L 2.5393701 0.3031496 2.5393701 0.4291339 0 P 0
L 2.5454525 0.111673 2.5454525 0.244233 2 P 0
L 2.5454525 0.244233 2.5460625 0.244843 2 P 0
L 2.5476225 2.313283 2.5476225 2.358813 0 P 0
L 2.5476225 2.313283 2.5798425 2.281063 0 P 0
L 2.5673025 2.358813 2.5673025 2.403523 0 P 0
L 2.5673025 2.403523 2.5758425 2.412063 0 P 0
L 2.5785826 3.4848031 2.5798425 3.486063 0 P 0
L 2.5818425 2.312063 2.5869925 2.317213 56 P 0
L 2.5846451 0.1377953 2.5846451 0.2652719 1 P 0
L 2.5868425 2.569063 2.5869925 2.568913 56 P 0
L 2.5869925 2.317213 2.5869925 2.358813 56 P 0
L 2.5869925 2.518253 2.5869925 2.568913 56 P 0
L 2.5981497 3.6422834 2.633937 3.6064961 2 P 0
L 2.5998425 2.4317334 2.5998425 2.436063 0 P 0
L 2.5998425 2.4317334 2.6066725 2.4249034 0 P 0
L 2.6066725 2.358813 2.6066725 2.4249034 0 P 0
L 2.6066825 0.878873 2.6066825 0.931903 56 P 0
L 2.6066825 0.931903 2.6088425 0.934063 56 P 0
L 2.6066825 1.038313 2.6066825 1.090903 56 P 0
L 2.6066825 1.090903 2.6068425 1.091063 56 P 0
L 2.6067769 0.8154384 2.6181102 0.8267717 1 P 0
L 2.6102362 0.259167 2.6102362 0.2795276 1 P 0
L 2.6122047 2.6663386 3.5688976 2.6663386 0 P 0
L 2.6240151 0.1377953 2.6240151 0.2259018 1 P 0
L 2.6248425 2.461063 2.6256025 2.461823 0 P 0
L 2.6248425 2.461063 2.6263625 2.459543 0 P 0
L 2.6259843 0.7952756 2.6259843 0.8093928 1 P 0
L 2.6263625 2.358813 2.6263625 2.459543 0 P 0
L 2.6263725 0.8467187 2.6263725 0.878873 1 P 0
L 2.6263725 0.9807033 2.6263725 1.038313 1 P 0
L 2.633937 3.6064961 2.6398425 3.6064961 2 P 0
L 2.636874 0.2479055 2.6377322 0.2470473 2 P 0
L 2.636874 0.2479055 2.6907891 0.2479055 2 P 0
L 2.6377322 0.2470473 2.6516693 0.2470473 2 P 0
L 2.6398425 3.5356299 2.645748 3.5356299 2 P 0
L 2.6398425 3.6064961 2.645748 3.6064961 2 P 0
L 2.645748 3.5356299 2.6748425 3.5065354 2 P 0
L 2.645748 3.6064961 2.659252 3.5929921 2 P 0
L 2.6458425 2.274063 2.6458425 2.2993472 0 P 0
L 2.6458425 2.2993472 2.6460425 2.2995472 0 P 0
L 2.6460425 2.2995472 2.6460425 2.358813 0 P 0
L 2.6460525 0.8578418 2.6460525 0.878873 1 P 0
L 2.6460525 0.9799318 2.6460525 1.038313 1 P 0
L 2.6516693 0.2470473 2.6633851 0.2353315 2 P 0
L 2.659252 3.5929921 2.7248425 3.5929921 2 P 0
L 2.6633851 0.1377953 2.6633851 0.2353315 2 P 0
L 2.6657325 2.291173 2.6657325 2.358813 0 P 0
L 2.6657325 2.291173 2.6658425 2.291063 0 P 0
L 2.6657425 1.038313 2.6657425 1.091963 56 P 0
L 2.6657425 1.091963 2.6658425 1.092063 56 P 0
L 2.6748425 3.501063 2.6748425 3.5065354 2 P 0
L 2.6792645 0.8288708 2.6792737 0.82888 1 P 0
L 2.6792737 0.82888 2.6811024 0.8307087 1 P 0
L 2.6798425 3.661063 2.6805511 3.6617716 0 P 0
L 2.6805511 3.6617716 2.7198425 3.6617716 0 P 0
L 2.6854125 2.311493 2.6854125 2.358813 56 P 0
L 2.6854125 2.311493 2.6858425 2.311063 56 P 0
L 2.6854125 2.518253 2.6854125 2.567633 56 P 0
L 2.6854125 2.567633 2.6858425 2.568063 56 P 0
L 2.6854225 0.8411383 2.6854225 0.878873 1 P 0
L 2.6854225 0.9806981 2.6854225 1.038313 1 P 0
L 2.6903352 2.7188785 2.6929134 2.7214567 0 P 0
L 2.6907891 0.2479055 2.7025049 0.2361897 2 P 0
L 2.6929134 0.7952756 2.6929134 0.8116992 1 P 0
L 2.694252 3.7503543 2.694252 3.7579135 2 P 0
L 2.694252 3.7579135 2.7224094 3.7860709 2 P 0
L 2.7025049 0.1380455 2.7025049 0.1806006 2 P 0
L 2.7025049 0.1380455 2.7027551 0.1377953 2 P 0
L 2.7025049 0.1806006 2.7025049 0.2361897 2 P 0
L 2.7025049 0.1806006 2.7035425 0.179563 2 P 0
L 2.7028425 2.293063 2.7028425 2.2952278 0 P 0
L 2.7028425 2.2952278 2.7058425 2.2982278 0 P 0
L 2.7035425 0.111063 2.7035425 0.179563 2 P 0
L 2.7051025 2.3200872 2.7051025 2.358813 0 P 0
L 2.7051025 2.3200872 2.7058425 2.3193472 0 P 0
L 2.7051125 0.8411504 2.7051125 0.878873 1 P 0
L 2.7051125 0.9799269 2.7051125 1.038313 1 P 0
L 2.7058425 2.2982278 2.7058425 2.3193472 0 P 0
L 2.7198425 3.6617716 2.7582283 3.6617716 0 P 0
L 2.7224094 3.7860709 2.7810946 3.7860709 2 P 0
L 2.7244825 1.093063 2.7247925 1.0905923 56 P 0
L 2.7247825 2.2972878 2.7247825 2.358813 0 P 0
L 2.7247825 2.2972878 2.7268425 2.2952278 0 P 0
L 2.7247925 1.038313 2.7247925 1.0905923 56 P 0
L 2.7248425 3.521063 2.7248425 3.5591338 2 P 0
L 2.7248425 3.5929921 2.7273149 3.5905197 2 P 0
L 2.7248425 3.729063 2.7248425 3.7297637 56 P 0
L 2.7248425 3.7297637 2.7327165 3.7376377 56 P 0
L 2.7268425 2.293063 2.7268425 2.2952278 0 P 0
L 2.7273149 3.5905197 2.7503858 3.5905197 2 P 0
L 2.7322834 0.7997175 2.7322835 0.7996858 1 P 0
L 2.7322835 0.7952756 2.7322835 0.7996858 1 P 0
L 2.7327165 3.7376377 2.7405906 3.7376377 56 P 0
L 2.7405906 3.7376377 2.7454331 3.7424802 56 P 0
L 2.7408425 0.113133 2.7429125 0.111063 1 P 0
L 2.7421251 0.1377953 2.7421251 0.2652683 1 P 0
L 2.7429125 0.111063 2.7458425 0.113993 1 P 0
L 2.7444825 0.8291685 2.7444825 0.878873 1 P 0
L 2.7444825 0.980703 2.7444825 1.038313 1 P 0
L 2.7454331 3.7424802 2.7454331 3.7503543 56 P 0
L 2.7468579 0.2782484 2.7468769 0.2782709 1 P 0
L 2.7477008 0.2796783 2.7483622 0.2814053 1 P 0
L 2.7487121 0.2821354 2.7488082 0.2823002 1 P 0
L 2.7488082 0.2823002 2.74882 0.282312 1 P 0
L 2.7503858 3.5905197 2.7748425 3.566063 2 P 0
L 2.7568898 3.1872047 2.840748 3.1872047 0 P 0
L 2.7582283 3.6617716 2.7975197 3.701063 0 P 0
L 2.7641625 0.805705 2.7641625 0.878873 1 P 0
L 2.7641625 0.979932 2.7641625 1.038313 1 P 0
L 2.7810946 3.7860709 2.809252 3.7579135 2 P 0
L 2.7814951 0.1377953 2.7814951 0.2747776 1 P 0
L 2.7838425 2.358813 2.7838425 2.429063 56 P 0
L 2.7838425 2.518253 2.7838425 2.568063 56 P 0
L 2.7838525 1.038313 2.7838525 1.0915923 56 P 0
L 2.7838525 1.0915923 2.7841625 1.094063 56 P 0
L 2.7975197 3.701063 3.0006299 3.701063 0 P 0
L 2.7992126 0.2519685 2.8176623 0.2335188 2 P 0
L 2.7992126 0.2519685 2.8375984 0.2519685 2 P 0
L 2.7998425 3.616063 2.829 3.6452205 0 P 0
L 2.8035225 2.358813 2.8038425 2.358493 0 P 0
L 2.8035325 0.8057048 2.8035325 0.878873 1 P 0
L 2.8035325 0.9806979 2.8035325 1.038313 1 P 0
L 2.8035325 1.038313 2.8038425 1.038003 1 P 0
L 2.8038425 2.307063 2.8038425 2.358493 0 P 0
L 2.809252 3.7503543 2.809252 3.7579135 2 P 0
L 2.8176623 0.1409981 2.8176623 0.2335188 2 P 0
L 2.8176623 0.1409981 2.8208651 0.1377953 2 P 0
L 2.8218425 2.601063 2.8232125 2.599693 0 P 0
L 2.8232125 2.518253 2.8232125 2.599693 0 P 0
L 2.8232225 0.8038441 2.8232225 0.878873 1 P 0
L 2.8232225 0.9799272 2.8232225 1.038313 1 P 0
L 2.829 3.6452205 2.829 3.6559291 0 P 0
L 2.829 3.6559291 2.8348425 3.6617716 0 P 0
L 2.8348425 3.6617716 2.8397638 3.6666929 0 P 0
L 2.8375984 0.2519685 2.8565402 0.2330267 2 P 0
L 2.8397638 3.6666929 2.9448425 3.6666929 0 P 0
L 2.840748 3.1872047 3.0488976 3.3953543 0 P 0
L 2.8418425 2.263063 2.8418425 2.299063 0 P 0
L 2.8418425 2.299063 2.8625825 2.319803 0 P 0
L 2.8428425 1.095063 2.8429025 1.095003 56 P 0
L 2.8429025 1.038313 2.8429025 1.095003 56 P 0
L 2.8565402 0.1414902 2.8565402 0.2330267 2 P 0
L 2.8565402 0.1414902 2.8570225 0.1410079 2 P 0
L 2.8570225 0.1410079 2.8602351 0.1377953 2 P 0
L 2.8604331 3.7503543 2.8604331 3.7846536 56 P 0
L 2.8604331 3.7846536 2.8608425 3.785063 56 P 0
L 2.8625825 2.319803 2.8625825 2.358813 0 P 0
L 2.8625925 0.7962118 2.8625925 0.878873 1 P 0
L 2.8718425 2.297063 2.8822625 2.307483 56 P 0
L 2.8818425 2.566063 2.8822625 2.565643 56 P 0
L 2.8822625 2.307483 2.8822625 2.358813 56 P 0
L 2.8822625 2.518253 2.8822625 2.565643 56 P 0
L 2.8822725 0.822866 2.8822725 0.878873 1 P 0
L 2.8888425 4.221063 2.8889212 4.2211417 56 P 0
L 2.8889212 4.2211417 2.9448425 4.2211417 56 P 0
L 2.8948425 2.431063 2.8948425 2.4650041 0 P 0
L 2.8948425 2.4650041 2.9019525 2.4721141 0 P 0
L 2.8996051 0.1377951 2.8996051 0.1377953 1 P 0
L 2.8996051 0.1377953 2.8996051 0.2652676 1 P 0
L 2.9003925 0.111063 2.9078425 0.118513 1 P 0
L 2.9018425 1.095063 2.9019625 1.094943 56 P 0
L 2.9019525 2.304953 2.9019525 2.358813 0 P 0
L 2.9019525 2.304953 2.9208425 2.286063 0 P 0
L 2.9019525 2.4721141 2.9019525 2.518253 0 P 0
L 2.9019625 0.878873 2.9019625 0.921183 56 P 0
L 2.9019625 0.921183 2.9338425 0.953063 56 P 0
L 2.9019625 1.038313 2.9019625 1.094943 56 P 0
L 2.9054946 0.2795104 2.9055118 0.2795276 1 P 0
L 2.9207375 2.428168 2.9207375 2.517358 0 P 0
L 2.9207375 2.428168 2.9208425 2.428063 0 P 0
L 2.9207375 2.517358 2.9216325 2.518253 0 P 0
L 2.9208425 2.286063 2.9428425 2.286063 0 P 0
L 2.9318425 0.118983 2.9397625 0.111063 1 P 0
L 2.9389751 0.1377953 2.9389751 0.2747784 1 P 0
L 2.9448425 3.7454331 2.9448425 3.951063 0 P 0
L 2.9488425 2.428063 2.9488425 2.456063 0 P 0
L 2.9488425 2.428063 2.9806925 2.396213 0 P 0
L 2.9574751 0.2519685 2.9697144 0.2378982 2 P 0
L 2.9588425 2.621063 2.9806925 2.599213 0 P 0
L 2.9610025 2.311903 2.9610025 2.358813 0 P 0
L 2.9610025 2.311903 2.9858425 2.287063 0 P 0
L 2.9746502 0.2247425 2.9746503 0.2247425 2 P 0
L 2.9746503 0.1414901 2.9746503 0.2247425 2 P 0
L 2.9746503 0.1414901 2.9751325 0.1410079 2 P 0
L 2.9751325 0.1410079 2.9783451 0.1377953 2 P 0
L 2.9806925 2.358813 2.9806925 2.396213 0 P 0
L 2.9806925 2.518253 2.9806925 2.599213 0 P 0
L 3.0006299 3.701063 3.035 3.6666929 0 P 0
L 3.035 3.6666929 3.0448425 3.6666929 0 P 0
L 3.0448425 3.7454331 3.0448425 3.951063 0 P 0
L 3.0448425 4.2211417 3.1448425 4.2211417 2 P 0
L 3.0488976 3.3953543 3.0685826 3.3953543 0 P 0
L 3.0531481 0.5718489 3.0551181 0.5738189 0 P 0
L 3.0551181 0.1592623 3.0551181 0.5738189 0 P 0
L 3.0551181 0.1592623 3.0570851 0.1572953 0 P 0
L 3.0578725 0.130563 3.0598425 0.132533 0 P 0
L 3.0685826 3.3953543 3.0688976 3.3956693 0 P 0
L 3.0972425 0.111063 3.0974409 0.1112614 2 P 0
L 3.0974409 0.1112614 3.0974409 0.2519685 2 P 0
L 3.1112205 3.1372047 3.1125984 3.1358268 0 P 0
L 3.1112205 3.1872047 3.1113189 3.1871063 0 P 0
L 3.1112205 3.2372047 3.172244 3.2372047 0 P 0
L 3.1112205 3.2872047 3.1275632 3.2872047 0 P 0
L 3.1113189 3.1871063 3.188878 3.1871063 0 P 0
L 3.1125984 3.1358268 3.1830708 3.1358268 0 P 0
L 3.1275632 3.2872047 3.1347796 3.2944211 0 P 0
L 3.1347796 3.2944211 3.1347796 3.3444253 0 P 0
L 3.1347796 3.3444253 3.2470472 3.4566929 0 P 0
L 3.1448425 3.6666929 3.2399212 3.6666929 0 P 0
L 3.1448425 3.7454331 3.1448425 3.951063 0 P 0
L 3.1448425 4.1461417 3.1448425 4.2211417 2 P 0
L 3.1448425 4.1461417 3.1895472 4.101437 2 P 0
L 3.172244 3.2372047 3.2057086 3.2706693 0 P 0
L 3.188878 3.1871063 3.1889764 3.1870079 0 P 0
L 3.1895472 3.8559025 3.1895472 4.101437 2 P 0
L 3.1895472 3.8559025 3.219252 3.8261977 2 P 0
L 3.1917598 2.8247538 3.1917598 2.9240433 0 P 0
L 3.1917598 2.8247538 3.2006317 2.8158819 0 P 0
L 3.1917598 2.9240433 3.2509842 2.9832677 0 P 0
L 3.1972633 1.714063 3.1972633 1.7154838 0 P 0
L 3.1972633 1.7154838 3.2344825 1.752703 0 P 0
L 3.2006317 2.8158819 3.2082519 2.8158819 0 P 0
L 3.2057086 3.2706693 3.3287401 3.2706693 0 P 0
L 3.2082519 2.8158819 3.2091732 2.8149606 0 P 0
L 3.2091732 2.8346456 3.2091732 2.8961811 0 P 0
L 3.2091732 2.8961811 3.2716535 2.9586614 0 P 0
L 3.219252 3.7503543 3.219252 3.8261977 2 P 0
L 3.2248425 1.6613472 3.2445583 1.681063 0 P 0
L 3.2293307 2.845 3.2293307 2.8805512 0 P 0
L 3.2293307 2.8805512 3.3448425 2.996063 0 P 0
L 3.2344825 1.752703 3.4920225 1.752703 0 P 0
L 3.2398425 3.596063 3.2423425 3.598563 0 P 0
L 3.2399212 3.6666929 3.2448425 3.6617716 0 P 0
L 3.2423425 3.598563 3.2423425 3.6592716 0 P 0
L 3.2423425 3.6592716 3.2448425 3.6617716 0 P 0
L 3.2445583 1.681063 3.271693 1.681063 0 P 0
L 3.2470472 3.4566929 3.2975474 3.4566929 0 P 0
L 3.2509842 2.9832677 3.2509842 3.0423228 0 P 0
L 3.2509842 3.0423228 3.3100381 3.1013767 0 P 0
L 3.2528425 1.661063 3.2658701 1.661063 0 P 0
L 3.2658701 1.661063 3.2726501 1.654283 0 P 0
L 3.2691732 2.7952756 3.2691732 2.8149606 0 P 0
L 3.2691732 2.8149606 3.2977401 2.8149606 0 P 0
L 3.2698425 3.785063 3.2704331 3.7844724 56 P 0
L 3.2704331 3.7503543 3.2704331 3.7844724 56 P 0
L 3.271693 1.681063 3.278793 1.673963 0 P 0
L 3.2726501 1.654283 3.4920225 1.654283 0 P 0
L 3.2755905 3.1417323 3.2771212 3.143263 0 P 0
L 3.2771212 3.143263 3.2859008 3.143263 0 P 0
L 3.278793 1.673963 3.4920225 1.673963 0 P 0
L 3.2859008 3.143263 3.3331103 3.1904725 0 P 0
L 3.2975474 3.4566929 3.3061773 3.448063 0 P 0
L 3.2977401 2.8149606 3.3708425 2.888063 0 P 0
L 3.2988425 1.971063 3.3784821 1.971063 0 P 0
L 3.3061773 3.448063 3.3588425 3.448063 0 P 0
L 3.3100381 3.1013767 3.4879914 3.1013767 0 P 0
L 3.3287401 3.2706693 3.390748 3.3326772 0 P 0
L 3.3291721 1.826063 3.4058425 1.826063 0 P 0
L 3.3308425 3.301063 3.3308425 3.3929291 56 P 0
L 3.3308425 3.3929291 3.3331103 3.3951969 56 P 0
L 3.3331103 3.1904725 3.3331103 3.2062205 0 P 0
L 3.3448425 2.996063 3.3452205 2.995685 0 P 0
L 3.3448425 3.951063 3.3498425 3.946063 0 P 0
L 3.3448425 4.2211417 3.3949212 4.2211417 56 P 0
L 3.3452205 2.995685 3.4444882 2.995685 0 P 0
L 3.3498425 3.6666929 3.4251968 3.6666929 0 P 0
L 3.3498425 3.7454331 3.3498425 3.946063 0 P 0
L 3.3588425 3.448063 3.3778425 3.467063 0 P 0
L 3.3688425 3.050063 3.3710073 3.050063 0 P 0
L 3.3708425 2.888063 3.4343071 2.888063 56 P 0
L 3.3710073 3.050063 3.3727317 3.0517874 0 P 0
L 3.3727317 3.0517874 3.4385827 3.0517874 0 P 0
L 3.3778425 3.467063 3.4031267 3.467063 0 P 0
L 3.3784821 1.971063 3.4590421 1.890503 0 P 0
L 3.3798425 1.336063 3.3831025 1.339323 0 P 0
L 3.3798425 1.386063 3.3811025 1.387323 0 P 0
L 3.3811025 1.387323 3.422518 1.387323 0 P 0
L 3.3831025 1.339323 3.4920225 1.339323 0 P 0
L 3.3921654 3.3951969 3.3934554 3.3939069 0 P 0
L 3.3928425 1.871063 3.4129675 1.850938 0 P 0
L 3.3934554 3.3334794 3.3934554 3.335458 0 P 0
L 3.3934554 3.335458 3.3934554 3.3939069 0 P 0
L 3.3934554 3.335458 3.4318504 3.297063 0 P 0
L 3.3949212 4.2211417 3.3958425 4.222063 56 P 0
L 3.4031267 3.467063 3.4148425 3.4553472 0 P 0
L 3.4048425 1.363323 3.4091721 1.363323 0 P 0
L 3.4058425 1.826063 3.4112225 1.831443 0 P 0
L 3.4068425 1.461063 3.4068425 1.4626866 56 P 0
L 3.4068425 1.4626866 3.4098425 1.4656866 56 P 0
L 3.4072822 1.411323 3.4318577 1.411323 57 P 0
L 3.4091721 1.363323 3.4134921 1.359003 0 P 0
L 3.4098425 1.4656866 3.4098425 1.468063 56 P 0
L 3.4098425 1.468063 3.4485125 1.506733 56 P 0
L 3.4108425 1.7136509 3.4632325 1.7136509 56 P 0
L 3.4112225 1.831443 3.4920225 1.831443 0 P 0
L 3.4129675 1.850938 3.4918275 1.850938 0 P 0
L 3.4134921 1.359003 3.4920225 1.359003 0 P 0
L 3.4138425 1.573063 3.4138425 1.593063 56 P 0
L 3.4138425 1.593063 3.4356925 1.614913 56 P 0
L 3.4144661 1.805063 3.4211661 1.811763 56 P 0
L 3.4148425 3.4446085 3.4148425 3.4553472 0 P 0
L 3.4148425 3.4446085 3.4238505 3.4356005 0 P 0
L 3.4211661 1.811763 3.4920225 1.811763 56 P 0
L 3.422518 1.387323 3.431148 1.378693 0 P 0
L 3.4238505 3.4313163 3.4238505 3.4356005 0 P 0
L 3.4238505 3.4313163 3.4285368 3.42663 0 P 0
L 3.4248425 3.636063 3.4251968 3.6364173 0 P 0
L 3.4251968 3.6364173 3.4251968 3.6666929 0 P 0
L 3.4251968 3.6666929 3.4649212 3.6666929 0 P 0
L 3.4285368 3.42663 3.4355354 3.42663 0 P 0
L 3.431148 1.378693 3.4920225 1.378693 0 P 0
L 3.4318504 3.297063 3.4918425 3.297063 0 P 0
L 3.4318577 1.411323 3.4448077 1.398373 57 P 0
L 3.4343071 2.888063 3.4385827 2.8923386 56 P 0
L 3.4355354 3.42663 3.4512205 3.4109449 0 P 0
L 3.4356925 1.614913 3.4920225 1.614913 56 P 0
L 3.4392507 1.870938 3.4918975 1.870938 0 P 0
L 3.444252 3.7503543 3.444252 3.783819 2 P 0
L 3.444252 3.783819 3.466496 3.806063 2 P 0
L 3.4448077 1.398373 3.4920225 1.398373 57 P 0
L 3.4485125 1.506733 3.4485125 1.5071077 56 P 0
L 3.4485125 1.5071077 3.4578878 1.516483 56 P 0
L 3.4512205 3.3951969 3.4512205 3.4109449 0 P 0
L 3.4578878 1.516483 3.4920225 1.516483 56 P 0
L 3.4590421 1.890503 3.4920225 1.890503 0 P 0
L 3.4632325 1.7136509 3.4634704 1.713413 56 P 0
L 3.4634704 1.713413 3.4919425 1.713413 56 P 0
L 3.464 3.648055 3.4698425 3.6538975 0 P 0
L 3.4649212 3.6666929 3.4698425 3.6617716 0 P 0
L 3.466496 3.806063 3.5398425 3.806063 2 P 0
L 3.4698425 3.6538975 3.4698425 3.6617716 0 P 0
L 3.4776771 2.797063 3.4848425 2.8042284 56 P 0
L 3.4848425 2.8042284 3.4848425 2.8923386 56 P 0
L 3.4848425 3.0517874 3.4848425 3.0943767 0 P 0
L 3.4848425 3.0943767 3.4918425 3.1013767 0 P 0
L 3.4879914 3.1013767 3.488147 3.1015323 0 P 0
L 3.488147 3.1015323 3.4916869 3.1015323 0 P 0
L 3.4915425 1.397893 3.4920225 1.398373 57 P 0
L 3.4916869 3.1015323 3.4918425 3.1013767 0 P 0
L 3.4918275 1.850938 3.4920225 1.851133 0 P 0
L 3.4918975 1.870938 3.4920225 1.870813 0 P 0
L 3.4919425 1.713413 3.4920225 1.713333 56 P 0
L 3.4920225 1.418063 3.5432189 1.418063 56 P 0
L 3.4920225 1.437743 3.4929425 1.438663 0 P 0
L 3.4920225 1.910183 3.5289625 1.910183 0 P 0
L 3.4920225 2.008613 3.5372925 2.008613 0 P 0
L 3.4920225 2.028293 3.5500725 2.028293 56 P 0
L 3.4920225 2.047983 3.5569225 2.047983 56 P 0
L 3.4920225 2.067663 3.5622425 2.067663 56 P 0
L 3.4920225 2.087353 3.5425525 2.087353 56 P 0
L 3.4929425 1.438663 3.5474425 1.438663 0 P 0
L 3.4954331 3.6974724 3.4954331 3.7503543 56 P 0
L 3.4954331 3.6974724 3.5318425 3.661063 56 P 0
L 3.5102756 3.3951969 3.5187232 3.4036445 0 P 0
L 3.5187232 3.4036445 3.5187232 3.4379437 0 P 0
L 3.5187232 3.4379437 3.5668425 3.486063 0 P 0
L 3.5289625 1.910183 3.5548425 1.936063 0 P 0
L 3.5298425 3.481063 3.5309449 3.4799606 0 P 0
L 3.5311023 2.8923386 3.5344602 2.8889807 0 P 0
L 3.5318425 3.660063 3.5318425 3.661063 56 P 0
L 3.5344602 2.8889807 3.5696807 2.8889807 0 P 0
L 3.5372925 2.008613 3.5548425 1.991063 0 P 0
L 3.5373384 2.9963386 3.5477716 2.9859054 0 P 0
L 3.5398425 3.806063 3.5403543 3.8065748 2 P 0
L 3.5403543 3.7151347 3.5403543 3.8065748 2 P 0
L 3.5403543 3.7151347 3.654111 3.601378 2 P 0
L 3.5403543 3.8065748 3.5406078 3.8068283 2 P 0
L 3.5406078 3.8068283 3.5696236 3.8068283 2 P 0
L 3.5425525 2.087353 3.5622425 2.067663 56 P 0
L 3.5432189 1.418063 3.5482189 1.413063 56 P 0
L 3.5474425 1.438663 3.5498425 1.441063 0 P 0
L 3.5482189 1.413063 3.5498425 1.413063 56 P 0
L 3.5500725 2.028293 3.5548425 2.033063 56 P 0
L 3.5548425 1.841063 3.5841425 1.811763 0 P 0
L 3.5548425 1.891063 3.5551225 1.890783 0 P 0
L 3.5548425 2.033063 3.5718425 2.033063 56 P 0
L 3.5551225 1.890783 3.6511825 1.890783 0 P 0
L 3.5569225 2.047983 3.5718425 2.033063 56 P 0
L 3.5622425 2.067663 3.5718425 2.058063 56 P 0
L 3.5668425 3.486063 3.6228425 3.486063 0 P 0
L 3.5688976 2.6663386 3.5885827 2.6860237 0 P 0
L 3.5696236 3.8068283 3.5898425 3.8270472 2 P 0
L 3.5696807 2.8889807 3.5885827 2.8700787 0 P 0
L 3.5718425 2.033063 3.5867625 2.047983 56 P 0
L 3.5718425 2.033063 3.5948425 2.033063 56 P 0
L 3.5718425 2.058063 3.5814425 2.067663 56 P 0
L 3.5814425 2.067663 3.6011325 2.087353 56 P 0
L 3.5814425 2.067663 3.6514625 2.067663 56 P 0
L 3.5841425 1.811763 3.6514625 1.811763 0 P 0
L 3.5867625 2.047983 3.6514625 2.047983 56 P 0
L 3.5885827 2.6860237 3.5885827 2.8700787 0 P 0
L 3.5898425 1.711063 3.5915425 1.711063 0 P 0
L 3.5898425 3.7275197 3.6085826 3.7275197 0 P 0
L 3.5898425 3.7846063 3.5898425 3.8270472 2 P 0
L 3.5898425 3.8270472 3.5898425 3.8525197 2 P 0
L 3.5898425 3.9096063 3.6185826 3.9096063 0 P 0
L 3.5908425 1.634063 3.5908425 1.662063 56 P 0
L 3.5908425 1.634063 3.6099925 1.614913 56 P 0
L 3.5948425 1.514063 3.5964661 1.514063 56 P 0
L 3.5948425 2.033063 3.5996125 2.028293 56 P 0
L 3.5964661 1.514063 3.5988861 1.516483 56 P 0
L 3.5988861 1.516483 3.6514625 1.516483 56 P 0
L 3.5996125 2.028293 3.6514625 2.028293 56 P 0
L 3.6011325 2.087353 3.6514625 2.087353 56 P 0
L 3.6038425 0.682063 3.6038425 0.7042362 56 P 0
L 3.6038425 0.7042362 3.6256693 0.726063 56 P 0
L 3.6085826 3.7275197 3.6671259 3.786063 0 P 0
L 3.6099925 1.614913 3.6514625 1.614913 56 P 0
L 3.6185826 3.9096063 3.6671259 3.861063 0 P 0
L 3.6256693 0.726063 3.6594094 0.726063 56 P 0
L 3.6428425 0.636063 3.6829133 0.636063 56 P 0
L 3.6511825 1.890783 3.6514625 1.890503 0 P 0
L 3.6514625 1.418063 3.7328425 1.418063 56 P 0
L 3.6514625 1.477113 3.6523825 1.478033 0 P 0
L 3.6514625 1.496803 3.7616527 1.496803 0 P 0
L 3.6514625 1.555853 3.7761054 1.555853 0 P 0
L 3.6514625 1.575543 3.7790428 1.575543 0 P 0
L 3.6514625 1.634593 3.6962587 1.634593 0 P 0
L 3.6514625 1.654283 3.6991961 1.654283 0 P 0
L 3.6514625 1.713333 3.7185725 1.713333 56 P 0
L 3.6514625 1.772393 3.7151562 1.772393 0 P 0
L 3.6514625 1.792073 3.7608525 1.792073 0 P 0
L 3.6514625 1.910183 3.7089625 1.910183 0 P 0
L 3.6514625 2.008613 3.7072925 2.008613 0 P 0
L 3.6523825 1.478033 3.8318125 1.478033 0 P 0
L 3.654111 3.601378 4.0570867 3.601378 2 P 0
L 3.6594094 0.7234878 3.6594094 0.726063 56 P 0
L 3.6671259 3.786063 3.6681102 3.786063 0 P 0
L 3.6671259 3.861063 3.6681102 3.861063 0 P 0
L 3.6888425 3.3295591 3.7013464 3.342063 56 P 0
L 3.6938425 3.1176299 3.699748 3.1176299 56 P 0
L 3.6962587 1.634593 3.7057887 1.625063 0 P 0
L 3.6991961 1.654283 3.7124161 1.641063 0 P 0
L 3.699748 3.1176299 3.7173858 3.0999921 56 P 0
L 3.6998425 3.751063 3.7015748 3.7527953 0 P 0
L 3.6998425 3.836063 3.7015748 3.8377953 0 P 0
L 3.7013464 3.342063 3.7448425 3.342063 56 P 0
L 3.7015748 3.7527953 3.7015748 3.786063 0 P 0
L 3.7015748 3.786063 3.7028248 3.784813 0 P 0
L 3.7015748 3.8377953 3.7015748 3.861063 0 P 0
L 3.7015748 3.861063 3.7028248 3.859813 0 P 0
L 3.702441 3.2610879 3.7324161 3.291063 2 P 0
L 3.7028248 3.784813 3.771309 3.784813 0 P 0
L 3.7028248 3.859813 3.771309 3.859813 0 P 0
L 3.7057887 1.625063 3.770612 1.625063 0 P 0
L 3.7072925 2.008613 3.7198425 1.996063 0 P 0
L 3.7089625 1.910183 3.7198425 1.921063 0 P 0
L 3.7124161 1.641063 3.7498425 1.641063 0 P 0
L 3.7151562 1.772393 3.7198425 1.7677067 0 P 0
L 3.7167716 0.636063 3.7167716 0.712559 0 P 0
L 3.7167716 0.712559 3.7302756 0.726063 0 P 0
L 3.7173858 3.0940866 3.7173858 3.0999921 56 P 0
L 3.7173858 3.0940866 3.7178425 3.0936299 56 P 0
L 3.7178425 3.072063 3.7178425 3.0936299 56 P 0
L 3.7185725 1.713333 3.7188425 1.713063 56 P 0
L 3.7198425 1.766063 3.7198425 1.7677067 0 P 0
L 3.7242925 1.674513 3.7248425 1.675063 0 P 0
L 3.7302756 0.726063 3.7302756 0.7319685 0 P 0
L 3.7302756 0.7319685 3.7378346 0.7244095 0 P 0
L 3.7324161 3.291063 3.8122689 3.291063 2 P 0
L 3.7378346 0.7244095 3.8956693 0.7244095 0 P 0
L 3.7498425 1.641063 3.7738632 1.6650837 0 P 0
L 3.7608525 1.792073 3.8048425 1.836063 0 P 0
L 3.7616527 1.496803 3.7759127 1.511063 0 P 0
L 3.7698425 3.2003465 3.7698425 3.2011339 56 P 0
L 3.7698425 3.2003465 3.777441 3.192748 56 P 0
L 3.770612 1.625063 3.8048425 1.6592935 0 P 0
L 3.771309 3.784813 3.772559 3.783563 0 P 0
L 3.771309 3.859813 3.772559 3.858563 0 P 0
L 3.772559 3.683563 3.7948733 3.683563 0 P 0
L 3.772559 3.758563 3.8257189 3.758563 56 P 0
L 3.772559 3.808563 3.8273425 3.808563 0 P 0
L 3.7738632 1.6650837 3.7738632 1.6661021 0 P 0
L 3.7759127 1.511063 3.8648425 1.511063 0 P 0
L 3.7761054 1.555853 3.7958955 1.5360629 0 P 0
L 3.777441 3.192748 3.7782284 3.192748 56 P 0
L 3.7778425 4.023063 3.7788425 4.023063 56 P 0
L 3.7782284 3.192748 3.8619134 3.109063 56 P 0
L 3.7788425 4.023063 3.7794803 4.0237008 56 P 0
L 3.7790428 1.575543 3.7885228 1.566063 0 P 0
L 3.7794803 4.0237008 3.8084646 4.0237008 56 P 0
L 3.7885228 1.566063 3.8948425 1.566063 0 P 0
L 3.7948733 3.683563 3.799015 3.6877047 0 P 0
L 3.7958955 1.5360629 3.9248424 1.5360629 0 P 0
L 3.799015 3.6877047 3.8008837 3.6877047 0 P 0
L 3.8008837 3.6877047 3.8714567 3.7582777 0 P 0
L 3.8038425 1.691063 3.8048425 1.690063 0 P 0
L 3.8048425 1.6592935 3.8048425 1.690063 0 P 0
L 3.8048425 1.836063 3.8048425 1.840063 0 P 0
L 3.8122689 3.291063 3.9698425 3.1334894 2 P 0
L 3.8257189 3.758563 3.8292189 3.762063 56 P 0
L 3.8273425 3.808563 3.8298425 3.806063 0 P 0
L 3.8292189 3.762063 3.8308425 3.762063 56 P 0
L 3.8318125 1.478033 3.8348425 1.481063 0 P 0
L 3.8619134 3.109063 3.8808425 3.109063 56 P 0
L 3.8714567 3.7582777 3.8714567 4.0237008 0 P 0
L 3.8956693 0.7244095 3.9797272 0.8084674 0 P 0
L 3.9029528 3.7435531 3.9029528 4.0237008 0 P 0
L 3.9029528 3.7435531 3.9588012 3.6877047 0 P 0
L 3.9114214 1.5996232 3.9254848 1.5996232 56 P 0
L 3.9114214 1.6196232 3.9115001 1.6195445 56 P 0
L 3.9114214 1.6396232 3.9115001 1.6395445 56 P 0
L 3.9114214 1.6596232 3.9574027 1.6596232 56 P 0
L 3.9114214 1.7796232 3.9197164 1.7796232 0 P 0
L 3.9115001 1.6195445 3.964361 1.6195445 56 P 0
L 3.9115001 1.6395445 3.969361 1.6395445 56 P 0
L 3.9197164 1.7796232 3.9206377 1.7805445 0 P 0
L 3.9206377 1.7805445 3.9206377 1.7918582 0 P 0
L 3.9206377 1.7918582 3.9448425 1.816063 0 P 0
L 3.9248424 1.5360629 3.9248425 1.536063 0 P 0
L 3.9254848 1.5996232 3.9255635 1.5995445 56 P 0
L 3.9255635 1.5995445 3.951361 1.5995445 56 P 0
L 3.9344488 3.7742126 3.9344488 4.0237008 0 P 0
L 3.9344488 3.7742126 3.9488189 3.7598425 0 P 0
L 3.9488189 3.7598425 3.9858464 3.7598425 0 P 0
L 3.951361 1.5995445 3.9698425 1.581063 56 P 0
L 3.9574027 1.6596232 3.9688425 1.671063 56 P 0
L 3.9588012 3.6877047 3.9606699 3.6877047 0 P 0
L 3.9598425 2.725063 3.9598425 2.7806299 56 P 0
L 3.9598425 2.725063 3.9608425 2.724063 56 P 0
L 3.9598425 2.8514961 3.9598425 2.9485827 2 P 0
L 3.9598425 2.8514961 4.0648425 2.8514961 2 P 0
L 3.9598425 2.9485827 4.0398425 3.0285827 2 P 0
L 3.9606699 3.6877047 3.9648116 3.683563 0 P 0
L 3.964361 1.6195445 3.9948425 1.589063 56 P 0
L 3.9648116 3.683563 3.9871259 3.683563 0 P 0
L 3.969361 1.6395445 4.0336945 1.575211 56 P 0
L 3.9698425 1.552063 3.9698425 1.581063 56 P 0
L 3.9698425 3.0987174 3.9698425 3.1334894 2 P 0
L 3.9698425 3.0987174 4.0293078 3.0392521 2 P 0
L 3.9797272 0.8084674 3.9797272 0.8906186 0 P 0
L 3.9858464 3.7598425 3.9871259 3.758563 0 P 0
L 3.9871259 3.708563 4.0358481 3.708563 0 P 0
L 3.9871259 3.733563 4.085689 3.733563 0 P 0
L 3.9871259 3.758563 4.0538386 3.758563 0 P 0
L 3.9871259 3.783563 4.0393425 3.783563 56 P 0
L 3.9948425 1.551063 3.9948425 1.589063 56 P 0
L 3.9968425 1.711063 4.0254027 1.7396232 56 P 0
L 4.0254027 1.7396232 4.0689017 1.7396232 56 P 0
L 4.0293078 3.0392521 4.0311417 3.0392521 2 P 0
L 4.0311417 3.0392521 4.0398425 3.0305513 2 P 0
L 4.0336945 1.547211 4.0336945 1.575211 56 P 0
L 4.0336945 1.547211 4.0348425 1.546063 56 P 0
L 4.0358481 3.708563 4.0498425 3.6945686 0 P 0
L 4.0393425 3.783563 4.0398425 3.784063 56 P 0
L 4.0398425 3.0285827 4.0398425 3.029567 2 P 0
L 4.0398425 3.029567 4.0398425 3.0305513 2 P 0
L 4.0398425 3.029567 4.0960631 3.029567 2 P 0
L 4.0398425 3.0925591 4.0528901 3.1056067 56 P 0
L 4.0498425 3.665063 4.0498425 3.6945686 0 P 0
L 4.0528901 3.1056067 4.0528901 3.1191106 56 P 0
L 4.0528901 3.1191106 4.0688425 3.135063 56 P 0
L 4.0538386 3.758563 4.0669291 3.7716535 0 P 0
L 4.0570867 3.601378 4.109252 3.6535433 2 P 0
L 4.0624043 2.595343 4.1878784 2.4698689 0 P 0
L 4.0648425 1.511063 4.0648425 1.5987019 0 P 0
L 4.0648425 1.5987019 4.0657638 1.5996232 0 P 0
L 4.0648425 1.7805445 4.0648425 1.796063 0 P 0
L 4.0648425 1.7805445 4.0657638 1.7796232 0 P 0
L 4.0648425 2.722063 4.0648425 2.7806299 56 P 0
L 4.0648425 2.8514961 4.0740945 2.8422441 2 P 0
L 4.0657638 1.5996232 4.0689017 1.5996232 0 P 0
L 4.0657638 1.7796232 4.0689017 1.7796232 0 P 0
L 4.0669291 3.7716535 4.1038189 3.7716535 0 P 0
L 4.0689017 1.6196232 4.1172823 1.6196232 0 P 0
L 4.0689017 1.6396232 4.1179981 1.6396232 0 P 0
L 4.0689017 1.6596232 4.1261562 1.6596232 0 P 0
L 4.0689017 1.6796232 4.1237791 1.6796232 56 P 0
L 4.0689017 1.7596232 4.1134083 1.7596232 0 P 0
L 4.0740945 2.8422441 4.1498425 2.8422441 2 P 0
L 4.085689 3.733563 4.1126772 3.7065748 0 P 0
L 4.0858425 3.892063 4.1046295 3.873276 56 P 0
L 4.0960631 3.029567 4.1098425 3.0433464 2 P 0
L 4.1038189 3.7716535 4.1048425 3.7706299 0 P 0
L 4.1046295 3.8417091 4.1046295 3.873276 56 P 0
L 4.1046295 3.8417091 4.1048425 3.8414961 56 P 0
L 4.1048425 3.7706299 4.1087796 3.774567 0 P 0
L 4.1087796 3.774567 4.1948425 3.774567 0 P 0
L 4.109252 3.6535433 4.3100394 3.6535433 2 P 0
L 4.1098425 3.0433464 4.1098425 3.0441338 2 P 0
L 4.1098425 3.0441338 4.1648425 3.0441338 2 P 0
L 4.1098425 3.0779921 4.1098425 3.126063 56 P 0
L 4.1098425 3.126063 4.1136945 3.129915 56 P 0
L 4.1126772 3.701063 4.1126772 3.7065748 0 P 0
L 4.1134083 1.7596232 4.121063 1.7519685 0 P 0
L 4.1136945 3.129915 4.1136945 3.133915 56 P 0
L 4.1136945 3.133915 4.1148425 3.135063 56 P 0
L 4.1172823 1.6196232 4.1358426 1.6010629 0 P 0
L 4.1179981 1.6396232 4.1265583 1.631063 0 P 0
L 4.1203866 3.5941508 4.1413948 3.5941508 0 P 0
L 4.121063 1.7519685 4.133937 1.7519685 0 P 0
L 4.1237791 1.6796232 4.1302189 1.686063 56 P 0
L 4.1261562 1.6596232 4.1347164 1.651063 0 P 0
L 4.1265583 1.631063 4.14262 1.631063 0 P 0
L 4.1302189 1.686063 4.1318425 1.686063 56 P 0
L 4.133937 1.7519685 4.1348425 1.751063 0 P 0
L 4.1347164 1.651063 4.1348425 1.651063 0 P 0
L 4.1348425 1.751063 4.1713386 1.751063 0 P 0
L 4.1358426 1.6010629 4.1798425 1.6010629 0 P 0
L 4.1413948 3.5941508 4.1505905 3.6033465 0 P 0
L 4.14262 1.631063 4.1500598 1.6236232 0 P 0
L 4.1498425 2.7898819 4.1500236 2.790063 2 P 0
L 4.1500236 2.790063 4.1761267 2.790063 2 P 0
L 4.1500598 1.6236232 4.2438987 1.6236232 0 P 0
L 4.1528425 3.135063 4.1539905 3.133915 56 P 0
L 4.1539905 3.127915 4.1539905 3.133915 56 P 0
L 4.1539905 3.127915 4.1648425 3.117063 56 P 0
L 4.1648425 3.0441338 4.2198425 3.0441338 2 P 0
L 4.1648425 3.0779921 4.1648425 3.117063 56 P 0
L 4.1670079 3.701063 4.185315 3.701063 0 P 0
L 4.1713386 1.751063 4.7277559 2.3074803 0 P 0
L 4.1761267 2.790063 4.1878425 2.8017788 2 P 0
L 4.1798425 1.6010629 4.1798425 1.601063 0 P 0
L 4.1805146 2.595343 4.2436362 2.6584646 0 P 0
L 4.185315 3.701063 4.1948425 3.7105905 0 P 0
L 4.1878425 2.8017788 4.1878425 2.820063 2 P 0
L 4.1878425 2.820063 4.2066378 2.8388583 2 P 0
L 4.1878784 2.4698689 4.9120209 2.4698689 0 P 0
L 4.1948425 3.7105905 4.1948425 3.774567 0 P 0
L 4.1948425 3.8375591 4.1948425 3.884063 56 P 0
L 4.2049212 3.6033465 4.2755905 3.6033465 0 P 0
L 4.2066378 2.8388583 4.2222047 2.8388583 2 P 0
L 4.2088425 3.135063 4.2094094 3.1356299 56 P 0
L 4.2088425 3.135063 4.2099905 3.133915 56 P 0
L 4.2094094 3.1356299 4.2094094 3.246063 56 P 0
L 4.2099905 3.129915 4.2099905 3.133915 56 P 0
L 4.2099905 3.129915 4.2198425 3.120063 56 P 0
L 4.2198425 3.0441338 4.2748425 3.0441338 2 P 0
L 4.2198425 3.0779921 4.2198425 3.120063 56 P 0
L 4.2222047 2.8388583 4.2348425 2.8514961 2 P 0
L 4.2348425 2.725063 4.2348425 2.7806299 2 P 0
L 4.2348425 2.8514961 4.3398425 2.8514961 2 P 0
L 4.2436362 2.6584646 4.8937008 2.6584646 0 P 0
L 4.2438987 1.6236232 4.9277558 2.3074803 0 P 0
L 4.2533465 3.774567 4.2548425 3.776063 2 P 0
L 4.2728425 3.0799921 4.2728425 3.135063 56 P 0
L 4.2728425 3.0799921 4.2748425 3.0779921 56 P 0
L 4.2748425 3.0441338 4.3348425 3.0441338 2 P 0
L 4.2802756 3.246063 4.4498425 3.246063 2 P 0
L 4.2986248 2.595343 4.8731609 2.595343 0 P 0
L 4.3100394 3.6535433 4.3316929 3.6318898 2 P 0
L 4.3316929 3.6043307 4.3316929 3.6318898 2 P 0
L 4.3316929 3.6043307 4.3326771 3.6033465 2 P 0
L 4.3326771 3.6033465 4.6771653 3.6033465 2 P 0
L 4.3338425 3.135063 4.3348425 3.134063 56 P 0
L 4.3348425 3.0441338 4.3948425 3.0441338 2 P 0
L 4.3348425 3.0779921 4.3348425 3.134063 56 P 0
L 4.3398425 2.725063 4.3398425 2.7806299 2 P 0
L 4.3398425 2.8514961 4.3918425 2.8514961 2 P 0
L 4.3878425 4.206063 4.4329134 4.206063 56 P 0
L 4.3918425 2.8514961 4.4010945 2.8422441 2 P 0
L 4.3948425 3.0441338 4.4548425 3.0441338 2 P 0
L 4.3948425 3.0779921 4.3948425 3.0787795 56 P 0
L 4.3948425 3.0787795 4.402441 3.086378 56 P 0
L 4.4010945 2.8422441 4.4348425 2.8422441 2 P 0
L 4.402441 3.086378 4.4032284 3.086378 56 P 0
L 4.4032284 3.086378 4.4318425 3.1149921 56 P 0
L 4.4318425 3.1149921 4.4318425 3.135063 56 P 0
L 4.4348425 2.7898819 4.5036614 2.7898819 2 P 0
L 4.4498425 3.246063 4.5398425 3.156063 2 P 0
L 4.4548425 3.0441338 4.4573149 3.0466062 2 P 0
L 4.4548425 3.0779921 4.4548425 3.108063 56 P 0
L 4.4548425 3.108063 4.4766945 3.129915 56 P 0
L 4.4573149 3.0466062 4.4748968 3.0466062 2 P 0
L 4.4748968 3.0466062 4.5398425 3.1115519 2 P 0
L 4.4766945 3.129915 4.4766945 3.133915 56 P 0
L 4.4766945 3.133915 4.4778425 3.135063 56 P 0
L 4.5398425 2.9040551 4.5398425 3.1115519 0 P 0
L 4.5398425 2.9040551 4.7293307 2.7145669 0 P 0
L 4.5398425 3.1115519 4.5398425 3.156063 0 P 0
L 4.5667716 4.206063 4.6526771 4.206063 0 P 0
L 4.6526771 4.206063 4.6526772 4.2060629 0 P 0
L 4.6526772 4.121063 4.6526772 4.2060629 0 P 0
L 4.6771653 3.6033465 4.7686835 3.5118283 2 P 0
L 4.7070078 4.206063 4.7070078 4.2115748 2 P 0
L 4.7070078 4.2115748 4.7111811 4.2157481 2 P 0
L 4.7070079 4.121063 4.7121385 4.1159324 0 P 0
L 4.7111811 4.2157481 4.7166929 4.2157481 2 P 0
L 4.7121385 4.1159324 4.7547119 4.1159324 0 P 0
L 4.7166929 4.2157481 4.7770078 4.276063 2 P 0
L 4.7293307 2.7145669 4.9206693 2.7145669 0 P 0
L 4.7686835 3.5118283 5.2740772 3.5118283 2 P 0
L 4.7770078 4.276063 5.2468425 4.276063 2 P 0
L 4.7942913 2.8080709 4.7952755 2.8090551 0 P 0
L 4.7942913 2.8080709 4.9094487 2.8080709 0 P 0
L 4.8731609 2.595343 5.0610236 2.4074803 0 P 0
L 4.8848427 2.7893701 4.8877954 2.7864174 0 P 0
L 4.8937008 2.6584646 5.2116142 2.3405512 0 P 0
L 4.9094487 2.8080709 4.9094488 2.8080708 0 P 0
L 4.9094488 3.9616142 4.9094488 4.1181102 0 P 0
L 4.9094488 4.1181102 4.9108425 4.1195039 0 P 0
L 4.9108425 4.1195039 4.9108425 4.203063 0 P 0
L 4.9108425 4.203063 4.9549134 4.203063 56 P 0
L 4.9120209 2.4698689 4.992126 2.3897638 0 P 0
L 4.9206693 2.7145669 5.3277559 2.3074803 0 P 0
L 4.9277558 2.3074803 4.9277559 2.3074803 0 P 0
L 4.9277559 1.0074803 4.992126 1.0718504 0 P 0
L 4.9549134 4.203063 4.9579134 4.206063 56 P 0
L 4.992126 1.0718504 4.992126 2.3897638 0 P 0
L 5.0610236 1.0742126 5.0610236 2.4074803 0 P 0
L 5.0610236 1.0742126 5.1277559 1.0074803 0 P 0
L 5.0917716 4.206063 5.2126771 4.206063 0 P 0
L 5.2116142 1.1338585 5.2116142 2.3405512 0 P 0
L 5.2116142 1.1338585 5.3277559 1.0177168 0 P 0
L 5.2126771 4.1260631 5.2126771 4.206063 0 P 0
L 5.2126771 4.1260631 5.2126772 4.126063 0 P 0
L 5.2468425 4.276063 5.2670078 4.2558977 2 P 0
L 5.2670078 4.206063 5.2670078 4.2558977 2 P 0
L 5.2670078 4.206063 5.2898425 4.206063 2 P 0
L 5.2670079 4.0888976 5.2670079 4.126063 0 P 0
L 5.2740772 3.5118283 5.2748425 3.511063 2 P 0
L 5.2748425 3.511063 5.2748425 3.5121454 2 P 0
L 5.2748425 3.5121454 5.2998425 3.5371454 2 P 0
L 5.2898425 4.206063 5.2998425 4.196063 2 P 0
L 5.2998425 3.5371454 5.2998425 4.196063 2 P 0
L 5.3277559 1.0074803 5.3277559 1.0177168 0 P 0
L 5.5778425 2.214063 5.6128425 2.214063 0 P 0
L 5.6128425 2.214063 5.6348425 2.236063 0 P 0
L 5.636811 3.3572835 5.6369212 3.3571733 2 P 0
L 5.6369212 3.320756 5.6369212 3.3571733 2 P 0
L 5.6369212 3.320756 5.6555118 3.3021654 2 P 0
L 5.6555118 3.3021654 5.8120079 3.3021654 2 P 0
L 5.6767717 3.3622047 5.6767717 3.5459922 56 P 0
L 5.6767717 3.5459922 5.6768425 3.546063 56 P 0
L 5.7220472 3.7838583 5.7220472 3.8444882 2 P 0
L 5.7220472 3.7838583 5.8048425 3.701063 2 P 0
L 5.7253937 4.0334646 5.8290944 4.1371654 2 P 0
L 5.7338425 3.3612205 5.7338425 3.556063 56 P 0
L 5.8048425 3.701063 5.8801181 3.701063 2 P 0
L 5.8120079 3.3021654 5.8120079 3.3612205 0 P 0
L 5.8120079 3.3021654 5.847441 3.3021654 2 P 0
L 5.8290944 4.1371654 6.2073228 4.1371654 2 P 0
L 5.847441 3.3021654 5.9948425 3.4495669 2 P 0
L 5.8801181 3.701063 5.8879921 3.708937 2 P 0
L 5.8879921 3.701063 5.8879921 3.708937 2 P 0
L 5.9948425 3.4495669 5.9948425 3.552063 2 P 0
L 5.9948425 3.552063 5.9988425 3.556063 2 P 0
L 5.9988425 3.556063 6.0356772 3.556063 2 P 0
L 6.0048425 2.3388977 6.0103543 2.3388977 0 P 0
L 6.0048425 2.3932284 6.0048425 2.434063 56 P 0
L 6.0103543 2.3388977 6.0409764 2.3695198 0 P 0
L 6.0316929 3.701063 6.0778425 3.701063 2 P 0
L 6.0409764 2.3695198 6.0563701 2.3695198 0 P 0
L 6.0488425 2.171063 6.0933464 2.171063 56 P 0
L 6.0563701 2.3695198 6.0648425 2.3779922 0 P 0
L 6.0648425 2.3441339 6.0679134 2.341063 0 P 0
L 6.0679134 2.341063 6.1574016 2.341063 0 P 0
L 6.0778425 3.701063 6.1198425 3.743063 2 P 0
L 6.0900079 3.556063 6.0900079 3.5615748 2 P 0
L 6.0900079 3.5615748 6.0941812 3.5657481 2 P 0
L 6.0941812 3.554063 6.0941812 3.5657481 2 P 0
L 6.0941812 3.554063 6.1508425 3.554063 2 P 0
L 6.1198425 3.743063 6.1198425 3.8198425 2 P 0
L 6.1228425 2.4338976 6.1283543 2.4338976 0 P 0
L 6.1228425 2.4882283 6.1870471 2.4882283 2 P 0
L 6.1283543 2.4338976 6.1385276 2.4237243 0 P 0
L 6.1385276 2.4182125 6.1385276 2.4237243 0 P 0
L 6.1385276 2.4182125 6.1471429 2.4095972 0 P 0
L 6.1471429 2.3982835 6.1471429 2.4095972 0 P 0
L 6.1471429 2.3982835 6.1543634 2.391063 0 P 0
L 6.1508425 3.554063 6.1628425 3.566063 2 P 0
L 6.1543634 2.391063 6.1574016 2.391063 0 P 0
L 6.1563385 2.171063 6.1563385 2.2399999 0 P 0
L 6.1563385 2.2399999 6.1574016 2.241063 0 P 0
L 6.1574016 2.291063 6.1849607 2.291063 0 P 0
L 6.1574016 2.391063 6.1849607 2.391063 0 P 0
L 6.1628425 3.566063 6.2029921 3.566063 2 P 0
L 6.1849607 2.291063 6.2348425 2.2411812 0 P 0
L 6.1849607 2.391063 6.2449607 2.451063 0 P 0
L 6.1870471 2.4882283 6.1998818 2.501063 2 P 0
L 6.1979921 3.5884481 6.1979921 3.701063 2 P 0
L 6.1979921 3.5884481 6.2001968 3.5862434 2 P 0
L 6.1979921 3.701063 6.1979921 3.7058195 2 P 0
L 6.1979921 3.7058195 6.2007874 3.7086148 2 P 0
L 6.1998818 2.501063 6.2848425 2.501063 2 P 0
L 6.2001968 3.5688583 6.2001968 3.5862434 2 P 0
L 6.2001968 3.5688583 6.2029921 3.566063 2 P 0
L 6.2007874 3.7086148 6.2263313 3.7086148 2 P 0
L 6.2073228 4.1371654 6.253937 4.0905512 2 P 0
L 6.2263313 3.7086148 6.253937 3.7362205 2 P 0
L 6.2348425 2.1288977 6.2390158 2.133071 2 P 0
L 6.2348425 2.1832284 6.2348425 2.2411812 0 P 0
L 6.2390158 2.133071 6.2649607 2.133071 2 P 0
L 6.2449607 2.451063 6.3126772 2.451063 0 P 0
L 6.253937 2.6732284 6.253937 2.7559055 2 P 0
L 6.253937 2.6732284 6.2711024 2.656063 2 P 0
L 6.253937 2.7559055 6.3720472 2.7559055 2 P 0
L 6.253937 2.8267717 6.253937 2.9094488 2 P 0
L 6.253937 3.7362205 6.253937 4.0905512 2 P 0
L 6.2649607 2.133071 6.281496 2.1496063 2 P 0
L 6.2711024 2.656063 6.3279134 2.656063 2 P 0
L 6.2748425 2.391063 6.3522834 2.391063 56 P 0
L 6.281496 2.1496063 6.281496 2.1929135 2 P 0
L 6.281496 2.1929135 6.281496 2.2716535 2 P 0
L 6.281496 2.1929135 6.2931299 2.1812796 2 P 0
L 6.281496 2.2716535 6.3009055 2.291063 2 P 0
L 6.2824161 3.226063 6.3024161 3.246063 0 P 0
L 6.2848425 2.501063 6.3279134 2.501063 2 P 0
L 6.2931299 2.1812796 6.4246259 2.1812796 2 P 0
L 6.2948425 3.701063 6.3416929 3.701063 2 P 0
L 6.3009055 2.291063 6.3522834 2.291063 2 P 0
L 6.3024161 3.246063 6.3431267 3.246063 0 P 0
L 6.3048425 3.121063 6.410433 3.121063 0 P 0
L 6.3094161 3.199063 6.3114161 3.201063 0 P 0
L 6.3114161 3.201063 6.3318621 3.201063 0 P 0
L 6.3198425 1.3750394 6.3198425 1.4601181 2 P 0
L 6.3198425 1.3750394 6.3641732 1.3307087 2 P 0
L 6.3198425 1.8420079 6.3690551 1.8420079 0 P 0
L 6.3279134 2.501063 6.3279134 2.556063 2 P 0
L 6.3279134 2.556063 6.3279134 2.611063 2 P 0
L 6.3279134 2.611063 6.3279134 2.656063 2 P 0
L 6.3318621 3.201063 6.3620196 3.2312205 0 P 0
L 6.3348425 2.1106299 6.3954094 2.1106299 56 P 0
L 6.3348425 3.266063 6.3348425 3.2697769 0 P 0
L 6.3348425 3.266063 6.3363732 3.2675937 0 P 0
L 6.3363732 3.2675937 6.3363732 3.2871606 0 P 0
L 6.3363732 3.2871606 6.3594757 3.3102631 0 P 0
L 6.3398425 3.151063 6.3412598 3.1524803 0 P 0
L 6.3412598 3.1524803 6.3883268 3.1524803 0 P 0
L 6.3431267 3.246063 6.3479692 3.2509055 0 P 0
L 6.3466929 3.566063 6.3810237 3.566063 2 P 0
L 6.3479692 3.2509055 6.3883268 3.2509055 0 P 0
L 6.3522834 2.241063 6.4683464 2.241063 0 P 0
L 6.3522834 2.341063 6.3971259 2.341063 0 P 0
L 6.3547483 3.3311384 6.356241 3.3296457 0 P 0
L 6.356241 3.3296457 6.3883268 3.3296457 0 P 0
L 6.3594757 3.3102631 6.3880243 3.3102631 0 P 0
L 6.3617717 2.501063 6.3978425 2.501063 56 P 0
L 6.3617717 2.556063 6.3968425 2.556063 56 P 0
L 6.3617717 2.611063 6.3968425 2.611063 56 P 0
L 6.3617717 2.656063 6.3978425 2.656063 56 P 0
L 6.3620196 3.2312205 6.3883268 3.2312205 0 P 0
L 6.3641732 1.3307087 6.6673228 1.3307087 2 P 0
L 6.3670079 2.451063 6.3690079 2.453063 56 P 0
L 6.3690079 2.453063 6.3988425 2.453063 56 P 0
L 6.3690551 1.8420079 6.4816142 1.954567 0 P 0
L 6.3720472 2.7559055 6.4547244 2.7559055 2 P 0
L 6.3720472 2.8267717 6.3720472 2.9094488 2 P 0
L 6.3799607 3.3099606 6.3883268 3.3099606 0 P 0
L 6.3810237 3.566063 6.4143701 3.5994094 2 P 0
L 6.3880243 3.3102631 6.3883268 3.3099606 0 P 0
L 6.3954094 2.1106299 6.3958425 2.111063 56 P 0
L 6.3968425 2.611063 6.3978425 2.610063 56 P 0
L 6.3971259 2.341063 6.4356299 2.302559 0 P 0
L 6.3978425 2.656063 6.3988425 2.657063 56 P 0
L 6.4098425 3.371063 6.4248425 3.371063 0 P 0
L 6.410433 3.121063 6.4203149 3.1309449 0 P 0
L 6.4143701 3.5994094 6.4143701 3.726378 2 P 0
L 6.4143701 3.726378 6.4902756 3.8022835 2 P 0
L 6.4203149 3.1309449 6.4203149 3.1500197 0 P 0
L 6.4203149 3.3321063 6.4212362 3.331185 0 P 0
L 6.4212362 3.3146693 6.4212362 3.331185 0 P 0
L 6.4212362 3.3146693 6.4448425 3.291063 0 P 0
L 6.4246259 2.1812796 6.4248425 2.181063 2 P 0
L 6.4248425 2.181063 6.5478478 2.181063 2 P 0
L 6.4248425 3.371063 6.44 3.3559055 0 P 0
L 6.4356299 2.302559 6.4698425 2.302559 0 P 0
L 6.4394094 3.0264961 6.4394094 3.071063 56 P 0
L 6.4394094 3.0264961 6.4568425 3.009063 56 P 0
L 6.4398425 3.191063 6.44 3.1909055 0 P 0
L 6.44 3.1500197 6.44 3.1909055 0 P 0
L 6.44 3.3321063 6.44 3.3559055 0 P 0
L 6.4475772 3.396063 6.459685 3.3839552 0 P 0
L 6.4547244 2.7559055 6.4901575 2.7913386 2 P 0
L 6.459685 3.3321063 6.459685 3.3839552 0 P 0
L 6.4598425 3.1500197 6.4605433 3.1493189 0 P 0
L 6.4598425 3.1500197 6.4607638 3.150941 0 P 0
L 6.4605433 3.1267008 6.4605433 3.1493189 0 P 0
L 6.4605433 3.1267008 6.5102756 3.0769685 0 P 0
L 6.4607638 3.150941 6.4607638 3.1646241 0 P 0
L 6.4607638 3.1646241 6.4694783 3.1733386 0 P 0
L 6.4683464 2.241063 6.4698425 2.2395669 0 P 0
L 6.4694783 3.1733386 6.4892619 3.1733386 0 P 0
L 6.4698425 2.302559 6.6431101 2.302559 0 P 0
L 6.4768425 3.231063 6.477 3.2312205 56 P 0
L 6.477 3.2312205 6.5113582 3.2312205 56 P 0
L 6.4793701 3.1437794 6.4794488 3.1437007 58 P 0
L 6.4793701 3.3321063 6.4793701 3.4255906 0 P 0
L 6.4793701 3.4255906 6.4798425 3.426063 0 P 0
L 6.4794488 3.1327559 6.4794488 3.1437007 58 P 0
L 6.4794488 3.1327559 6.4871417 3.125063 58 P 0
L 6.4816142 1.954567 6.5198425 1.954567 0 P 0
L 6.4871417 3.125063 6.5514661 3.125063 58 P 0
L 6.4892619 3.1733386 6.4904351 3.1721654 0 P 0
L 6.4901575 2.7913386 6.6691732 2.7913386 2 P 0
L 6.4902756 3.8022835 6.5657087 3.8022835 2 P 0
L 6.4904351 3.1721654 6.5113582 3.1721654 0 P 0
L 6.5098425 3.456063 6.5113582 3.4545473 0 P 0
L 6.5102756 2.9680709 6.5102756 3.071063 2 P 0
L 6.5102756 2.9680709 6.5492126 2.9291339 2 P 0
L 6.5102756 3.071063 6.5102756 3.0769685 0 P 0
L 6.5102756 3.071063 6.5122047 3.0729921 0 P 0
L 6.5113582 3.1918504 6.6041339 3.1918504 0 P 0
L 6.5113582 3.2115354 6.5527952 3.2115354 0 P 0
L 6.5113582 3.3296457 6.5113582 3.4545473 0 P 0
L 6.5122047 3.0729921 6.5848425 3.0729921 0 P 0
L 6.5198425 1.9535827 6.5198425 1.954567 0 P 0
L 6.5198425 1.9535827 6.5423622 1.931063 0 P 0
L 6.5198425 2.0175591 6.5333464 2.031063 0 P 0
L 6.5333464 2.031063 6.6374016 2.031063 0 P 0
L 6.5423622 1.931063 6.6374016 1.931063 0 P 0
L 6.5478478 2.181063 6.5872572 2.2204724 2 P 0
L 6.5488425 1.531063 6.6294094 1.531063 56 P 0
L 6.5492126 2.9291339 6.6397637 2.9291339 2 P 0
L 6.5514661 3.125063 6.55597 3.1295669 58 P 0
L 6.5527952 3.2115354 6.6048425 3.2635827 0 P 0
L 6.55597 3.1295669 6.6048425 3.1295669 58 P 0
L 6.5657087 3.8022835 6.5694882 3.806063 2 P 0
L 6.5694882 3.806063 6.7348425 3.806063 2 P 0
L 6.5848425 3.0391338 6.6197717 3.0391338 56 P 0
L 6.5872572 2.2204724 6.7106299 2.2204724 2 P 0
L 6.6018425 1.777063 6.6028425 1.776063 56 P 0
L 6.6028425 1.612063 6.6038425 1.611063 56 P 0
L 6.6028425 1.672063 6.6038425 1.671063 56 P 0
L 6.6028425 1.722063 6.6038425 1.721063 56 P 0
L 6.6028425 1.776063 6.6429133 1.776063 56 P 0
L 6.6038425 1.611063 6.6429133 1.611063 56 P 0
L 6.6038425 1.671063 6.6429133 1.671063 56 P 0
L 6.6038425 1.721063 6.6429133 1.721063 56 P 0
L 6.6041339 3.1918504 6.6048425 3.192559 0 P 0
L 6.6048425 3.1295669 6.6051969 3.1299213 58 P 0
L 6.6048425 3.192559 6.7049842 3.192559 0 P 0
L 6.6048425 3.2635827 6.6048425 3.264567 0 P 0
L 6.6048425 3.264567 6.7049842 3.264567 0 P 0
L 6.6048425 3.3275591 6.6183464 3.341063 56 P 0
L 6.6051969 3.1299213 6.6476378 3.1299213 58 P 0
L 6.6078425 2.176063 6.6502756 2.176063 56 P 0
L 6.6183464 3.341063 6.6488425 3.341063 56 P 0
L 6.6197717 3.0391338 6.6268425 3.032063 56 P 0
L 6.6288425 1.372063 6.6294094 1.3726299 56 P 0
L 6.6294094 1.3726299 6.6294094 1.421063 56 P 0
L 6.6374016 1.881063 6.6998425 1.881063 56 P 0
L 6.6374016 1.981063 6.6916929 1.981063 2 P 0
L 6.6397637 2.9291339 6.6798425 2.8890551 2 P 0
L 6.6431101 2.302559 6.6798425 2.3392914 0 P 0
L 6.6502756 2.176063 6.6598425 2.1664961 56 P 0
L 6.6598425 2.0956299 6.6665519 2.1023393 2 P 0
L 6.6665519 2.1023393 6.7004416 2.1023393 2 P 0
L 6.6673228 1.3307087 6.7002756 1.3636615 2 P 0
L 6.6691732 2.7913386 6.6798425 2.8020079 2 P 0
L 6.6767716 1.5604725 6.6767716 1.611063 2 P 0
L 6.6767716 1.5604725 6.7002756 1.5369685 2 P 0
L 6.6767716 1.611063 6.6767716 1.671063 2 P 0
L 6.6767716 1.671063 6.6767716 1.721063 2 P 0
L 6.6767716 1.721063 6.6767716 1.776063 2 P 0
L 6.6767716 1.776063 6.8081889 1.776063 2 P 0
L 6.6798425 2.3392914 6.6798425 2.4201181 0 P 0
L 6.6798425 2.8020079 6.6798425 2.8890551 2 P 0
L 6.6858425 1.828063 6.7185038 1.828063 56 P 0
L 6.6916929 1.981063 6.7121574 2.0015275 2 P 0
L 6.7002756 1.3636615 6.7002756 1.421063 2 P 0
L 6.7002756 1.421063 6.7002756 1.531063 2 P 0
L 6.7002756 1.531063 6.7002756 1.5369685 2 P 0
L 6.7004416 2.1023393 6.7121574 2.1140551 2 P 0
L 6.7049842 3.192559 6.7265748 3.1709684 0 P 0
L 6.7049842 3.264567 6.7265748 3.2861576 0 P 0
L 6.7106299 2.2204724 6.75 2.1811023 2 P 0
L 6.7121574 2.0015275 6.7121574 2.1140551 2 P 0
L 6.7121574 2.1140551 6.7121574 2.1353858 2 P 0
L 6.7121574 2.1353858 6.7199999 2.1432283 2 P 0
L 6.7185038 1.828063 6.7276771 1.8188897 56 P 0
L 6.7199999 2.1432283 6.7443307 2.1432283 2 P 0
L 6.7265748 3.1680709 6.7265748 3.1709684 0 P 0
L 6.7265748 3.2861576 6.7265748 3.2940551 0 P 0
L 6.7276771 1.816063 6.7276771 1.8188897 56 P 0
L 6.7348425 3.806063 6.9001969 3.806063 2 P 0
L 6.7443307 2.1432283 6.7498425 2.1432283 2 P 0
L 6.7443307 2.1432283 6.75 2.1488976 2 P 0
L 6.7498425 2.0359448 6.7498425 2.0888976 0 P 0
L 6.7498425 2.0359448 6.8047243 1.981063 0 P 0
L 6.75 2.1488976 6.75 2.1811023 2 P 0
L 6.7820077 1.8745275 6.7820078 1.816063 0 P 0
L 6.7820077 1.8745275 6.7885431 1.8810629 0 P 0
L 6.7885431 1.8810629 6.8322834 1.881063 0 P 0
L 6.8047243 1.881063 6.8322834 1.881063 0 P 0
L 6.8047243 1.981063 6.8322834 1.981063 0 P 0
L 6.8081889 1.776063 6.8426771 1.8105512 2 P 0
L 6.8322834 1.881063 6.8807481 1.881063 0 P 0
L 6.8322834 1.931063 6.9317716 1.931063 0 P 0
L 6.8322834 2.031063 6.836126 2.031063 0 P 0
L 6.836126 2.031063 6.8433465 2.0382835 0 P 0
L 6.8426771 1.6682284 6.8426771 1.8105512 2 P 0
L 6.8426771 1.6682284 6.8448425 1.666063 2 P 0
L 6.8426771 1.8105512 6.8426771 1.816063 2 P 0
L 6.8433465 2.0382835 6.8433465 2.096063 0 P 0
L 6.8448425 1.661063 6.8448425 1.666063 2 P 0
L 6.8807481 1.881063 6.8970078 1.8648033 0 P 0
L 6.8970078 1.816063 6.8970078 1.8648033 0 P 0
L 6.9063386 2.096063 6.9488425 2.096063 56 P 0
L 6.9317716 1.931063 6.9398425 1.9229921 0 P 0
L 6.9398425 1.8891338 7.0046064 1.8891338 0 P 0
L 6.9488425 2.096063 6.9498425 2.095063 56 P 0
L 6.9744094 1.9399606 7.0115747 1.9399606 56 P 0
L 7.0046064 1.8891338 7.0098425 1.8838977 0 P 0
L 7.0098425 1.9382284 7.0107086 1.9390945 56 P 0
L 7.0115747 1.9399606 7.0155043 1.9438902 56 P 0
P 0.0998425 0.806063 73 P 0 0 ;0=62,1=0
P 0.0998425 1.006063 73 P 0 0 ;0=62,1=0
P 0.0998425 1.331063 73 P 0 0 ;0=62,1=0
P 0.0998425 1.531063 73 P 0 0 ;0=62,1=0
P 0.0998425 1.856063 73 P 0 0 ;0=62,1=0
P 0.0998425 2.056063 73 P 0 0 ;0=62,1=0
P 0.0998425 2.381063 73 P 0 0 ;0=62,1=0
P 0.0998425 2.581063 73 P 0 0 ;0=62,1=0
P 0.1998425 0.906063 72 P 0 0 ;0=61,1=0
P 0.1998425 1.431063 72 P 0 0 ;0=61,1=0
P 0.1998425 1.956063 72 P 0 0 ;0=61,1=0
P 0.1998425 2.481063 72 P 0 0 ;0=61,1=0
P 0.285433 4.152063 78 P 0 0 ;0=68,1=0
P 0.2854331 0.3681102 78 P 0 0 ;0=68,1=0
P 0.2998425 0.806063 73 P 0 0 ;0=62,1=0
P 0.2998425 1.006063 73 P 0 0 ;0=62,1=0
P 0.2998425 1.331063 73 P 0 0 ;0=62,1=0
P 0.2998425 1.531063 73 P 0 0 ;0=62,1=0
P 0.2998425 1.856063 73 P 0 0 ;0=62,1=0
P 0.2998425 2.056063 73 P 0 0 ;0=62,1=0
P 0.2998425 2.381063 73 P 0 0 ;0=62,1=0
P 0.2998425 2.581063 73 P 0 0 ;0=62,1=0
P 0.5948031 0.906063 11 P 0 0 ;0=8,1=0,2
P 0.5948031 1.431063 11 P 0 0 ;0=8,1=0,2
P 0.5948031 1.956063 11 P 0 0 ;0=8,1=0,2
P 0.5948031 2.481063 11 P 0 0 ;0=8,1=0,2
P 0.6389685 4.0388976 52 P 0 0 ;0=49,1=0,2
P 0.6389685 4.0932283 52 P 0 0 ;0=49,1=0,2
P 0.6448425 4.1975197 38 P 0 0 ;0=35,1=0,2
P 0.6448425 4.2546063 38 P 0 0 ;0=35,1=0,2
P 0.6548425 0.8479921 12 P 0 0 ;0=9,1=0,2
P 0.6548425 0.9641339 12 P 0 0 ;0=9,1=0,2
P 0.6548425 1.3729921 12 P 0 0 ;0=9,1=0,2
P 0.6548425 1.4891339 12 P 0 0 ;0=9,1=0,2
P 0.6548425 1.8979921 12 P 0 0 ;0=9,1=0,2
P 0.6548425 2.0141339 12 P 0 0 ;0=9,1=0,2
P 0.6548425 2.4229921 12 P 0 0 ;0=9,1=0,2
P 0.6548425 2.5391339 12 P 0 0 ;0=9,1=0,2
P 0.8406351 4.0388976 52 P 0 0 ;0=49,1=0,2
P 0.8406351 4.0932283 52 P 0 0 ;0=49,1=0,2
P 0.8465091 4.1975197 38 P 0 0 ;0=35,1=0,2
P 0.8465091 4.2546063 38 P 0 0 ;0=35,1=0,2
P 0.9005905 1.7470472 33 P 0 0 ;0=30,1=0,2
P 0.9015747 0.7185038 33 P 0 0 ;0=30,1=0,2
P 0.9045275 1.2244094 33 P 0 0 ;0=30,1=0,2
P 0.9084645 2.2844487 33 P 0 0 ;0=30,1=0,2
P 0.9326378 0.906063 37 P 0 0 ;0=34,1=0,2
P 0.9326378 1.431063 37 P 0 0 ;0=34,1=0,2
P 0.9326378 1.956063 37 P 0 0 ;0=34,1=0,2
P 0.9326378 2.481063 37 P 0 0 ;0=34,1=0,2
P 0.9596456 1.7470472 33 P 0 0 ;0=30,1=0,2
P 0.9606298 0.7185038 33 P 0 0 ;0=30,1=0,2
P 0.9635826 1.2244094 33 P 0 0 ;0=30,1=0,2
P 0.9675196 2.2844487 33 P 0 0 ;0=30,1=0,2
P 1.0423017 4.0388976 52 P 0 0 ;0=49,1=0,2
P 1.0423017 4.0932283 52 P 0 0 ;0=49,1=0,2
P 1.0481757 4.1975197 38 P 0 0 ;0=35,1=0,2
P 1.0481757 4.2546063 38 P 0 0 ;0=35,1=0,2
P 1.1570472 0.906063 37 P 0 0 ;0=34,1=0,2
P 1.1570472 1.431063 37 P 0 0 ;0=34,1=0,2
P 1.1570472 1.956063 37 P 0 0 ;0=34,1=0,2
P 1.1570472 2.481063 37 P 0 0 ;0=34,1=0,2
P 1.2439683 4.0388976 52 P 0 0 ;0=49,1=0,2
P 1.2439683 4.0932283 52 P 0 0 ;0=49,1=0,2
P 1.2498423 4.1975197 38 P 0 0 ;0=35,1=0,2
P 1.2498423 4.2546063 38 P 0 0 ;0=35,1=0,2
P 1.3464567 3.9783465 55 P 0 0 ;0=52,1=0,2
P 1.3464567 4.0374016 55 P 0 0 ;0=52,1=0,2
P 1.3464567 4.0826772 55 P 0 0 ;0=52,1=0,2
P 1.3464567 4.1417323 55 P 0 0 ;0=52,1=0,2
P 1.4576771 4.053937 75 P 0 0 ;0=64,1=0
P 1.4576771 4.153937 75 P 0 0 ;0=64,1=0
P 1.4576771 4.253937 76 P 0 0 ;0=64,1=0
P 1.6171125 1.319673 44 P 0 0 ;0=41,1=0,2
P 1.6171125 1.339363 44 P 0 0 ;0=41,1=0,2
P 1.6171125 1.359043 44 P 0 0 ;0=41,1=0,2
P 1.6171125 1.378733 44 P 0 0 ;0=41,1=0,2
P 1.6171125 1.398413 44 P 0 0 ;0=41,1=0,2
P 1.6171125 1.418103 44 P 0 0 ;0=41,1=0,2
P 1.6171125 1.437783 44 P 0 0 ;0=41,1=0,2
P 1.6171125 1.457473 44 P 0 0 ;0=41,1=0,2
P 1.6171125 1.477153 44 P 0 0 ;0=41,1=0,2
P 1.6171125 1.496843 44 P 0 0 ;0=41,1=0,2
P 1.6171125 1.516523 44 P 0 0 ;0=41,1=0,2
P 1.6171125 1.536213 44 P 0 0 ;0=41,1=0,2
P 1.6171125 1.555893 44 P 0 0 ;0=41,1=0,2
P 1.6171125 1.575583 44 P 0 0 ;0=41,1=0,2
P 1.6171125 1.595263 44 P 0 0 ;0=41,1=0,2
P 1.6171125 1.614953 44 P 0 0 ;0=41,1=0,2
P 1.6171125 1.634633 44 P 0 0 ;0=41,1=0,2
P 1.6171125 1.654323 44 P 0 0 ;0=41,1=0,2
P 1.6171125 1.674003 44 P 0 0 ;0=41,1=0,2
P 1.6171125 1.693693 44 P 0 0 ;0=41,1=0,2
P 1.6171125 1.713373 44 P 0 0 ;0=41,1=0,2
P 1.6171125 1.733063 44 P 0 0 ;0=41,1=0,2
P 1.6171125 1.752743 44 P 0 0 ;0=41,1=0,2
P 1.6171125 1.772433 44 P 0 0 ;0=41,1=0,2
P 1.6171125 1.792113 44 P 0 0 ;0=41,1=0,2
P 1.6171125 1.811803 44 P 0 0 ;0=41,1=0,2
P 1.6171125 1.831483 44 P 0 0 ;0=41,1=0,2
P 1.6171125 1.851173 44 P 0 0 ;0=41,1=0,2
P 1.6171125 1.870853 44 P 0 0 ;0=41,1=0,2
P 1.6171125 1.890543 44 P 0 0 ;0=41,1=0,2
P 1.6171125 1.910223 44 P 0 0 ;0=41,1=0,2
P 1.6171125 1.929913 44 P 0 0 ;0=41,1=0,2
P 1.6171125 1.949593 44 P 0 0 ;0=41,1=0,2
P 1.6171125 1.969283 44 P 0 0 ;0=41,1=0,2
P 1.6171125 1.988963 44 P 0 0 ;0=41,1=0,2
P 1.6171125 2.008653 44 P 0 0 ;0=41,1=0,2
P 1.6171125 2.028333 44 P 0 0 ;0=41,1=0,2
P 1.6171125 2.048023 44 P 0 0 ;0=41,1=0,2
P 1.6171125 2.067703 44 P 0 0 ;0=41,1=0,2
P 1.6171125 2.087393 44 P 0 0 ;0=41,1=0,2
P 1.631559 4.024563 14 P 0 0 ;0=11,1=0,2
P 1.631559 4.049563 14 P 0 0 ;0=11,1=0,2
P 1.631559 4.074563 14 P 0 0 ;0=11,1=0,2
P 1.631559 4.099563 14 P 0 0 ;0=11,1=0,2
P 1.631559 4.124563 14 P 0 0 ;0=11,1=0,2
P 1.631559 4.149563 14 P 0 0 ;0=11,1=0,2
P 1.631559 4.174563 14 P 0 0 ;0=11,1=0,2
P 1.631559 4.199563 14 P 0 0 ;0=11,1=0,2
P 1.6643465 4.273063 50 P 0 0 ;0=47,1=0,2
P 1.6968325 1.275383 45 P 0 0 ;0=42,1=0,2
P 1.6968325 1.309833 74 P 0 0 ;0=63,1=0
P 1.6968325 2.097233 74 P 0 0 ;0=63,1=0
P 1.6968325 2.131683 45 P 0 0 ;0=42,1=0,2
P 1.7273386 4.273063 50 P 0 0 ;0=47,1=0,2
P 1.7765525 1.319673 44 P 0 0 ;0=41,1=0,2
P 1.7765525 1.339363 44 P 0 0 ;0=41,1=0,2
P 1.7765525 1.359043 44 P 0 0 ;0=41,1=0,2
P 1.7765525 1.378733 44 P 0 0 ;0=41,1=0,2
P 1.7765525 1.398413 44 P 0 0 ;0=41,1=0,2
P 1.7765525 1.418103 44 P 0 0 ;0=41,1=0,2
P 1.7765525 1.437783 44 P 0 0 ;0=41,1=0,2
P 1.7765525 1.457473 44 P 0 0 ;0=41,1=0,2
P 1.7765525 1.477153 44 P 0 0 ;0=41,1=0,2
P 1.7765525 1.496843 44 P 0 0 ;0=41,1=0,2
P 1.7765525 1.516523 44 P 0 0 ;0=41,1=0,2
P 1.7765525 1.536213 44 P 0 0 ;0=41,1=0,2
P 1.7765525 1.555893 44 P 0 0 ;0=41,1=0,2
P 1.7765525 1.575583 44 P 0 0 ;0=41,1=0,2
P 1.7765525 1.595263 44 P 0 0 ;0=41,1=0,2
P 1.7765525 1.614953 44 P 0 0 ;0=41,1=0,2
P 1.7765525 1.634633 44 P 0 0 ;0=41,1=0,2
P 1.7765525 1.654323 44 P 0 0 ;0=41,1=0,2
P 1.7765525 1.674003 44 P 0 0 ;0=41,1=0,2
P 1.7765525 1.693693 44 P 0 0 ;0=41,1=0,2
P 1.7765525 1.713373 44 P 0 0 ;0=41,1=0,2
P 1.7765525 1.733063 44 P 0 0 ;0=41,1=0,2
P 1.7765525 1.752743 44 P 0 0 ;0=41,1=0,2
P 1.7765525 1.772433 44 P 0 0 ;0=41,1=0,2
P 1.7765525 1.792113 44 P 0 0 ;0=41,1=0,2
P 1.7765525 1.811803 44 P 0 0 ;0=41,1=0,2
P 1.7765525 1.831483 44 P 0 0 ;0=41,1=0,2
P 1.7765525 1.851173 44 P 0 0 ;0=41,1=0,2
P 1.7765525 1.870853 44 P 0 0 ;0=41,1=0,2
P 1.7765525 1.890543 44 P 0 0 ;0=41,1=0,2
P 1.7765525 1.910223 44 P 0 0 ;0=41,1=0,2
P 1.7765525 1.929913 44 P 0 0 ;0=41,1=0,2
P 1.7765525 1.949593 44 P 0 0 ;0=41,1=0,2
P 1.7765525 1.969283 44 P 0 0 ;0=41,1=0,2
P 1.7765525 1.988963 44 P 0 0 ;0=41,1=0,2
P 1.7765525 2.008653 44 P 0 0 ;0=41,1=0,2
P 1.7765525 2.028333 44 P 0 0 ;0=41,1=0,2
P 1.7765525 2.048023 44 P 0 0 ;0=41,1=0,2
P 1.7765525 2.067703 44 P 0 0 ;0=41,1=0,2
P 1.7765525 2.087393 44 P 0 0 ;0=41,1=0,2
P 1.7972451 0.1377953 27 P 0 0 ;0=24,1=0,2
P 1.8024094 4.276063 48 P 0 0 ;0=45,1=0,2
P 1.836122 0.2691929 60 P 0 0
P 1.8366151 0.1377953 27 P 0 0 ;0=24,1=0,2
P 1.8461259 4.024563 14 P 0 0 ;0=11,1=0,2
P 1.8461259 4.049563 14 P 0 0 ;0=11,1=0,2
P 1.8461259 4.074563 14 P 0 0 ;0=11,1=0,2
P 1.8461259 4.099563 14 P 0 0 ;0=11,1=0,2
P 1.8461259 4.124563 14 P 0 0 ;0=11,1=0,2
P 1.8461259 4.149563 14 P 0 0 ;0=11,1=0,2
P 1.8461259 4.174563 14 P 0 0 ;0=11,1=0,2
P 1.8461259 4.199563 14 P 0 0 ;0=11,1=0,2
P 1.8732756 4.276063 48 P 0 0 ;0=45,1=0,2
P 1.8759851 0.1377953 27 P 0 0 ;0=24,1=0,2
P 1.9153551 0.1377953 27 P 0 0 ;0=24,1=0,2
P 1.9338425 4.0748977 52 P 0 0 ;0=49,1=0,2
P 1.9338425 4.1292284 52 P 0 0 ;0=49,1=0,2
P 1.9547251 0.1377953 27 P 0 0 ;0=24,1=0,2
P 1.9940951 0.1377953 27 P 0 0 ;0=24,1=0,2
P 2.0334651 0.1377953 27 P 0 0 ;0=24,1=0,2
P 2.0433071 4.057874 75 P 0 0 ;0=64,1=0
P 2.0433071 4.157874 75 P 0 0 ;0=64,1=0
P 2.0433071 4.257874 76 P 0 0 ;0=64,1=0
P 2.0728351 0.1377953 27 P 0 0 ;0=24,1=0,2
P 2.1122051 0.1377953 27 P 0 0 ;0=24,1=0,2
P 2.1123027 0.269685 59 P 0 0
P 2.1398425 3.6641339 41 P 0 0 ;0=38,1=0,2
P 2.1398425 3.6979922 41 P 0 0 ;0=38,1=0,2
P 2.1468425 2.6248976 52 P 0 0 ;0=49,1=0,2
P 2.1468425 2.6792283 52 P 0 0 ;0=49,1=0,2
P 2.1515748 4.0157481 55 P 0 0 ;0=52,1=0,2
P 2.1515748 4.0748032 55 P 0 0 ;0=52,1=0,2
P 2.1515751 0.1377953 27 P 0 0 ;0=24,1=0,2
P 2.1686825 2.438533 47 P 0 0 ;0=44,1=0,2
P 2.1686925 0.958593 47 P 0 0 ;0=44,1=0,2
P 2.1909451 0.1377953 27 P 0 0 ;0=24,1=0,2
P 2.1996929 4.275063 8 P 0 0 ;0=5,1=0,2
P 2.2031325 2.438533 74 P 0 0 ;0=63,1=0
P 2.2031425 0.958593 74 P 0 0 ;0=63,1=0
P 2.2098425 3.6456299 39 P 0 0 ;0=36,1=0,2
P 2.2098425 3.7164961 39 P 0 0 ;0=36,1=0,2
P 2.2125984 4.0157481 55 P 0 0 ;0=52,1=0,2
P 2.2125984 4.0748032 55 P 0 0 ;0=52,1=0,2
P 2.2129725 2.358813 46 P 0 0 ;0=43,1=0,2
P 2.2129725 2.518253 46 P 0 0 ;0=43,1=0,2
P 2.2129825 0.878873 46 P 0 0 ;0=43,1=0,2
P 2.2129825 1.038313 46 P 0 0 ;0=43,1=0,2
P 2.2326625 2.358813 46 P 0 0 ;0=43,1=0,2
P 2.2326625 2.518253 46 P 0 0 ;0=43,1=0,2
P 2.2326725 0.878873 46 P 0 0 ;0=43,1=0,2
P 2.2326725 1.038313 46 P 0 0 ;0=43,1=0,2
P 2.2341417 4.1736851 6 P 0 0 ;0=3,1=0,2
P 2.2523425 2.358813 46 P 0 0 ;0=43,1=0,2
P 2.2523425 2.518253 46 P 0 0 ;0=43,1=0,2
P 2.2523525 0.878873 46 P 0 0 ;0=43,1=0,2
P 2.2523525 1.038313 46 P 0 0 ;0=43,1=0,2
P 2.2715433 4.275063 4 P 0 0 ;0=1,1=0,2
P 2.2720325 2.358813 46 P 0 0 ;0=43,1=0,2
P 2.2720325 2.518253 46 P 0 0 ;0=43,1=0,2
P 2.2720425 0.878873 46 P 0 0 ;0=43,1=0,2
P 2.2720425 1.038313 46 P 0 0 ;0=43,1=0,2
P 2.2813858 4.1703386 7 P 0 0 ;0=4,1=0,2
P 2.2917125 2.358813 46 P 0 0 ;0=43,1=0,2
P 2.2917125 2.518253 46 P 0 0 ;0=43,1=0,2
P 2.2917225 0.878873 46 P 0 0 ;0=43,1=0,2
P 2.2917225 1.038313 46 P 0 0 ;0=43,1=0,2
P 2.3069763 4.1703386 7 P 0 0 ;0=4,1=0,2
P 2.3090551 0.1377953 27 P 0 0 ;0=24,1=0,2
P 2.3114025 2.358813 46 P 0 0 ;0=43,1=0,2
P 2.3114025 2.518253 46 P 0 0 ;0=43,1=0,2
P 2.3114125 0.878873 46 P 0 0 ;0=43,1=0,2
P 2.3114125 1.038313 46 P 0 0 ;0=43,1=0,2
P 2.3310825 2.358813 46 P 0 0 ;0=43,1=0,2
P 2.3310825 2.518253 46 P 0 0 ;0=43,1=0,2
P 2.3310925 0.878873 46 P 0 0 ;0=43,1=0,2
P 2.3310925 1.038313 46 P 0 0 ;0=43,1=0,2
P 2.3325669 4.1703386 7 P 0 0 ;0=4,1=0,2
P 2.3348425 3.4045276 54 P 0 0 ;0=51,1=0,2
P 2.3348425 3.4832677 54 P 0 0 ;0=51,1=0,2
P 2.3348425 3.5620079 54 P 0 0 ;0=51,1=0,2
P 2.3348425 3.640748 54 P 0 0 ;0=51,1=0,2
P 2.3484251 0.1377953 27 P 0 0 ;0=24,1=0,2
P 2.3507725 2.358813 46 P 0 0 ;0=43,1=0,2
P 2.3507725 2.518253 46 P 0 0 ;0=43,1=0,2
P 2.3507825 0.878873 46 P 0 0 ;0=43,1=0,2
P 2.3507825 1.038313 46 P 0 0 ;0=43,1=0,2
P 2.3581575 4.1703386 7 P 0 0 ;0=4,1=0,2
P 2.3704525 2.358813 46 P 0 0 ;0=43,1=0,2
P 2.3704525 2.518253 46 P 0 0 ;0=43,1=0,2
P 2.3704625 0.878873 46 P 0 0 ;0=43,1=0,2
P 2.3704625 1.038313 46 P 0 0 ;0=43,1=0,2
P 2.3778425 4.275063 5 P 0 0 ;0=2,1=0,2
P 2.383748 4.1703386 7 P 0 0 ;0=4,1=0,2
P 2.3877951 0.1377953 27 P 0 0 ;0=24,1=0,2
P 2.3877954 2.8996063 55 P 0 0 ;0=52,1=0,2
P 2.3877954 2.9586614 55 P 0 0 ;0=52,1=0,2
P 2.3901425 2.358813 46 P 0 0 ;0=43,1=0,2
P 2.3901425 2.518253 46 P 0 0 ;0=43,1=0,2
P 2.3901525 0.878873 46 P 0 0 ;0=43,1=0,2
P 2.3901525 1.038313 46 P 0 0 ;0=43,1=0,2
P 2.4098225 2.358813 46 P 0 0 ;0=43,1=0,2
P 2.4098225 2.518253 46 P 0 0 ;0=43,1=0,2
P 2.4098325 0.878873 46 P 0 0 ;0=43,1=0,2
P 2.4098325 1.038313 46 P 0 0 ;0=43,1=0,2
P 2.4271651 0.1377953 27 P 0 0 ;0=24,1=0,2
P 2.4295125 2.358813 46 P 0 0 ;0=43,1=0,2
P 2.4295125 2.518253 46 P 0 0 ;0=43,1=0,2
P 2.4295225 0.878873 46 P 0 0 ;0=43,1=0,2
P 2.4295225 1.038313 46 P 0 0 ;0=43,1=0,2
P 2.4309921 4.1736851 6 P 0 0 ;0=3,1=0,2
P 2.4491925 2.358813 46 P 0 0 ;0=43,1=0,2
P 2.4491925 2.518253 46 P 0 0 ;0=43,1=0,2
P 2.4492025 0.878873 46 P 0 0 ;0=43,1=0,2
P 2.4492025 1.038313 46 P 0 0 ;0=43,1=0,2
P 2.4654409 4.275063 8 P 0 0 ;0=5,1=0,2
P 2.4665351 0.1377953 27 P 0 0 ;0=24,1=0,2
P 2.4688825 2.358813 46 P 0 0 ;0=43,1=0,2
P 2.4688825 2.518253 46 P 0 0 ;0=43,1=0,2
P 2.4688925 0.878873 46 P 0 0 ;0=43,1=0,2
P 2.4688925 1.038313 46 P 0 0 ;0=43,1=0,2
P 2.4885625 2.358813 46 P 0 0 ;0=43,1=0,2
P 2.4885625 2.518253 46 P 0 0 ;0=43,1=0,2
P 2.4885725 0.878873 46 P 0 0 ;0=43,1=0,2
P 2.4885725 1.038313 46 P 0 0 ;0=43,1=0,2
P 2.503937 0.5738189 53 P 0 0 ;0=50,1=0,2
P 2.503937 0.6072835 53 P 0 0 ;0=50,1=0,2
P 2.5059051 0.1377953 27 P 0 0 ;0=24,1=0,2
P 2.5082525 2.358813 46 P 0 0 ;0=43,1=0,2
P 2.5082525 2.518253 46 P 0 0 ;0=43,1=0,2
P 2.5082625 0.878873 46 P 0 0 ;0=43,1=0,2
P 2.5082625 1.038313 46 P 0 0 ;0=43,1=0,2
P 2.5098425 3.4045276 54 P 0 0 ;0=51,1=0,2
P 2.5098425 3.4832677 54 P 0 0 ;0=51,1=0,2
P 2.5098425 3.5620079 54 P 0 0 ;0=51,1=0,2
P 2.5098425 3.640748 54 P 0 0 ;0=51,1=0,2
P 2.5279325 2.358813 46 P 0 0 ;0=43,1=0,2
P 2.5279325 2.518253 46 P 0 0 ;0=43,1=0,2
P 2.5279425 0.878873 46 P 0 0 ;0=43,1=0,2
P 2.5279425 1.038313 46 P 0 0 ;0=43,1=0,2
P 2.5452751 0.1377953 27 P 0 0 ;0=24,1=0,2
P 2.5476225 2.358813 46 P 0 0 ;0=43,1=0,2
P 2.5476225 2.518253 46 P 0 0 ;0=43,1=0,2
P 2.5476325 0.878873 46 P 0 0 ;0=43,1=0,2
P 2.5476325 1.038313 46 P 0 0 ;0=43,1=0,2
P 2.5673025 2.358813 46 P 0 0 ;0=43,1=0,2
P 2.5673025 2.518253 46 P 0 0 ;0=43,1=0,2
P 2.5673125 0.878873 46 P 0 0 ;0=43,1=0,2
P 2.5673125 1.038313 46 P 0 0 ;0=43,1=0,2
P 2.5846451 0.1377953 27 P 0 0 ;0=24,1=0,2
P 2.5869925 2.358813 46 P 0 0 ;0=43,1=0,2
P 2.5869925 2.518253 46 P 0 0 ;0=43,1=0,2
P 2.5870025 0.878873 46 P 0 0 ;0=43,1=0,2
P 2.5870025 1.038313 46 P 0 0 ;0=43,1=0,2
P 2.6066725 2.358813 46 P 0 0 ;0=43,1=0,2
P 2.6066725 2.518253 46 P 0 0 ;0=43,1=0,2
P 2.6066825 0.878873 46 P 0 0 ;0=43,1=0,2
P 2.6066825 1.038313 46 P 0 0 ;0=43,1=0,2
P 2.6240151 0.1377953 27 P 0 0 ;0=24,1=0,2
P 2.6263625 2.358813 46 P 0 0 ;0=43,1=0,2
P 2.6263625 2.518253 46 P 0 0 ;0=43,1=0,2
P 2.6263725 0.878873 46 P 0 0 ;0=43,1=0,2
P 2.6263725 1.038313 46 P 0 0 ;0=43,1=0,2
P 2.6398425 3.5356299 39 P 0 0 ;0=36,1=0,2
P 2.6398425 3.6064961 39 P 0 0 ;0=36,1=0,2
P 2.6460425 2.358813 46 P 0 0 ;0=43,1=0,2
P 2.6460425 2.518253 46 P 0 0 ;0=43,1=0,2
P 2.6460525 0.878873 46 P 0 0 ;0=43,1=0,2
P 2.6460525 1.038313 46 P 0 0 ;0=43,1=0,2
P 2.6633851 0.1377953 27 P 0 0 ;0=24,1=0,2
P 2.6657325 2.358813 46 P 0 0 ;0=43,1=0,2
P 2.6657325 2.518253 46 P 0 0 ;0=43,1=0,2
P 2.6657425 0.878873 46 P 0 0 ;0=43,1=0,2
P 2.6657425 1.038313 46 P 0 0 ;0=43,1=0,2
P 2.6854125 2.358813 46 P 0 0 ;0=43,1=0,2
P 2.6854125 2.518253 46 P 0 0 ;0=43,1=0,2
P 2.6854225 0.878873 46 P 0 0 ;0=43,1=0,2
P 2.6854225 1.038313 46 P 0 0 ;0=43,1=0,2
P 2.694252 3.7503543 13 P 0 0 ;0=10,1=0,2
P 2.7027551 0.1377953 27 P 0 0 ;0=24,1=0,2
P 2.7051025 2.358813 46 P 0 0 ;0=43,1=0,2
P 2.7051025 2.518253 46 P 0 0 ;0=43,1=0,2
P 2.7051125 0.878873 46 P 0 0 ;0=43,1=0,2
P 2.7051125 1.038313 46 P 0 0 ;0=43,1=0,2
P 2.7198425 3.6617716 13 P 0 0 ;0=10,1=0,2
P 2.7247825 2.358813 46 P 0 0 ;0=43,1=0,2
P 2.7247825 2.518253 46 P 0 0 ;0=43,1=0,2
P 2.7247925 0.878873 46 P 0 0 ;0=43,1=0,2
P 2.7247925 1.038313 46 P 0 0 ;0=43,1=0,2
P 2.7248425 3.5591338 41 P 0 0 ;0=38,1=0,2
P 2.7248425 3.5929921 41 P 0 0 ;0=38,1=0,2
P 2.7421251 0.1377953 27 P 0 0 ;0=24,1=0,2
P 2.7444725 2.358813 46 P 0 0 ;0=43,1=0,2
P 2.7444725 2.518253 46 P 0 0 ;0=43,1=0,2
P 2.7444825 0.878873 46 P 0 0 ;0=43,1=0,2
P 2.7444825 1.038313 46 P 0 0 ;0=43,1=0,2
P 2.7454331 3.7503543 13 P 0 0 ;0=10,1=0,2
P 2.7568898 2.9372047 3 P 0 0 ;0=0,1=0,2
P 2.7568898 2.9872047 3 P 0 0 ;0=0,1=0,2
P 2.7568898 3.0372047 3 P 0 0 ;0=0,1=0,2
P 2.7568898 3.0872047 3 P 0 0 ;0=0,1=0,2
P 2.7568898 3.1372047 3 P 0 0 ;0=0,1=0,2
P 2.7568898 3.1872047 3 P 0 0 ;0=0,1=0,2
P 2.7568898 3.2372047 3 P 0 0 ;0=0,1=0,2
P 2.7568898 3.2872047 3 P 0 0 ;0=0,1=0,2
P 2.7641525 2.358813 46 P 0 0 ;0=43,1=0,2
P 2.7641525 2.518253 46 P 0 0 ;0=43,1=0,2
P 2.7641625 0.878873 46 P 0 0 ;0=43,1=0,2
P 2.7641625 1.038313 46 P 0 0 ;0=43,1=0,2
P 2.7814951 0.1377953 27 P 0 0 ;0=24,1=0,2
P 2.7838425 2.358813 46 P 0 0 ;0=43,1=0,2
P 2.7838425 2.518253 46 P 0 0 ;0=43,1=0,2
P 2.7838525 0.878873 46 P 0 0 ;0=43,1=0,2
P 2.7838525 1.038313 46 P 0 0 ;0=43,1=0,2
P 2.8035225 2.358813 46 P 0 0 ;0=43,1=0,2
P 2.8035225 2.518253 46 P 0 0 ;0=43,1=0,2
P 2.8035325 0.878873 46 P 0 0 ;0=43,1=0,2
P 2.8035325 1.038313 46 P 0 0 ;0=43,1=0,2
P 2.809252 3.7503543 13 P 0 0 ;0=10,1=0,2
P 2.8208651 0.1377953 27 P 0 0 ;0=24,1=0,2
P 2.8232125 2.358813 46 P 0 0 ;0=43,1=0,2
P 2.8232125 2.518253 46 P 0 0 ;0=43,1=0,2
P 2.8232225 0.878873 46 P 0 0 ;0=43,1=0,2
P 2.8232225 1.038313 46 P 0 0 ;0=43,1=0,2
P 2.8348425 3.6617716 13 P 0 0 ;0=10,1=0,2
P 2.8428925 2.358813 46 P 0 0 ;0=43,1=0,2
P 2.8428925 2.518253 46 P 0 0 ;0=43,1=0,2
P 2.8429025 0.878873 46 P 0 0 ;0=43,1=0,2
P 2.8429025 1.038313 46 P 0 0 ;0=43,1=0,2
P 2.8602351 0.1377953 27 P 0 0 ;0=24,1=0,2
P 2.8604331 3.7503543 13 P 0 0 ;0=10,1=0,2
P 2.8625825 2.358813 46 P 0 0 ;0=43,1=0,2
P 2.8625825 2.518253 46 P 0 0 ;0=43,1=0,2
P 2.8625925 0.878873 46 P 0 0 ;0=43,1=0,2
P 2.8625925 1.038313 46 P 0 0 ;0=43,1=0,2
P 2.8822625 2.358813 46 P 0 0 ;0=43,1=0,2
P 2.8822625 2.518253 46 P 0 0 ;0=43,1=0,2
P 2.8822725 0.878873 46 P 0 0 ;0=43,1=0,2
P 2.8822725 1.038313 46 P 0 0 ;0=43,1=0,2
P 2.8996051 0.1377953 27 P 0 0 ;0=24,1=0,2
P 2.9019525 2.358813 46 P 0 0 ;0=43,1=0,2
P 2.9019525 2.518253 46 P 0 0 ;0=43,1=0,2
P 2.9019625 0.878873 46 P 0 0 ;0=43,1=0,2
P 2.9019625 1.038313 46 P 0 0 ;0=43,1=0,2
P 2.9216325 2.358813 46 P 0 0 ;0=43,1=0,2
P 2.9216325 2.518253 46 P 0 0 ;0=43,1=0,2
P 2.9216425 0.878873 46 P 0 0 ;0=43,1=0,2
P 2.9216425 1.038313 46 P 0 0 ;0=43,1=0,2
P 2.9389751 0.1377953 27 P 0 0 ;0=24,1=0,2
P 2.9413225 2.358813 46 P 0 0 ;0=43,1=0,2
P 2.9413225 2.518253 46 P 0 0 ;0=43,1=0,2
P 2.9413325 0.878873 46 P 0 0 ;0=43,1=0,2
P 2.9413325 1.038313 46 P 0 0 ;0=43,1=0,2
P 2.9448425 3.6666929 24 P 0 0 ;0=21,1=0,2
P 2.9448425 3.7454331 24 P 0 0 ;0=21,1=0,2
P 2.9448425 3.951063 23 P 0 0 ;0=20,1=0,2
P 2.9448425 4.2211417 23 P 0 0 ;0=20,1=0,2
P 2.9610025 2.358813 46 P 0 0 ;0=43,1=0,2
P 2.9610025 2.518253 46 P 0 0 ;0=43,1=0,2
P 2.9610125 0.878873 46 P 0 0 ;0=43,1=0,2
P 2.9610125 1.038313 46 P 0 0 ;0=43,1=0,2
P 2.9783451 0.1377953 27 P 0 0 ;0=24,1=0,2
P 2.9806925 2.358813 46 P 0 0 ;0=43,1=0,2
P 2.9806925 2.518253 46 P 0 0 ;0=43,1=0,2
P 2.9807025 0.878873 46 P 0 0 ;0=43,1=0,2
P 2.9807025 1.038313 46 P 0 0 ;0=43,1=0,2
P 2.9905325 2.438533 74 P 0 0 ;0=63,1=0
P 2.9905425 0.958593 74 P 0 0 ;0=63,1=0
P 2.9948425 4.0861024 64 P 0 0 ;0=54,1=0
P 3.0177151 0.1377953 27 P 0 0 ;0=24,1=0,2
P 3.0249825 2.438533 47 P 0 0 ;0=44,1=0,2
P 3.0249925 0.958593 47 P 0 0 ;0=44,1=0,2
P 3.0448425 3.6666929 24 P 0 0 ;0=21,1=0,2
P 3.0448425 3.7454331 24 P 0 0 ;0=21,1=0,2
P 3.0448425 3.951063 23 P 0 0 ;0=20,1=0,2
P 3.0448425 4.2211417 23 P 0 0 ;0=20,1=0,2
P 3.0551181 0.5738189 53 P 0 0 ;0=50,1=0,2
P 3.0551181 0.6072835 53 P 0 0 ;0=50,1=0,2
P 3.0570851 0.1572953 28 P 0 0 ;0=25,1=0,2
P 3.0964551 0.1377953 27 P 0 0 ;0=24,1=0,2
P 3.1112205 2.9372047 3 P 0 0 ;0=0,1=0,2
P 3.1112205 2.9872047 3 P 0 0 ;0=0,1=0,2
P 3.1112205 3.0372047 3 P 0 0 ;0=0,1=0,2
P 3.1112205 3.0872047 3 P 0 0 ;0=0,1=0,2
P 3.1112205 3.1372047 3 P 0 0 ;0=0,1=0,2
P 3.1112205 3.1872047 3 P 0 0 ;0=0,1=0,2
P 3.1112205 3.2372047 3 P 0 0 ;0=0,1=0,2
P 3.1112205 3.2872047 3 P 0 0 ;0=0,1=0,2
P 3.1448425 3.6666929 24 P 0 0 ;0=21,1=0,2
P 3.1448425 3.7454331 24 P 0 0 ;0=21,1=0,2
P 3.1448425 3.951063 23 P 0 0 ;0=20,1=0,2
P 3.1448425 4.2211417 23 P 0 0 ;0=20,1=0,2
P 3.2091732 2.7952756 42 P 0 0 ;0=39,1=0,2
P 3.2091732 2.8149606 42 P 0 0 ;0=39,1=0,2
P 3.2091732 2.8346456 42 P 0 0 ;0=39,1=0,2
P 3.219252 3.7503543 13 P 0 0 ;0=10,1=0,2
P 3.2293307 2.7849212 43 P 0 0 ;0=40,1=0,2
P 3.2293307 2.845 43 P 0 0 ;0=40,1=0,2
P 3.2448425 3.6617716 13 P 0 0 ;0=10,1=0,2
P 3.2448425 3.951063 23 P 0 0 ;0=20,1=0,2
P 3.2448425 4.2211417 23 P 0 0 ;0=20,1=0,2
P 3.2490157 2.7849212 43 P 0 0 ;0=40,1=0,2
P 3.2490157 2.845 43 P 0 0 ;0=40,1=0,2
P 3.2691732 2.7952756 42 P 0 0 ;0=39,1=0,2
P 3.2691732 2.8149606 42 P 0 0 ;0=39,1=0,2
P 3.2691732 2.8346456 42 P 0 0 ;0=39,1=0,2
P 3.2704331 3.7503543 13 P 0 0 ;0=10,1=0,2
P 3.2948425 4.0861024 64 P 0 0 ;0=54,1=0
P 3.3331103 3.2062205 18 P 0 0 ;0=15,1=0,2
P 3.3331103 3.3951969 18 P 0 0 ;0=15,1=0,2
P 3.3448425 3.951063 23 P 0 0 ;0=20,1=0,2
P 3.3448425 4.2211417 23 P 0 0 ;0=20,1=0,2
P 3.3498425 3.6666929 24 P 0 0 ;0=21,1=0,2
P 3.3498425 3.7454331 24 P 0 0 ;0=21,1=0,2
P 3.3921654 3.2062205 18 P 0 0 ;0=15,1=0,2
P 3.3921654 3.3951969 18 P 0 0 ;0=15,1=0,2
P 3.4385827 2.8923386 20 P 0 0 ;0=17,1=0,2
P 3.4385827 3.0517874 20 P 0 0 ;0=17,1=0,2
P 3.444252 3.7503543 13 P 0 0 ;0=10,1=0,2
P 3.4444882 2.948441 22 P 0 0 ;0=19,1=0,2
P 3.4444882 2.995685 22 P 0 0 ;0=19,1=0,2
P 3.4512205 3.2062205 18 P 0 0 ;0=15,1=0,2
P 3.4512205 3.3951969 18 P 0 0 ;0=15,1=0,2
P 3.4698425 3.6617716 13 P 0 0 ;0=10,1=0,2
P 3.4776771 2.797063 25 P 0 0 ;0=22,1=0,2
P 3.4848425 2.8923386 21 P 0 0 ;0=18,1=0,2
P 3.4848425 3.0517874 21 P 0 0 ;0=18,1=0,2
P 3.4920225 1.319633 44 P 0 0 ;0=41,1=0,2
P 3.4920225 1.339323 44 P 0 0 ;0=41,1=0,2
P 3.4920225 1.359003 44 P 0 0 ;0=41,1=0,2
P 3.4920225 1.378693 44 P 0 0 ;0=41,1=0,2
P 3.4920225 1.398373 44 P 0 0 ;0=41,1=0,2
P 3.4920225 1.418063 44 P 0 0 ;0=41,1=0,2
P 3.4920225 1.437743 44 P 0 0 ;0=41,1=0,2
P 3.4920225 1.457433 44 P 0 0 ;0=41,1=0,2
P 3.4920225 1.477113 44 P 0 0 ;0=41,1=0,2
P 3.4920225 1.496803 44 P 0 0 ;0=41,1=0,2
P 3.4920225 1.516483 44 P 0 0 ;0=41,1=0,2
P 3.4920225 1.536173 44 P 0 0 ;0=41,1=0,2
P 3.4920225 1.555853 44 P 0 0 ;0=41,1=0,2
P 3.4920225 1.575543 44 P 0 0 ;0=41,1=0,2
P 3.4920225 1.595223 44 P 0 0 ;0=41,1=0,2
P 3.4920225 1.614913 44 P 0 0 ;0=41,1=0,2
P 3.4920225 1.634593 44 P 0 0 ;0=41,1=0,2
P 3.4920225 1.654283 44 P 0 0 ;0=41,1=0,2
P 3.4920225 1.673963 44 P 0 0 ;0=41,1=0,2
P 3.4920225 1.693653 44 P 0 0 ;0=41,1=0,2
P 3.4920225 1.713333 44 P 0 0 ;0=41,1=0,2
P 3.4920225 1.733023 44 P 0 0 ;0=41,1=0,2
P 3.4920225 1.752703 44 P 0 0 ;0=41,1=0,2
P 3.4920225 1.772393 44 P 0 0 ;0=41,1=0,2
P 3.4920225 1.792073 44 P 0 0 ;0=41,1=0,2
P 3.4920225 1.811763 44 P 0 0 ;0=41,1=0,2
P 3.4920225 1.831443 44 P 0 0 ;0=41,1=0,2
P 3.4920225 1.851133 44 P 0 0 ;0=41,1=0,2
P 3.4920225 1.870813 44 P 0 0 ;0=41,1=0,2
P 3.4920225 1.890503 44 P 0 0 ;0=41,1=0,2
P 3.4920225 1.910183 44 P 0 0 ;0=41,1=0,2
P 3.4920225 1.929873 44 P 0 0 ;0=41,1=0,2
P 3.4920225 1.949553 44 P 0 0 ;0=41,1=0,2
P 3.4920225 1.969243 44 P 0 0 ;0=41,1=0,2
P 3.4920225 1.988923 44 P 0 0 ;0=41,1=0,2
P 3.4920225 2.008613 44 P 0 0 ;0=41,1=0,2
P 3.4920225 2.028293 44 P 0 0 ;0=41,1=0,2
P 3.4920225 2.047983 44 P 0 0 ;0=41,1=0,2
P 3.4920225 2.067663 44 P 0 0 ;0=41,1=0,2
P 3.4920225 2.087353 44 P 0 0 ;0=41,1=0,2
P 3.4954331 3.7503543 13 P 0 0 ;0=10,1=0,2
P 3.5102756 3.2062205 18 P 0 0 ;0=15,1=0,2
P 3.5102756 3.3951969 18 P 0 0 ;0=15,1=0,2
P 3.5251968 2.948441 22 P 0 0 ;0=19,1=0,2
P 3.5251968 2.995685 22 P 0 0 ;0=19,1=0,2
P 3.5311023 2.8923386 20 P 0 0 ;0=17,1=0,2
P 3.5311023 3.0517874 20 P 0 0 ;0=17,1=0,2
P 3.5320078 2.797063 25 P 0 0 ;0=22,1=0,2
P 3.5693307 3.2062205 18 P 0 0 ;0=15,1=0,2
P 3.5693307 3.3853543 19 P 0 0 ;0=16,1=0,2
P 3.5717425 1.275343 45 P 0 0 ;0=42,1=0,2
P 3.5717425 1.309793 74 P 0 0 ;0=63,1=0
P 3.5717425 2.097193 74 P 0 0 ;0=63,1=0
P 3.5717425 2.131643 45 P 0 0 ;0=42,1=0,2
P 3.5898425 3.7275197 38 P 0 0 ;0=35,1=0,2
P 3.5898425 3.7846063 38 P 0 0 ;0=35,1=0,2
P 3.5898425 3.8525197 38 P 0 0 ;0=35,1=0,2
P 3.5898425 3.9096063 38 P 0 0 ;0=35,1=0,2
P 3.6514625 1.319633 44 P 0 0 ;0=41,1=0,2
P 3.6514625 1.339323 44 P 0 0 ;0=41,1=0,2
P 3.6514625 1.359003 44 P 0 0 ;0=41,1=0,2
P 3.6514625 1.378693 44 P 0 0 ;0=41,1=0,2
P 3.6514625 1.398373 44 P 0 0 ;0=41,1=0,2
P 3.6514625 1.418063 44 P 0 0 ;0=41,1=0,2
P 3.6514625 1.437743 44 P 0 0 ;0=41,1=0,2
P 3.6514625 1.457433 44 P 0 0 ;0=41,1=0,2
P 3.6514625 1.477113 44 P 0 0 ;0=41,1=0,2
P 3.6514625 1.496803 44 P 0 0 ;0=41,1=0,2
P 3.6514625 1.516483 44 P 0 0 ;0=41,1=0,2
P 3.6514625 1.536173 44 P 0 0 ;0=41,1=0,2
P 3.6514625 1.555853 44 P 0 0 ;0=41,1=0,2
P 3.6514625 1.575543 44 P 0 0 ;0=41,1=0,2
P 3.6514625 1.595223 44 P 0 0 ;0=41,1=0,2
P 3.6514625 1.614913 44 P 0 0 ;0=41,1=0,2
P 3.6514625 1.634593 44 P 0 0 ;0=41,1=0,2
P 3.6514625 1.654283 44 P 0 0 ;0=41,1=0,2
P 3.6514625 1.673963 44 P 0 0 ;0=41,1=0,2
P 3.6514625 1.693653 44 P 0 0 ;0=41,1=0,2
P 3.6514625 1.713333 44 P 0 0 ;0=41,1=0,2
P 3.6514625 1.733023 44 P 0 0 ;0=41,1=0,2
P 3.6514625 1.752703 44 P 0 0 ;0=41,1=0,2
P 3.6514625 1.772393 44 P 0 0 ;0=41,1=0,2
P 3.6514625 1.792073 44 P 0 0 ;0=41,1=0,2
P 3.6514625 1.811763 44 P 0 0 ;0=41,1=0,2
P 3.6514625 1.831443 44 P 0 0 ;0=41,1=0,2
P 3.6514625 1.851133 44 P 0 0 ;0=41,1=0,2
P 3.6514625 1.870813 44 P 0 0 ;0=41,1=0,2
P 3.6514625 1.890503 44 P 0 0 ;0=41,1=0,2
P 3.6514625 1.910183 44 P 0 0 ;0=41,1=0,2
P 3.6514625 1.929873 44 P 0 0 ;0=41,1=0,2
P 3.6514625 1.949553 44 P 0 0 ;0=41,1=0,2
P 3.6514625 1.969243 44 P 0 0 ;0=41,1=0,2
P 3.6514625 1.988923 44 P 0 0 ;0=41,1=0,2
P 3.6514625 2.008613 44 P 0 0 ;0=41,1=0,2
P 3.6514625 2.028293 44 P 0 0 ;0=41,1=0,2
P 3.6514625 2.047983 44 P 0 0 ;0=41,1=0,2
P 3.6514625 2.067663 44 P 0 0 ;0=41,1=0,2
P 3.6514625 2.087353 44 P 0 0 ;0=41,1=0,2
P 3.6594094 0.726063 48 P 0 0 ;0=45,1=0,2
P 3.6681102 3.786063 26 P 0 0 ;0=23,1=0,2
P 3.6681102 3.861063 26 P 0 0 ;0=23,1=0,2
P 3.6829133 0.636063 49 P 0 0 ;0=46,1=0,2
P 3.6888425 3.266567 40 P 0 0 ;0=37,1=0,2
P 3.6888425 3.3295591 40 P 0 0 ;0=37,1=0,2
P 3.6938425 3.1176299 39 P 0 0 ;0=36,1=0,2
P 3.6938425 3.1884961 39 P 0 0 ;0=36,1=0,2
P 3.6962598 4.0276378 9 P 0 0 ;0=6,1=0,2
P 3.6962598 4.2441732 9 P 0 0 ;0=6,1=0,2
P 3.7015748 3.786063 26 P 0 0 ;0=23,1=0,2
P 3.7015748 3.861063 26 P 0 0 ;0=23,1=0,2
P 3.7167716 0.636063 49 P 0 0 ;0=46,1=0,2
P 3.7302756 0.726063 48 P 0 0 ;0=45,1=0,2
P 3.7698425 3.2011339 41 P 0 0 ;0=38,1=0,2
P 3.7698425 3.2349922 41 P 0 0 ;0=38,1=0,2
P 3.772559 3.683563 14 P 0 0 ;0=11,1=0,2
P 3.772559 3.708563 14 P 0 0 ;0=11,1=0,2
P 3.772559 3.733563 14 P 0 0 ;0=11,1=0,2
P 3.772559 3.758563 14 P 0 0 ;0=11,1=0,2
P 3.772559 3.783563 14 P 0 0 ;0=11,1=0,2
P 3.772559 3.808563 14 P 0 0 ;0=11,1=0,2
P 3.772559 3.833563 14 P 0 0 ;0=11,1=0,2
P 3.772559 3.858563 14 P 0 0 ;0=11,1=0,2
P 3.7848425 4.126063 63 P 0 0 ;0=53,1=0
P 3.8084646 4.0237008 10 P 0 0 ;0=7,1=0,2
P 3.8399606 4.0237008 10 P 0 0 ;0=7,1=0,2
P 3.8714567 4.0237008 10 P 0 0 ;0=7,1=0,2
P 3.9029528 4.0237008 10 P 0 0 ;0=7,1=0,2
P 3.9114214 1.5996232 30 P 0 0 ;0=27,1=0,2
P 3.9114214 1.6196232 30 P 0 0 ;0=27,1=0,2
P 3.9114214 1.6396232 30 P 0 0 ;0=27,1=0,2
P 3.9114214 1.6596232 30 P 0 0 ;0=27,1=0,2
P 3.9114214 1.6796232 30 P 0 0 ;0=27,1=0,2
P 3.9114214 1.6996232 30 P 0 0 ;0=27,1=0,2
P 3.9114214 1.7196232 30 P 0 0 ;0=27,1=0,2
P 3.9114214 1.7396232 30 P 0 0 ;0=27,1=0,2
P 3.9114214 1.7596232 30 P 0 0 ;0=27,1=0,2
P 3.9114214 1.7796232 30 P 0 0 ;0=27,1=0,2
P 3.9344488 4.0237008 10 P 0 0 ;0=7,1=0,2
P 3.9580709 4.126063 63 P 0 0 ;0=53,1=0
P 3.9598425 2.7806299 39 P 0 0 ;0=36,1=0,2
P 3.9598425 2.8514961 39 P 0 0 ;0=36,1=0,2
P 3.9797272 0.8906186 67 P 0 0 ;0=56,1=0
P 3.9797272 2.4890438 67 P 0 0 ;0=56,1=0
P 3.9871259 3.683563 14 P 0 0 ;0=11,1=0,2
P 3.9871259 3.708563 14 P 0 0 ;0=11,1=0,2
P 3.9871259 3.733563 14 P 0 0 ;0=11,1=0,2
P 3.9871259 3.758563 14 P 0 0 ;0=11,1=0,2
P 3.9871259 3.783563 14 P 0 0 ;0=11,1=0,2
P 3.9871259 3.808563 14 P 0 0 ;0=11,1=0,2
P 3.9871259 3.833563 14 P 0 0 ;0=11,1=0,2
P 3.9871259 3.858563 14 P 0 0 ;0=11,1=0,2
P 4.0398425 3.029567 40 P 0 0 ;0=37,1=0,2
P 4.0398425 3.0925591 40 P 0 0 ;0=37,1=0,2
P 4.0466536 4.0276378 9 P 0 0 ;0=6,1=0,2
P 4.0466536 4.2441732 9 P 0 0 ;0=6,1=0,2
P 4.0624044 2.595343 67 P 0 0 ;0=56,1=0
P 4.0648425 2.7806299 39 P 0 0 ;0=36,1=0,2
P 4.0648425 2.8514961 39 P 0 0 ;0=36,1=0,2
P 4.0689017 1.5996232 30 P 0 0 ;0=27,1=0,2
P 4.0689017 1.6196232 30 P 0 0 ;0=27,1=0,2
P 4.0689017 1.6396232 30 P 0 0 ;0=27,1=0,2
P 4.0689017 1.6596232 30 P 0 0 ;0=27,1=0,2
P 4.0689017 1.6796232 30 P 0 0 ;0=27,1=0,2
P 4.0689017 1.6996232 30 P 0 0 ;0=27,1=0,2
P 4.0689017 1.7196232 30 P 0 0 ;0=27,1=0,2
P 4.0689017 1.7396232 30 P 0 0 ;0=27,1=0,2
P 4.0689017 1.7596232 30 P 0 0 ;0=27,1=0,2
P 4.0689017 1.7796232 30 P 0 0 ;0=27,1=0,2
P 4.1048425 3.7706299 39 P 0 0 ;0=36,1=0,2
P 4.1048425 3.8414961 39 P 0 0 ;0=36,1=0,2
P 4.1098425 3.0441338 41 P 0 0 ;0=38,1=0,2
P 4.1098425 3.0779921 41 P 0 0 ;0=38,1=0,2
P 4.1126772 3.701063 25 P 0 0 ;0=22,1=0,2
P 4.1498425 2.7898819 34 P 0 0 ;0=31,1=0,2
P 4.1498425 2.8422441 34 P 0 0 ;0=31,1=0,2
P 4.1505905 3.6033465 25 P 0 0 ;0=22,1=0,2
P 4.1648425 3.0441338 41 P 0 0 ;0=38,1=0,2
P 4.1648425 3.0779921 41 P 0 0 ;0=38,1=0,2
P 4.1670079 3.701063 25 P 0 0 ;0=22,1=0,2
P 4.1805146 2.595343 67 P 0 0 ;0=56,1=0
P 4.1948425 3.774567 40 P 0 0 ;0=37,1=0,2
P 4.1948425 3.8375591 40 P 0 0 ;0=37,1=0,2
P 4.2049212 3.6033465 25 P 0 0 ;0=22,1=0,2
P 4.2094094 3.246063 48 P 0 0 ;0=45,1=0,2
P 4.2198425 3.0441338 41 P 0 0 ;0=38,1=0,2
P 4.2198425 3.0779921 41 P 0 0 ;0=38,1=0,2
P 4.2348425 2.7806299 39 P 0 0 ;0=36,1=0,2
P 4.2348425 2.8514961 39 P 0 0 ;0=36,1=0,2
P 4.2748425 3.0441338 41 P 0 0 ;0=38,1=0,2
P 4.2748425 3.0779921 41 P 0 0 ;0=38,1=0,2
P 4.2755905 3.6033465 51 P 0 0 ;0=48,1=0,2
P 4.2802756 3.246063 48 P 0 0 ;0=45,1=0,2
P 4.2986248 2.595343 67 P 0 0 ;0=56,1=0
P 4.3277559 1.0074803 66 P 0 0 ;0=55,1=0
P 4.3277559 2.3074803 65 P 0 0 ;0=55,1=0
P 4.3326771 3.6033465 51 P 0 0 ;0=48,1=0,2
P 4.3348425 3.0441338 41 P 0 0 ;0=38,1=0,2
P 4.3348425 3.0779921 41 P 0 0 ;0=38,1=0,2
P 4.3398425 2.7806299 39 P 0 0 ;0=36,1=0,2
P 4.3398425 2.8514961 39 P 0 0 ;0=36,1=0,2
P 4.3948425 3.0441338 41 P 0 0 ;0=38,1=0,2
P 4.3948425 3.0779921 41 P 0 0 ;0=38,1=0,2
P 4.4329134 4.206063 29 P 0 0 ;0=26,1=0,2
P 4.4348425 2.7898819 34 P 0 0 ;0=31,1=0,2
P 4.4348425 2.8422441 34 P 0 0 ;0=31,1=0,2
P 4.4548425 3.0441338 41 P 0 0 ;0=38,1=0,2
P 4.4548425 3.0779921 41 P 0 0 ;0=38,1=0,2
P 4.5667716 4.206063 29 P 0 0 ;0=26,1=0,2
P 4.6526771 4.206063 25 P 0 0 ;0=22,1=0,2
P 4.6526772 4.121063 25 P 0 0 ;0=22,1=0,2
P 4.7070078 4.206063 25 P 0 0 ;0=22,1=0,2
P 4.7070079 4.121063 25 P 0 0 ;0=22,1=0,2
P 4.7277559 2.3074803 65 P 0 0 ;0=55,1=0
P 4.9094488 2.8080708 36 P 0 0 ;0=33,1=0,2
P 4.9094488 3.9616142 36 P 0 0 ;0=33,1=0,2
P 4.9277559 1.0074803 65 P 0 0 ;0=55,1=0
P 4.9277559 2.3074803 65 P 0 0 ;0=55,1=0
P 4.9579134 4.206063 29 P 0 0 ;0=26,1=0,2
P 5.0917716 4.206063 29 P 0 0 ;0=26,1=0,2
P 5.1277559 1.0074803 65 P 0 0 ;0=55,1=0
P 5.1277559 2.3074803 65 P 0 0 ;0=55,1=0
P 5.2126771 4.206063 25 P 0 0 ;0=22,1=0,2
P 5.2126772 4.126063 25 P 0 0 ;0=22,1=0,2
P 5.2670078 4.206063 25 P 0 0 ;0=22,1=0,2
P 5.2670079 4.126063 25 P 0 0 ;0=22,1=0,2
P 5.3277559 1.0074803 65 P 0 0 ;0=55,1=0
P 5.3277559 2.3074803 65 P 0 0 ;0=55,1=0
P 5.5781524 0.8906186 67 P 0 0 ;0=56,1=0
P 5.5781524 1.6898312 67 P 0 0 ;0=56,1=0
P 5.5781524 2.4890438 67 P 0 0 ;0=56,1=0
P 5.6344488 3.359252 49 P 0 0 ;0=46,1=0,2
P 5.6683071 3.359252 49 P 0 0 ;0=46,1=0,2
P 5.7234252 3.8444882 68 P 0 0 ;0=57,1=0
P 5.7234252 4.0255906 68 P 0 0 ;0=57,1=0
P 5.7411417 3.3612205 48 P 0 0 ;0=45,1=0,2
P 5.8120079 3.3612205 48 P 0 0 ;0=45,1=0,2
P 5.8879921 3.701063 16 P 0 0 ;0=13,1=0,2
P 5.9348031 3.9379527 69 P 0 0 ;0=58,1=0
P 6.0048425 2.3388977 52 P 0 0 ;0=49,1=0,2
P 6.0048425 2.3932284 52 P 0 0 ;0=49,1=0,2
P 6.0316929 3.701063 16 P 0 0 ;0=13,1=0,2
P 6.0356772 3.556063 25 P 0 0 ;0=22,1=0,2
P 6.0648425 2.3441339 41 P 0 0 ;0=38,1=0,2
P 6.0648425 2.3779922 41 P 0 0 ;0=38,1=0,2
P 6.0900079 3.556063 25 P 0 0 ;0=22,1=0,2
P 6.0933464 2.171063 50 P 0 0 ;0=47,1=0,2
P 6.1198425 3.8198425 71 P 0 0 ;0=60,1=0
P 6.1198425 4.056063 70 P 0 0 ;0=59,1=0
P 6.1228425 2.4338976 52 P 0 0 ;0=49,1=0,2
P 6.1228425 2.4882283 52 P 0 0 ;0=49,1=0,2
P 6.1563385 2.171063 50 P 0 0 ;0=47,1=0,2
P 6.1574016 2.241063 15 P 0 0 ;0=12,1=0,2
P 6.1574016 2.291063 15 P 0 0 ;0=12,1=0,2
P 6.1574016 2.341063 15 P 0 0 ;0=12,1=0,2
P 6.1574016 2.391063 15 P 0 0 ;0=12,1=0,2
P 6.1979921 3.701063 16 P 0 0 ;0=13,1=0,2
P 6.2029921 3.566063 16 P 0 0 ;0=13,1=0,2
P 6.2348425 2.1288977 52 P 0 0 ;0=49,1=0,2
P 6.2348425 2.1832284 52 P 0 0 ;0=49,1=0,2
P 6.253937 2.7559055 39 P 0 0 ;0=36,1=0,2
P 6.253937 2.8267717 39 P 0 0 ;0=36,1=0,2
P 6.3126772 2.451063 25 P 0 0 ;0=22,1=0,2
P 6.3198425 1.4601181 35 P 0 0 ;0=32,1=0,2
P 6.3198425 1.8420079 35 P 0 0 ;0=32,1=0,2
P 6.3279134 2.501063 49 P 0 0 ;0=46,1=0,2
P 6.3279134 2.556063 49 P 0 0 ;0=46,1=0,2
P 6.3279134 2.611063 49 P 0 0 ;0=46,1=0,2
P 6.3279134 2.656063 49 P 0 0 ;0=46,1=0,2
P 6.3348425 2.1106299 39 P 0 0 ;0=36,1=0,2
P 6.3348425 2.1814961 39 P 0 0 ;0=36,1=0,2
P 6.3416929 3.701063 16 P 0 0 ;0=13,1=0,2
P 6.3466929 3.566063 16 P 0 0 ;0=13,1=0,2
P 6.3522834 2.241063 15 P 0 0 ;0=12,1=0,2
P 6.3522834 2.291063 15 P 0 0 ;0=12,1=0,2
P 6.3522834 2.341063 15 P 0 0 ;0=12,1=0,2
P 6.3522834 2.391063 15 P 0 0 ;0=12,1=0,2
P 6.3617717 2.501063 49 P 0 0 ;0=46,1=0,2
P 6.3617717 2.556063 49 P 0 0 ;0=46,1=0,2
P 6.3617717 2.611063 49 P 0 0 ;0=46,1=0,2
P 6.3617717 2.656063 49 P 0 0 ;0=46,1=0,2
P 6.3670079 2.451063 25 P 0 0 ;0=22,1=0,2
P 6.3720472 2.7559055 39 P 0 0 ;0=36,1=0,2
P 6.3720472 2.8267717 39 P 0 0 ;0=36,1=0,2
P 6.3883268 3.1524803 31 P 0 0 ;0=28,1=0,2
P 6.3883268 3.1721654 31 P 0 0 ;0=28,1=0,2
P 6.3883268 3.1918504 31 P 0 0 ;0=28,1=0,2
P 6.3883268 3.2115354 31 P 0 0 ;0=28,1=0,2
P 6.3883268 3.2312205 31 P 0 0 ;0=28,1=0,2
P 6.3883268 3.2509055 31 P 0 0 ;0=28,1=0,2
P 6.3883268 3.2705906 31 P 0 0 ;0=28,1=0,2
P 6.3883268 3.2902756 31 P 0 0 ;0=28,1=0,2
P 6.3883268 3.3099606 31 P 0 0 ;0=28,1=0,2
P 6.3883268 3.3296457 31 P 0 0 ;0=28,1=0,2
P 6.4203149 3.1500197 32 P 0 0 ;0=29,1=0,2
P 6.4203149 3.3321063 32 P 0 0 ;0=29,1=0,2
P 6.4394094 3.071063 48 P 0 0 ;0=45,1=0,2
P 6.44 3.1500197 32 P 0 0 ;0=29,1=0,2
P 6.44 3.3321063 32 P 0 0 ;0=29,1=0,2
P 6.459685 3.3321063 32 P 0 0 ;0=29,1=0,2
P 6.4598425 3.1500197 32 P 0 0 ;0=29,1=0,2
P 6.4698425 2.2395669 40 P 0 0 ;0=37,1=0,2
P 6.4698425 2.302559 40 P 0 0 ;0=37,1=0,2
P 6.4793701 3.1500197 32 P 0 0 ;0=29,1=0,2
P 6.4793701 3.3321063 32 P 0 0 ;0=29,1=0,2
P 6.5102756 3.071063 48 P 0 0 ;0=45,1=0,2
P 6.5113582 3.1524803 31 P 0 0 ;0=28,1=0,2
P 6.5113582 3.1721654 31 P 0 0 ;0=28,1=0,2
P 6.5113582 3.1918504 31 P 0 0 ;0=28,1=0,2
P 6.5113582 3.2115354 31 P 0 0 ;0=28,1=0,2
P 6.5113582 3.2312205 31 P 0 0 ;0=28,1=0,2
P 6.5113582 3.2509055 31 P 0 0 ;0=28,1=0,2
P 6.5113582 3.2705906 31 P 0 0 ;0=28,1=0,2
P 6.5113582 3.2902756 31 P 0 0 ;0=28,1=0,2
P 6.5113582 3.3099606 31 P 0 0 ;0=28,1=0,2
P 6.5113582 3.3296457 31 P 0 0 ;0=28,1=0,2
P 6.5198425 1.954567 40 P 0 0 ;0=37,1=0,2
P 6.5198425 2.0175591 40 P 0 0 ;0=37,1=0,2
P 6.5694882 3.5895276 68 P 0 0 ;0=66,1=0
P 6.5694882 3.806063 68 P 0 0 ;0=66,1=0
P 6.5694882 4.0934646 77 P 0 0 ;0=67,1=0
P 6.5848425 3.0391338 41 P 0 0 ;0=38,1=0,2
P 6.5848425 3.0729921 41 P 0 0 ;0=38,1=0,2
P 6.6048425 3.1295669 40 P 0 0 ;0=37,1=0,2
P 6.6048425 3.192559 40 P 0 0 ;0=37,1=0,2
P 6.6048425 3.264567 40 P 0 0 ;0=37,1=0,2
P 6.6048425 3.3275591 40 P 0 0 ;0=37,1=0,2
P 6.6294094 1.421063 48 P 0 0 ;0=45,1=0,2
P 6.6294094 1.531063 48 P 0 0 ;0=45,1=0,2
P 6.6374016 1.881063 15 P 0 0 ;0=12,1=0,2
P 6.6374016 1.931063 15 P 0 0 ;0=12,1=0,2
P 6.6374016 1.981063 15 P 0 0 ;0=12,1=0,2
P 6.6374016 2.031063 15 P 0 0 ;0=12,1=0,2
P 6.6429133 1.611063 49 P 0 0 ;0=46,1=0,2
P 6.6429133 1.671063 49 P 0 0 ;0=46,1=0,2
P 6.6429133 1.721063 49 P 0 0 ;0=46,1=0,2
P 6.6429133 1.776063 49 P 0 0 ;0=46,1=0,2
P 6.6598425 2.0956299 39 P 0 0 ;0=36,1=0,2
P 6.6598425 2.1664961 39 P 0 0 ;0=36,1=0,2
P 6.6767716 1.611063 49 P 0 0 ;0=46,1=0,2
P 6.6767716 1.671063 49 P 0 0 ;0=46,1=0,2
P 6.6767716 1.721063 49 P 0 0 ;0=46,1=0,2
P 6.6767716 1.776063 49 P 0 0 ;0=46,1=0,2
P 6.6798425 2.4201181 35 P 0 0 ;0=32,1=0,2
P 6.6798425 2.8020079 35 P 0 0 ;0=32,1=0,2
P 6.7002756 1.421063 48 P 0 0 ;0=45,1=0,2
P 6.7002756 1.531063 48 P 0 0 ;0=45,1=0,2
P 6.7265748 3.1680709 17 P 0 0 ;0=14,1=0,2
P 6.7265748 3.2940551 17 P 0 0 ;0=14,1=0,2
P 6.7276771 1.816063 25 P 0 0 ;0=22,1=0,2
P 6.7348425 3.5895276 68 P 0 0 ;0=66,1=0
P 6.7348425 3.806063 68 P 0 0 ;0=66,1=0
P 6.7498425 2.0888976 52 P 0 0 ;0=49,1=0,2
P 6.7498425 2.1432283 52 P 0 0 ;0=49,1=0,2
P 6.7820078 1.816063 25 P 0 0 ;0=22,1=0,2
P 6.8322834 1.881063 15 P 0 0 ;0=12,1=0,2
P 6.8322834 1.931063 15 P 0 0 ;0=12,1=0,2
P 6.8322834 1.981063 15 P 0 0 ;0=12,1=0,2
P 6.8322834 2.031063 15 P 0 0 ;0=12,1=0,2
P 6.8426771 1.816063 25 P 0 0 ;0=22,1=0,2
P 6.8433465 2.096063 50 P 0 0 ;0=47,1=0,2
P 6.8970078 1.816063 25 P 0 0 ;0=22,1=0,2
P 6.9001969 3.5895276 68 P 0 0 ;0=66,1=0
P 6.9001969 3.806063 68 P 0 0 ;0=66,1=0
P 6.9001969 4.0934646 77 P 0 0 ;0=65,1=0
P 6.9063386 2.096063 50 P 0 0 ;0=47,1=0,2
P 6.9398425 1.8891338 41 P 0 0 ;0=38,1=0,2
P 6.9398425 1.9229921 41 P 0 0 ;0=38,1=0,2
P 6.9431102 3.1680709 17 P 0 0 ;0=14,1=0,2
P 6.9431102 3.2940551 17 P 0 0 ;0=14,1=0,2
P 7.0098425 1.8838977 52 P 0 0 ;0=49,1=0,2
P 7.0098425 1.9382284 52 P 0 0 ;0=49,1=0,2
S P 0
OB 4.6208425 3.246063 I
OS 4.6208425 2.826063
OS 4.5028425 2.708063
OS 4.3556875 2.708063
OS 4.3546243 2.7095544
OS 4.3534727 2.713063
OS 4.3567981 2.7180398
OS 4.3581951 2.725063
OS 4.3581951 2.7499921
OS 4.3763858 2.7499921
OS 4.3763858 2.8112677
OS 4.3032992 2.8112677
OS 4.3032992 2.7499921
OS 4.3214899 2.7499921
OS 4.3214899 2.725063
OS 4.3228869 2.7180398
OS 4.3262123 2.713063
OS 4.3250607 2.7095544
OS 4.3239975 2.708063
OS 4.2506875 2.708063
OS 4.2496243 2.7095544
OS 4.2484727 2.713063
OS 4.2517981 2.7180398
OS 4.2531951 2.725063
OS 4.2531951 2.7499921
OS 4.2713858 2.7499921
OS 4.2713858 2.8112677
OS 4.2120728 2.8112677
OS 4.2100017 2.8162677
OS 4.2142397 2.8205057
OS 4.2222047 2.8205057
OS 4.2239773 2.8208583
OS 4.2713858 2.8208583
OS 4.2713858 2.8331435
OS 4.3032992 2.8331435
OS 4.3032992 2.8208583
OS 4.3763858 2.8208583
OS 4.3763858 2.8331435
OS 4.3842406 2.8331435
OS 4.3881172 2.8292669
OS 4.3940712 2.8252885
OS 4.4010945 2.8238915
OS 4.4040156 2.8238915
OS 4.4075511 2.8203559
OS 4.4075511 2.8171181
OS 4.4075512 2.812118
OS 4.4075512 2.7647559
OS 4.4621338 2.7647559
OS 4.4621338 2.7715293
OS 4.5036614 2.7715293
OS 4.5106846 2.7729263
OS 4.5166386 2.7769047
OS 4.520617 2.7828587
OS 4.522014 2.7898819
OS 4.520617 2.7969051
OS 4.5166386 2.8028591
OS 4.5106846 2.8068375
OS 4.5036614 2.8082345
OS 4.4656694 2.8082345
OS 4.4621339 2.8117701
OS 4.4621339 2.8150079
OS 4.4621338 2.820008
OS 4.4621338 2.8673701
OS 4.4075513 2.8673701
OS 4.4075513 2.8673702
OS 4.4025512 2.8659891
OS 4.3988658 2.8684517
OS 4.3918425 2.8698487
OS 4.3763858 2.8698487
OS 4.3763858 2.8821339
OS 4.3032992 2.8821339
OS 4.3032992 2.8698487
OS 4.2713858 2.8698487
OS 4.2713858 2.8821339
OS 4.1982992 2.8821339
OS 4.1982992 2.854935
OS 4.1936606 2.8518356
OS 4.1748653 2.8330402
OS 4.1708869 2.8270863
OS 4.1694899 2.820063
OS 4.1694899 2.8150079
OS 4.1225512 2.8150079
OS 4.1225512 2.7647559
OS 4.1771338 2.7647559
OS 4.1771338 2.7719107
OS 4.18315 2.7731074
OS 4.1891039 2.7770858
OS 4.1936798 2.7816616
OS 4.1982992 2.7797482
OS 4.1982992 2.7499921
OS 4.2164899 2.7499921
OS 4.2164899 2.725063
OS 4.2178869 2.7180398
OS 4.2212123 2.713063
OS 4.2200607 2.7095544
OS 4.2189975 2.708063
OS 4.0807446 2.7080629
OS 4.078072 2.713063
OS 4.0799142 2.7158201
OS 4.081156 2.722063
OS 4.0799142 2.7283059
OS 4.0780972 2.7310253
OS 4.0780972 2.7499921
OS 4.1013858 2.7499921
OS 4.1013858 2.8112677
OS 4.0282992 2.8112677
OS 4.0282992 2.7499921
OS 4.0515878 2.7499921
OS 4.0515878 2.7310253
OS 4.0497708 2.7283059
OS 4.048529 2.722063
OS 4.0497708 2.7158201
OS 4.051613 2.713063
OS 4.0489404 2.7080629
OS 3.9746959 2.7080629
OS 3.9733494 2.7106566
OS 3.9727356 2.713063
OS 3.9759142 2.7178201
OS 3.977156 2.724063
OS 3.9759142 2.7303059
OS 3.9730972 2.7345219
OS 3.9730972 2.7499921
OS 3.9963858 2.7499921
OS 3.9963858 2.8112677
OS 3.9232992 2.8112677
OS 3.9232992 2.7499921
OS 3.9465878 2.7499921
OS 3.9465878 2.7315286
OS 3.9457708 2.7303059
OS 3.944529 2.724063
OS 3.9457708 2.7178201
OS 3.9489494 2.713063
OS 3.9483356 2.7106566
OS 3.9469891 2.7080629
OS 3.6008178 2.7080629
OS 3.6008178 2.8700787
OS 3.5998865 2.8747609
OS 3.5972342 2.8787302
OS 3.5783322 2.8976322
OS 3.5743629 2.9002845
OS 3.5696807 2.9012158
OS 3.5597716 2.9012158
OS 3.5597716 2.9216614
OS 3.5597717 2.9229764
OS 3.5597717 2.9266615
OS 3.5597716 2.9279765
OS 3.5597716 2.9689054
OS 3.5597717 2.9702205
OS 3.5597717 2.9739055
OS 3.5597716 2.9752206
OS 3.5597716 2.9847234
OS 3.5600067 2.9859054
OS 3.5597716 2.9870874
OS 3.5597716 3.0174645
OS 3.5097965 3.0174645
OS 3.5066221 3.0211496
OS 3.506622 3.0224646
OS 3.506622 3.0824252
OS 3.4970776 3.0824252
OS 3.4970776 3.0877908
OS 3.4980854 3.0879913
OS 3.5033779 3.0915276
OS 3.5069142 3.0968201
OS 3.508156 3.103063
OS 3.5069142 3.1093059
OS 3.5033779 3.1145984
OS 3.4980854 3.1181347
OS 3.4918425 3.1193765
OS 3.4855996 3.1181347
OS 3.4803071 3.1145984
OS 3.4796479 3.1136118
OS 3.3100381 3.1136118
OS 3.3053559 3.1126805
OS 3.3013866 3.1100282
OS 3.2423327 3.0509743
OS 3.2396804 3.047005
OS 3.2387491 3.0423228
OS 3.2387491 2.9883357
OS 3.2189504 2.968537
OS 3.2161543 2.969427
OS 3.2140315 2.9706891
OS 3.2129142 2.9763059
OS 3.2093779 2.9815984
OS 3.2040854 2.9851347
OS 3.1978425 2.9863765
OS 3.1915996 2.9851347
OS 3.1863071 2.9815984
OS 3.1827708 2.9763059
OS 3.181529 2.970063
OS 3.1827708 2.9638201
OS 3.1863071 2.9585276
OS 3.1915996 2.9549913
OS 3.1972164 2.953874
OS 3.1984785 2.9517512
OS 3.1993685 2.9489551
OS 3.1831083 2.9326948
OS 3.180456 2.9287255
OS 3.1795247 2.9240433
OS 3.1795247 2.8247538
OS 3.180456 2.8200716
OS 3.1831083 2.8161023
OS 3.1919802 2.8072304
OS 3.1957598 2.8047049
OS 3.1957598 2.7823544
OS 3.2225866 2.7823544
OS 3.2225866 2.8315866
OS 3.2422519 2.8315866
OS 3.2422519 2.8584134
OS 3.2415658 2.8584134
OS 3.2415658 2.8754833
OS 3.3460778 2.9799952
OS 3.3510854 2.9809913
OS 3.354765 2.9834499
OS 3.4099134 2.9834499
OS 3.4099134 2.9752206
OS 3.4099133 2.9739055
OS 3.4099133 2.9702205
OS 3.4099134 2.9689054
OS 3.4099134 2.9279765
OS 3.4099133 2.9266615
OS 3.4099133 2.9229764
OS 3.4099134 2.9216614
OS 3.4099134 2.9013177
OS 3.3798048 2.9013177
OS 3.3770854 2.9031347
OS 3.3708425 2.9043765
OS 3.3645996 2.9031347
OS 3.3593071 2.8995984
OS 3.3557708 2.8943059
OS 3.3547747 2.8892982
OS 3.2926722 2.8271957
OS 3.2825866 2.8271957
OS 3.2825866 2.8278818
OS 3.2557598 2.8278818
OS 3.2557598 2.7983346
OS 3.2360945 2.7983346
OS 3.2360945 2.7715078
OS 3.2619369 2.7715078
OS 3.2619369 2.7823544
OS 3.2825866 2.7823544
OS 3.2825866 2.8027255
OS 3.2977401 2.8027255
OS 3.3024223 2.8036568
OS 3.3063916 2.8063091
OS 3.3720777 2.8719952
OS 3.3770854 2.8729913
OS 3.3798048 2.8748083
OS 3.4099134 2.8748083
OS 3.4099134 2.8617008
OS 3.4715878 2.8617008
OS 3.4715878 2.824748
OS 3.4555039 2.824748
OS 3.4555039 2.769378
OS 3.4998503 2.769378
OS 3.4998503 2.824748
OS 3.4980972 2.824748
OS 3.4980972 2.8617008
OS 3.5597716 2.8617008
OS 3.5597716 2.8763622
OS 3.5647716 2.8765868
OS 3.5763476 2.8650108
OS 3.5763476 2.7080629
OS 2.8278423 2.7080628
OS 2.6728427 2.8630632
OS 2.6728425 3.325063
OS 2.8988425 3.551063
OS 4.3158422 3.551063
OS 4.6208425 3.246063
OE
OB 3.6228425 3.5023765 H
OS 3.6165996 3.5011347
OS 3.6123543 3.4982981
OS 3.5668425 3.4982981
OS 3.5621603 3.4973668
OS 3.558191 3.4947145
OS 3.5498163 3.4863398
OS 3.5444324 3.488027
OS 3.5413779 3.4925984
OS 3.5360854 3.4961347
OS 3.5298425 3.4973765
OS 3.5235996 3.4961347
OS 3.5183071 3.4925984
OS 3.5147708 3.4873059
OS 3.513529 3.481063
OS 3.5147708 3.4748201
OS 3.5183071 3.4695276
OS 3.5228785 3.4664731
OS 3.5245657 3.4610892
OS 3.5100717 3.4465952
OS 3.5074194 3.4426259
OS 3.5066246 3.4386299
OS 3.4839056 3.4386299
OS 3.4828564 3.439502
OS 3.4813779 3.4445277
OS 3.4849142 3.4498201
OS 3.486156 3.456063
OS 3.4849142 3.4623059
OS 3.4813779 3.4675984
OS 3.4760854 3.4711347
OS 3.4698425 3.4723765
OS 3.4635996 3.4711347
OS 3.4583071 3.4675984
OS 3.4564545 3.4648257
OS 3.4560708 3.4646973
OS 3.4506698 3.4651682
OS 3.4483779 3.4685984
OS 3.4430854 3.4721347
OS 3.4368425 3.4733765
OS 3.4305996 3.4721347
OS 3.4253071 3.4685984
OS 3.4249279 3.4680309
OS 3.4199519 3.4675408
OS 3.4117782 3.4757145
OS 3.4078089 3.4783668
OS 3.4031267 3.4792981
OS 3.3778425 3.4792981
OS 3.3731603 3.4783668
OS 3.369191 3.4757146
OS 3.3576073 3.4641308
OS 3.3525996 3.4631347
OS 3.3483543 3.4602981
OS 3.3112452 3.4602981
OS 3.3061989 3.4653444
OS 3.3022296 3.4679967
OS 3.2975474 3.468928
OS 3.2470472 3.468928
OS 3.242365 3.4679967
OS 3.2383957 3.4653444
OS 3.1261281 3.3530768
OS 3.1234758 3.3491075
OS 3.1225445 3.3444253
OS 3.1225445 3.3074038
OS 3.0836614 3.3074038
OS 3.0759315 3.3058662
OS 3.0693785 3.3014876
OS 3.0649999 3.2949346
OS 3.0634623 3.2872047
OS 3.0649999 3.2794748
OS 3.0693785 3.2729218
OS 3.0759315 3.2685432
OS 3.0836614 3.2670056
OS 3.1387796 3.2670056
OS 3.1465095 3.2685432
OS 3.1530625 3.2729218
OS 3.1574411 3.2794748
OS 3.1589787 3.2872047
OS 3.1574411 3.2949346
OS 3.1530625 3.3014876
OS 3.1470147 3.3055286
OS 3.1470147 3.3393574
OS 3.2521151 3.4444578
OS 3.2924795 3.4444578
OS 3.2975258 3.4394115
OS 3.3014951 3.4367592
OS 3.3054253 3.4359775
OS 3.3054253 3.3624962
OS 3.3028424 3.3603765
OS 3.2965996 3.3591347
OS 3.2913071 3.3555984
OS 3.2877708 3.3503059
OS 3.286529 3.344063
OS 3.2877708 3.3378201
OS 3.2913071 3.3325276
OS 3.2965996 3.3289913
OS 3.3028425 3.3277495
OS 3.3090854 3.3289913
OS 3.3125878 3.3313315
OS 3.3175878 3.3290168
OS 3.3175878 3.3100253
OS 3.3157708 3.3073059
OS 3.314529 3.301063
OS 3.3157708 3.2948201
OS 3.3193071 3.2895276
OS 3.3216553 3.2879586
OS 3.3217107 3.2878198
OS 3.3202196 3.2829044
OS 3.2656991 3.2829044
OS 3.2652066 3.2879043
OS 3.2669122 3.2882437
OS 3.2699401 3.288846
OS 3.2752326 3.2923823
OS 3.2787689 3.2976748
OS 3.2800107 3.3039177
OS 3.2787689 3.3101606
OS 3.2752326 3.3154531
OS 3.2699401 3.3189894
OS 3.2636972 3.3202312
OS 3.2574543 3.3189894
OS 3.2521618 3.3154531
OS 3.2486255 3.3101606
OS 3.2473837 3.3039177
OS 3.2486255 3.2976748
OS 3.2521618 3.2923823
OS 3.2574543 3.288846
OS 3.260482 3.2882437
OS 3.2621878 3.2879043
OS 3.2616953 3.2829044
OS 3.2057086 3.2829044
OS 3.2010264 3.2819731
OS 3.1970571 3.2793208
OS 3.1671761 3.2494398
OS 3.1544308 3.2494398
OS 3.1530625 3.2514876
OS 3.1465095 3.2558662
OS 3.1387796 3.2574038
OS 3.0836614 3.2574038
OS 3.0759315 3.2558662
OS 3.0693785 3.2514876
OS 3.0649999 3.2449346
OS 3.0634623 3.2372047
OS 3.0649999 3.2294748
OS 3.0693785 3.2229218
OS 3.0759315 3.2185432
OS 3.0836614 3.2170056
OS 3.1387796 3.2170056
OS 3.1465095 3.2185432
OS 3.1530625 3.2229218
OS 3.1544308 3.2249696
OS 3.172244 3.2249696
OS 3.1769262 3.2259009
OS 3.1808955 3.2285532
OS 3.2107765 3.2584342
OS 3.3287401 3.2584342
OS 3.3334223 3.2593655
OS 3.3373916 3.2620178
OS 3.3546711 3.2792973
OS 3.3592792 3.2768342
OS 3.358529 3.273063
OS 3.3597708 3.2668201
OS 3.3633071 3.2615276
OS 3.3685996 3.2579913
OS 3.3748425 3.2567495
OS 3.3810854 3.2579913
OS 3.3863779 3.2615276
OS 3.3899142 3.2668201
OS 3.391156 3.273063
OS 3.3899142 3.2793059
OS 3.3863779 3.2845984
OS 3.3810854 3.2881347
OS 3.3748425 3.2893765
OS 3.3710713 3.2886263
OS 3.3686082 3.2932344
OS 3.3934921 3.3181183
OS 3.4231989 3.2884115
OS 3.4271682 3.2857592
OS 3.4318504 3.2848279
OS 3.4813543 3.2848279
OS 3.4855996 3.2819913
OS 3.4918425 3.2807495
OS 3.4980854 3.2819913
OS 3.5033779 3.2855276
OS 3.5069142 3.2908201
OS 3.508156 3.297063
OS 3.5069142 3.3033059
OS 3.5033779 3.3085984
OS 3.4980854 3.3121347
OS 3.4918425 3.3133765
OS 3.4855996 3.3121347
OS 3.4813543 3.3092981
OS 3.4369183 3.3092981
OS 3.4056905 3.3405259
OS 3.4056905 3.3517639
OS 3.4198502 3.3517639
OS 3.4198502 3.3517637
OS 3.4235357 3.3517637
OS 3.4235357 3.3517639
OS 3.4775905 3.3517639
OS 3.4789055 3.3517638
OS 3.4825906 3.3517638
OS 3.4839056 3.3517639
OS 3.5366456 3.3517639
OS 3.5379606 3.3517638
OS 3.5416457 3.3485894
OS 3.5416457 3.3351115
OS 3.5366221 3.3341122
OS 3.5313296 3.3305759
OS 3.5277933 3.3252834
OS 3.5265515 3.3190405
OS 3.5277933 3.3127976
OS 3.5313296 3.3075051
OS 3.5366221 3.3039688
OS 3.542865 3.302727
OS 3.5491079 3.3039688
OS 3.5544004 3.3075051
OS 3.5579367 3.3127976
OS 3.5591785 3.3190405
OS 3.5579367 3.3252834
OS 3.5567372 3.3270787
OS 3.5594098 3.3320787
OS 3.5970157 3.3320787
OS 3.5970157 3.4386299
OS 3.5437835 3.4386299
OS 3.5417124 3.4436299
OS 3.5719104 3.4738279
OS 3.6123543 3.4738279
OS 3.6165996 3.4709913
OS 3.6228425 3.4697495
OS 3.6290854 3.4709913
OS 3.6343779 3.4745276
OS 3.6379142 3.4798201
OS 3.639156 3.486063
OS 3.6379142 3.4923059
OS 3.6343779 3.4975984
OS 3.6290854 3.5011347
OS 3.6228425 3.5023765
OE
OB 3.0688976 3.4119828 H
OS 3.0626547 3.410741
OS 3.057938 3.4075894
OS 3.0488976 3.4075894
OS 3.0442154 3.4066581
OS 3.0402461 3.4040058
OS 2.8356801 3.1994398
OS 2.8001001 3.1994398
OS 2.7987318 3.2014876
OS 2.7921788 3.2058662
OS 2.7844489 3.2074038
OS 2.7293307 3.2074038
OS 2.7216008 3.2058662
OS 2.7150478 3.2014876
OS 2.7106692 3.1949346
OS 2.7091316 3.1872047
OS 2.7106692 3.1794748
OS 2.7150478 3.1729218
OS 2.7216008 3.1685432
OS 2.7293307 3.1670056
OS 2.7844489 3.1670056
OS 2.7921788 3.1685432
OS 2.7987318 3.1729218
OS 2.8001001 3.1749696
OS 2.840748 3.1749696
OS 2.8454302 3.1759009
OS 2.8493995 3.1785532
OS 3.0539655 3.3831192
OS 3.0588808 3.3831192
OS 3.0626547 3.3805976
OS 3.0688976 3.3793558
OS 3.0751405 3.3805976
OS 3.080433 3.3841339
OS 3.0839693 3.3894264
OS 3.0852111 3.3956693
OS 3.0839693 3.4019122
OS 3.080433 3.4072047
OS 3.0751405 3.410741
OS 3.0688976 3.4119828
OE
OB 3.7448425 3.3583765 H
OS 3.7385996 3.3571347
OS 3.7358802 3.3553177
OS 3.7155433 3.3553177
OS 3.7155433 3.3572441
OS 3.6621417 3.3572441
OS 3.6621417 3.3123165
OS 3.6571416 3.3087203
OS 3.6538425 3.3093765
OS 3.6475996 3.3081347
OS 3.6423071 3.3045984
OS 3.6387708 3.2993059
OS 3.637529 3.293063
OS 3.6387708 3.2868201
OS 3.6423071 3.2815276
OS 3.6475996 3.2779913
OS 3.6538425 3.2767495
OS 3.6600854 3.2779913
OS 3.6653779 3.2815276
OS 3.6689142 3.2868201
OS 3.670156 3.293063
OS 3.6693979 3.296874
OS 3.6727539 3.3018741
OS 3.7155433 3.3018741
OS 3.7155433 3.3288083
OS 3.7358802 3.3288083
OS 3.7385996 3.3269913
OS 3.7448425 3.3257495
OS 3.7510854 3.3269913
OS 3.7563779 3.3305276
OS 3.7599142 3.3358201
OS 3.761156 3.342063
OS 3.7599142 3.3483059
OS 3.7563779 3.3535984
OS 3.7510854 3.3571347
OS 3.7448425 3.3583765
OE
OB 2.7844489 3.3074038 H
OS 2.7293307 3.3074038
OS 2.7216008 3.3058662
OS 2.7150478 3.3014876
OS 2.7106692 3.2949346
OS 2.7091316 3.2872047
OS 2.7106692 3.2794748
OS 2.7150478 3.2729218
OS 2.7216008 3.2685432
OS 2.7293307 3.2670056
OS 2.7844489 3.2670056
OS 2.7921788 3.2685432
OS 2.7987318 3.2729218
OS 2.8031104 3.2794748
OS 2.804648 3.2872047
OS 2.8031104 3.2949346
OS 2.7987318 3.3014876
OS 2.7921788 3.3058662
OS 2.7844489 3.3074038
OE
OB 3.4825906 3.2496536 H
OS 3.4789055 3.2496536
OS 3.4775905 3.2496535
OS 3.4248505 3.2496535
OS 3.4235355 3.2496536
OS 3.4198504 3.2496536
OS 3.4185354 3.2496535
OS 3.3657954 3.2496535
OS 3.3644804 3.2496536
OS 3.3607953 3.2496536
OS 3.3594803 3.2496535
OS 3.3054253 3.2496535
OS 3.3054253 3.1800905
OS 3.2820165 3.1566817
OS 3.2818334 3.156804
OS 3.2755905 3.1580458
OS 3.2693476 3.156804
OS 3.2640551 3.1532677
OS 3.2605188 3.1479752
OS 3.259277 3.1417323
OS 3.2605188 3.1354894
OS 3.2640551 3.1301969
OS 3.2693476 3.1266606
OS 3.2755905 3.1254188
OS 3.2818334 3.1266606
OS 3.2871259 3.1301969
OS 3.287954 3.1314363
OS 3.290583 3.1319592
OS 3.2945523 3.1346115
OS 3.3227283 3.1627875
OS 3.3594803 3.1627875
OS 3.3607953 3.1627874
OS 3.3644804 3.1627874
OS 3.3657954 3.1627875
OS 3.4185354 3.1627875
OS 3.4198504 3.1627874
OS 3.4235355 3.1627874
OS 3.4248505 3.1627875
OS 3.4775905 3.1627875
OS 3.4789055 3.1627874
OS 3.4825906 3.1627874
OS 3.4839056 3.1627875
OS 3.5379606 3.1627875
OS 3.5379606 3.2496535
OS 3.4839056 3.2496535
OS 3.4825906 3.2496536
OE
OB 3.7448425 3.2773765 H
OS 3.7385996 3.2761347
OS 3.7333071 3.2725984
OS 3.7297708 3.2673059
OS 3.728529 3.261063
OS 3.7297708 3.2548201
OS 3.7333071 3.2495276
OS 3.7385996 3.2459913
OS 3.7448425 3.2447495
OS 3.7510854 3.2459913
OS 3.7563779 3.2495276
OS 3.7599142 3.2548201
OS 3.761156 3.261063
OS 3.7599142 3.2673059
OS 3.7563779 3.2725984
OS 3.7510854 3.2761347
OS 3.7448425 3.2773765
OE
OB 3.2308425 3.2513765 H
OS 3.2245996 3.2501347
OS 3.2193071 3.2465984
OS 3.2157708 3.2413059
OS 3.214529 3.235063
OS 3.2157708 3.2288201
OS 3.2193071 3.2235276
OS 3.2245996 3.2199913
OS 3.2308425 3.2187495
OS 3.2370854 3.2199913
OS 3.2423779 3.2235276
OS 3.2459142 3.2288201
OS 3.247156 3.235063
OS 3.2459142 3.2413059
OS 3.2423779 3.2465984
OS 3.2370854 3.2501347
OS 3.2308425 3.2513765
OE
OB 3.1387796 3.2074038 H
OS 3.0836614 3.2074038
OS 3.0759315 3.2058662
OS 3.0693785 3.2014876
OS 3.0649999 3.1949346
OS 3.0634623 3.1872047
OS 3.0649999 3.1794748
OS 3.0693785 3.1729218
OS 3.0759315 3.1685432
OS 3.0836614 3.1670056
OS 3.1387796 3.1670056
OS 3.1465095 3.1685432
OS 3.1530625 3.1729218
OS 3.1543651 3.1748712
OS 3.1783409 3.1748712
OS 3.1827335 3.1719362
OS 3.1889764 3.1706944
OS 3.1952193 3.1719362
OS 3.2005118 3.1754725
OS 3.2040481 3.180765
OS 3.2052899 3.1870079
OS 3.2040481 3.1932508
OS 3.2005118 3.1985433
OS 3.1952193 3.2020796
OS 3.1889764 3.2033214
OS 3.1827335 3.2020796
OS 3.1786355 3.1993414
OS 3.1544966 3.1993414
OS 3.1530625 3.2014876
OS 3.1465095 3.2058662
OS 3.1387796 3.2074038
OE
OB 4.4778425 3.1513765 H
OS 4.4715996 3.1501347
OS 4.4663071 3.1465984
OS 4.4627708 3.1413059
OS 4.461529 3.135063
OS 4.4617892 3.1337547
OS 4.4530065 3.124972
OS 4.4474526 3.1264892
OS 4.4468695 3.1287533
OS 4.4469142 3.1288201
OS 4.448156 3.135063
OS 4.4469142 3.1413059
OS 4.4433779 3.1465984
OS 4.4380854 3.1501347
OS 4.4318425 3.1513765
OS 4.4255996 3.1501347
OS 4.4203071 3.1465984
OS 4.4167708 3.1413059
OS 4.415529 3.135063
OS 4.4167708 3.1288201
OS 4.4185878 3.1261007
OS 4.4185878 3.1204824
OS 4.3974833 3.0993779
OS 4.3742441 3.0993779
OS 4.3742441 3.0566063
OS 4.4154409 3.0566063
OS 4.4154409 3.0798455
OS 4.4296247 3.0940293
OS 4.4342441 3.0921158
OS 4.4342441 3.0566063
OS 4.4754409 3.0566063
OS 4.4754409 3.0993779
OS 4.4719735 3.0993779
OS 4.4699024 3.1043779
OS 4.486067 3.1205425
OS 4.4869999 3.1219387
OS 4.4893779 3.1235276
OS 4.4929142 3.1288201
OS 4.494156 3.135063
OS 4.4929142 3.1413059
OS 4.4893779 3.1465984
OS 4.4840854 3.1501347
OS 4.4778425 3.1513765
OE
OB 3.1387796 3.1574038 H
OS 3.0836614 3.1574038
OS 3.0759315 3.1558662
OS 3.0693785 3.1514876
OS 3.0649999 3.1449346
OS 3.0634623 3.1372047
OS 3.0649999 3.1294748
OS 3.0693785 3.1229218
OS 3.0759315 3.1185432
OS 3.0836614 3.1170056
OS 3.1387796 3.1170056
OS 3.1465095 3.1185432
OS 3.1530625 3.1229218
OS 3.1535101 3.1235917
OS 3.1725826 3.1235917
OS 3.1768279 3.1207551
OS 3.1830708 3.1195133
OS 3.1893137 3.1207551
OS 3.1946062 3.1242914
OS 3.1981425 3.1295839
OS 3.1993843 3.1358268
OS 3.1981425 3.1420697
OS 3.1946062 3.1473622
OS 3.1893137 3.1508985
OS 3.1830708 3.1521403
OS 3.1768279 3.1508985
OS 3.1725826 3.1480619
OS 3.1553515 3.1480619
OS 3.1530625 3.1514876
OS 3.1465095 3.1558662
OS 3.1387796 3.1574038
OE
OB 2.7844489 3.1574038 H
OS 2.7293307 3.1574038
OS 2.7216008 3.1558662
OS 2.7150478 3.1514876
OS 2.7106692 3.1449346
OS 2.7091316 3.1372047
OS 2.7106692 3.1294748
OS 2.7150478 3.1229218
OS 2.7216008 3.1185432
OS 2.7293307 3.1170056
OS 2.7844489 3.1170056
OS 2.7921788 3.1185432
OS 2.7987318 3.1229218
OS 2.8031104 3.1294748
OS 2.804648 3.1372047
OS 2.8031104 3.1449346
OS 2.7987318 3.1514876
OS 2.7921788 3.1558662
OS 2.7844489 3.1574038
OE
OB 3.9398425 3.1373765 H
OS 3.9335996 3.1361347
OS 3.9283071 3.1325984
OS 3.9247708 3.1273059
OS 3.923529 3.121063
OS 3.9247708 3.1148201
OS 3.9283071 3.1095276
OS 3.9335996 3.1059913
OS 3.9398425 3.1047495
OS 3.9460854 3.1059913
OS 3.9513779 3.1095276
OS 3.9549142 3.1148201
OS 3.956156 3.121063
OS 3.9549142 3.1273059
OS 3.9513779 3.1325984
OS 3.9460854 3.1361347
OS 3.9398425 3.1373765
OE
OB 3.8068425 3.2513765 H
OS 3.8005996 3.2501347
OS 3.7953071 3.2465984
OS 3.7917708 3.2413059
OS 3.790529 3.235063
OS 3.7917708 3.2288201
OS 3.793481 3.2262604
OS 3.789967 3.2225198
OS 3.7873601 3.2225197
OS 3.7492441 3.2225197
OS 3.7492441 3.1797481
OS 3.7724833 3.1797481
OS 3.8525409 3.0996905
OS 3.8568411 3.0968172
OS 3.8619134 3.0958083
OS 3.8718802 3.0958083
OS 3.8745996 3.0939913
OS 3.8808425 3.0927495
OS 3.8870854 3.0939913
OS 3.8923779 3.0975276
OS 3.8959142 3.1028201
OS 3.897156 3.109063
OS 3.8959142 3.1153059
OS 3.8923779 3.1205984
OS 3.8870854 3.1241347
OS 3.8808425 3.1253765
OS 3.8745996 3.1241347
OS 3.8718802 3.1223177
OS 3.8674037 3.1223177
OS 3.8587005 3.1310209
OS 3.860152 3.1358056
OS 3.8610854 3.1359913
OS 3.8663779 3.1395276
OS 3.8699142 3.1448201
OS 3.871156 3.151063
OS 3.8699142 3.1573059
OS 3.8663779 3.1625984
OS 3.8610854 3.1661347
OS 3.8548425 3.1673765
OS 3.8485996 3.1661347
OS 3.8483568 3.1659724
OS 3.8447519 3.1695773
OS 3.8449142 3.1698201
OS 3.846156 3.176063
OS 3.8449142 3.1823059
OS 3.8413779 3.1875984
OS 3.8360854 3.1911347
OS 3.8298425 3.1923765
OS 3.8235996 3.1911347
OS 3.8183071 3.1875984
OS 3.8162663 3.1845441
OS 3.8106076 3.1832934
OS 3.810036 3.183429
OS 3.810498 3.1889396
OS 3.8113779 3.1895276
OS 3.8149142 3.1948201
OS 3.816156 3.201063
OS 3.8149142 3.2073059
OS 3.8113779 3.2125984
OS 3.8091229 3.2141051
OS 3.8101787 3.2194131
OS 3.8130854 3.2199913
OS 3.8183779 3.2235276
OS 3.8219142 3.2288201
OS 3.823156 3.235063
OS 3.8219142 3.2413059
OS 3.8183779 3.2465984
OS 3.8130854 3.2501347
OS 3.8068425 3.2513765
OE
OB 3.1387796 3.1074038 H
OS 3.0836614 3.1074038
OS 3.0759315 3.1058662
OS 3.0693785 3.1014876
OS 3.0649999 3.0949346
OS 3.0634623 3.0872047
OS 3.0649999 3.0794748
OS 3.0693785 3.0729218
OS 3.0759315 3.0685432
OS 3.0836614 3.0670056
OS 3.1387796 3.0670056
OS 3.1465095 3.0685432
OS 3.1530625 3.0729218
OS 3.1574411 3.0794748
OS 3.1589787 3.0872047
OS 3.1574411 3.0949346
OS 3.1530625 3.1014876
OS 3.1465095 3.1058662
OS 3.1387796 3.1074038
OE
OB 2.7844489 3.1074038 H
OS 2.7293307 3.1074038
OS 2.7216008 3.1058662
OS 2.7150478 3.1014876
OS 2.7106692 3.0949346
OS 2.7091316 3.0872047
OS 2.7106692 3.0794748
OS 2.7150478 3.0729218
OS 2.7216008 3.0685432
OS 2.7293307 3.0670056
OS 2.7844489 3.0670056
OS 2.7921788 3.0685432
OS 2.7987318 3.0729218
OS 2.8031104 3.0794748
OS 2.804648 3.0872047
OS 2.8031104 3.0949346
OS 2.7987318 3.1014876
OS 2.7921788 3.1058662
OS 2.7844489 3.1074038
OE
OB 4.0688425 3.1513765 H
OS 4.0625996 3.1501347
OS 4.0573071 3.1465984
OS 4.0537708 3.1413059
OS 4.0531328 3.1380983
OS 4.0435176 3.1284831
OS 4.0406444 3.124183
OS 4.0398609 3.1202441
OS 4.0131417 3.1202441
OS 4.0131417 3.0648741
OS 4.0665433 3.0648741
OS 4.0665433 3.1140188
OS 4.0718778 3.1193533
OS 4.0750854 3.1199913
OS 4.0803779 3.1235276
OS 4.0839142 3.1288201
OS 4.085156 3.135063
OS 4.0839142 3.1413059
OS 4.0803779 3.1465984
OS 4.0750854 3.1501347
OS 4.0688425 3.1513765
OE
OB 4.3338425 3.1513765 H
OS 4.3275996 3.1501347
OS 4.3223071 3.1465984
OS 4.3187708 3.1413059
OS 4.317529 3.135063
OS 4.3187708 3.1288201
OS 4.3215878 3.1246041
OS 4.3215878 3.0993779
OS 4.3142441 3.0993779
OS 4.3142441 3.0566063
OS 4.3554409 3.0566063
OS 4.3554409 3.0993779
OS 4.3480972 3.0993779
OS 4.3480972 3.1275974
OS 4.3489142 3.1288201
OS 4.350156 3.135063
OS 4.3489142 3.1413059
OS 4.3453779 3.1465984
OS 4.3400854 3.1501347
OS 4.3338425 3.1513765
OE
OB 4.2728425 3.1513765 H
OS 4.2665996 3.1501347
OS 4.2613071 3.1465984
OS 4.2577708 3.1413059
OS 4.256529 3.135063
OS 4.2577708 3.1288201
OS 4.2595878 3.1261007
OS 4.2595878 3.0993779
OS 4.2542441 3.0993779
OS 4.2542441 3.0566063
OS 4.2954409 3.0566063
OS 4.2954409 3.0993779
OS 4.2860972 3.0993779
OS 4.2860972 3.1261007
OS 4.2879142 3.1288201
OS 4.289156 3.135063
OS 4.2879142 3.1413059
OS 4.2843779 3.1465984
OS 4.2790854 3.1501347
OS 4.2728425 3.1513765
OE
OB 4.2400472 3.2826063 H
OS 4.1787716 3.2826063
OS 4.1787716 3.2095197
OS 4.1961547 3.2095197
OS 4.1961547 3.1448737
OS 4.1937708 3.1413059
OS 4.192529 3.135063
OS 4.1937708 3.1288201
OS 4.1973071 3.1235276
OS 4.1996851 3.1219387
OS 4.200618 3.1205425
OS 4.2065878 3.1145727
OS 4.2065878 3.0993779
OS 4.1992441 3.0993779
OS 4.1992441 3.0566063
OS 4.2404409 3.0566063
OS 4.2404409 3.0993779
OS 4.2330972 3.0993779
OS 4.2330972 3.120063
OS 4.2320882 3.1251354
OS 4.229215 3.1294355
OS 4.2248958 3.1337547
OS 4.225156 3.135063
OS 4.2239142 3.1413059
OS 4.2226641 3.1431768
OS 4.2226641 3.2095197
OS 4.2400472 3.2095197
OS 4.2400472 3.2826063
OE
OB 4.1528425 3.1513765 H
OS 4.1465996 3.1501347
OS 4.1413071 3.1465984
OS 4.1377708 3.1413059
OS 4.136529 3.135063
OS 4.1377708 3.1288201
OS 4.1413071 3.1235276
OS 4.1416547 3.1232953
OS 4.1417448 3.1228426
OS 4.144618 3.1185425
OS 4.1515878 3.1115727
OS 4.1515878 3.0993779
OS 4.1442441 3.0993779
OS 4.1442441 3.0566063
OS 4.1854409 3.0566063
OS 4.1854409 3.0993779
OS 4.1780972 3.0993779
OS 4.1780972 3.117063
OS 4.1770882 3.1221354
OS 4.174215 3.1264355
OS 4.1685639 3.1320866
OS 4.169156 3.135063
OS 4.1679142 3.1413059
OS 4.1643779 3.1465984
OS 4.1590854 3.1501347
OS 4.1528425 3.1513765
OE
OB 4.1148425 3.1513765 H
OS 4.1085996 3.1501347
OS 4.1033071 3.1465984
OS 4.0997708 3.1413059
OS 4.098529 3.135063
OS 4.0989172 3.1331115
OS 4.0975968 3.1311354
OS 4.0965878 3.126063
OS 4.0965878 3.0993779
OS 4.0892441 3.0993779
OS 4.0892441 3.0566063
OS 4.1304409 3.0566063
OS 4.1304409 3.0993779
OS 4.1230972 3.0993779
OS 4.1230972 3.1205877
OS 4.1239999 3.1219387
OS 4.1263779 3.1235276
OS 4.1299142 3.1288201
OS 4.131156 3.135063
OS 4.1299142 3.1413059
OS 4.1263779 3.1465984
OS 4.1210854 3.1501347
OS 4.1148425 3.1513765
OE
OB 3.7303858 3.1482677 H
OS 3.6572992 3.1482677
OS 3.6572992 3.0869921
OS 3.7045878 3.0869921
OS 3.7045878 3.0810253
OS 3.7027708 3.0783059
OS 3.701529 3.072063
OS 3.7027708 3.0658201
OS 3.7063071 3.0605276
OS 3.7115996 3.0569913
OS 3.7178425 3.0557495
OS 3.7240854 3.0569913
OS 3.7293779 3.0605276
OS 3.7329142 3.0658201
OS 3.734156 3.072063
OS 3.7329142 3.0783059
OS 3.7310972 3.0810253
OS 3.7310972 3.0936299
OS 3.7306405 3.095926
OS 3.7306405 3.0999921
OS 3.7303858 3.1012725
OS 3.7303858 3.1482677
OE
OB 3.1387796 3.0574038 H
OS 3.0836614 3.0574038
OS 3.0759315 3.0558662
OS 3.0693785 3.0514876
OS 3.0649999 3.0449346
OS 3.0634623 3.0372047
OS 3.0649999 3.0294748
OS 3.0693785 3.0229218
OS 3.0759315 3.0185432
OS 3.0836614 3.0170056
OS 3.1387796 3.0170056
OS 3.1465095 3.0185432
OS 3.1530625 3.0229218
OS 3.1574411 3.0294748
OS 3.1589787 3.0372047
OS 3.1574411 3.0449346
OS 3.1530625 3.0514876
OS 3.1465095 3.0558662
OS 3.1387796 3.0574038
OE
OB 2.7844489 3.0574038 H
OS 2.7293307 3.0574038
OS 2.7216008 3.0558662
OS 2.7150478 3.0514876
OS 2.7106692 3.0449346
OS 2.7091316 3.0372047
OS 2.7106692 3.0294748
OS 2.7150478 3.0229218
OS 2.7216008 3.0185432
OS 2.7293307 3.0170056
OS 2.7844489 3.0170056
OS 2.7921788 3.0185432
OS 2.7987318 3.0229218
OS 2.8031104 3.0294748
OS 2.804648 3.0372047
OS 2.8031104 3.0449346
OS 2.7987318 3.0514876
OS 2.7921788 3.0558662
OS 2.7844489 3.0574038
OE
OB 3.1387796 3.0074038 H
OS 3.0836614 3.0074038
OS 3.0759315 3.0058662
OS 3.0693785 3.0014876
OS 3.0649999 2.9949346
OS 3.0634623 2.9872047
OS 3.0649999 2.9794748
OS 3.0693785 2.9729218
OS 3.0759315 2.9685432
OS 3.0836614 2.9670056
OS 3.1387796 2.9670056
OS 3.1465095 2.9685432
OS 3.1530625 2.9729218
OS 3.1574411 2.9794748
OS 3.1589787 2.9872047
OS 3.1574411 2.9949346
OS 3.1530625 3.0014876
OS 3.1465095 3.0058662
OS 3.1387796 3.0074038
OE
OB 2.7844489 3.0074038 H
OS 2.7293307 3.0074038
OS 2.7216008 3.0058662
OS 2.7150478 3.0014876
OS 2.7106692 2.9949346
OS 2.7091316 2.9872047
OS 2.7106692 2.9794748
OS 2.7150478 2.9729218
OS 2.7216008 2.9685432
OS 2.7293307 2.9670056
OS 2.7844489 2.9670056
OS 2.7921788 2.9685432
OS 2.7987318 2.9729218
OS 2.8031104 2.9794748
OS 2.804648 2.9872047
OS 2.8031104 2.9949346
OS 2.7987318 3.0014876
OS 2.7921788 3.0058662
OS 2.7844489 3.0074038
OE
OB 3.1387796 2.9574038 H
OS 3.0836614 2.9574038
OS 3.0759315 2.9558662
OS 3.0693785 2.9514876
OS 3.0649999 2.9449346
OS 3.0634623 2.9372047
OS 3.0649999 2.9294748
OS 3.0693785 2.9229218
OS 3.0759315 2.9185432
OS 3.0836614 2.9170056
OS 3.1387796 2.9170056
OS 3.1465095 2.9185432
OS 3.1530625 2.9229218
OS 3.1574411 2.9294748
OS 3.1589787 2.9372047
OS 3.1574411 2.9449346
OS 3.1530625 2.9514876
OS 3.1465095 2.9558662
OS 3.1387796 2.9574038
OE
OB 2.7844489 2.9574038 H
OS 2.7293307 2.9574038
OS 2.7216008 2.9558662
OS 2.7150478 2.9514876
OS 2.7106692 2.9449346
OS 2.7091316 2.9372047
OS 2.7106692 2.9294748
OS 2.7150478 2.9229218
OS 2.7216008 2.9185432
OS 2.7293307 2.9170056
OS 2.7844489 2.9170056
OS 2.7921788 2.9185432
OS 2.7987318 2.9229218
OS 2.8031104 2.9294748
OS 2.804648 2.9372047
OS 2.8031104 2.9449346
OS 2.7987318 2.9514876
OS 2.7921788 2.9558662
OS 2.7844489 2.9574038
OE
SE
S P 0
OB 6.8051181 2.7027559 I
OS 6.3523621 2.7027559
OS 6.3326771 2.6830709
OS 6.3326771 2.4862205
OS 6.1161417 2.4862205
OS 6.1109186 2.4809974
OS 6.1062992 2.4829109
OS 6.1062992 2.7716536
OS 6.4507874 2.7716536
OS 6.4606299 2.7814961
OS 6.4606299 2.9685039
OS 6.8051181 2.9685039
OS 6.8051181 2.7027559
OE
SE
S P 0
OB 6.9429134 1.511811 I
OS 6.726378 1.2952756
OS 6.6633858 1.2952756
OS 6.6633858 1.5904646
OS 6.6642991 1.5904646
OS 6.6642991 1.6316614
OS 6.6633858 1.6316614
OS 6.6633858 1.6504646
OS 6.6642991 1.6504646
OS 6.6642991 1.6916614
OS 6.6633858 1.6916614
OS 6.6633858 1.7004646
OS 6.6642991 1.7004646
OS 6.6642991 1.7416614
OS 6.6633858 1.7416614
OS 6.6633858 1.7554646
OS 6.6642991 1.7554646
OS 6.6642991 1.7883149
OS 6.6882033 1.8122191
OS 6.6920854 1.8129913
OS 6.6948048 1.8148083
OS 6.7055039 1.8148083
OS 6.7055039 1.788378
OS 6.7498503 1.788378
OS 6.7498503 1.8437479
OS 6.7537284 1.8464567
OS 6.7559565 1.8464567
OS 6.7598346 1.8437479
OS 6.7598346 1.788378
OS 6.804181 1.788378
OS 6.804181 1.8437479
OS 6.8080591 1.8464567
OS 6.8709565 1.8464567
OS 6.8748346 1.8437479
OS 6.8748346 1.788378
OS 6.919181 1.788378
OS 6.919181 1.8437479
OS 6.9230591 1.8464567
OS 6.9429134 1.8464567
OS 6.9429134 1.511811
OE
SE
S P 0
OB 7.0019685 3.5 I
OS 6.4704724 3.5
OS 6.4704724 3.8937008
OS 7.0019685 3.8937008
OS 7.0019685 3.5
OE
OB 6.9001969 3.6472339 H
OS 6.8852614 3.6452676
OS 6.8713437 3.6395027
OS 6.8593924 3.6303321
OS 6.8502218 3.6183808
OS 6.8444569 3.6044631
OS 6.8424906 3.5895276
OS 6.8444569 3.5745921
OS 6.8502218 3.5606744
OS 6.8593924 3.5487231
OS 6.8713437 3.5395525
OS 6.8852614 3.5337876
OS 6.9001969 3.5318213
OS 6.9151324 3.5337876
OS 6.9290501 3.5395525
OS 6.9410014 3.5487231
OS 6.950172 3.5606744
OS 6.9559369 3.5745921
OS 6.9579032 3.5895276
OS 6.9559369 3.6044631
OS 6.950172 3.6183808
OS 6.9410014 3.6303321
OS 6.9290501 3.6395027
OS 6.9151324 3.6452676
OS 6.9001969 3.6472339
OE
OB 6.7348425 3.6472339 H
OS 6.719907 3.6452676
OS 6.7059893 3.6395027
OS 6.694038 3.6303321
OS 6.6848674 3.6183808
OS 6.6791025 3.6044631
OS 6.6771362 3.5895276
OS 6.6791025 3.5745921
OS 6.6848674 3.5606744
OS 6.694038 3.5487231
OS 6.7059893 3.5395525
OS 6.719907 3.5337876
OS 6.7348425 3.5318213
OS 6.749778 3.5337876
OS 6.7636957 3.5395525
OS 6.775647 3.5487231
OS 6.7848176 3.5606744
OS 6.7905825 3.5745921
OS 6.7925488 3.5895276
OS 6.7905825 3.6044631
OS 6.7848176 3.6183808
OS 6.775647 3.6303321
OS 6.7636957 3.6395027
OS 6.749778 3.6452676
OS 6.7348425 3.6472339
OE
OB 6.5694882 3.6472339 H
OS 6.5545527 3.6452676
OS 6.540635 3.6395027
OS 6.5286837 3.6303321
OS 6.5195131 3.6183807
OS 6.5137482 3.6044631
OS 6.5117819 3.5895276
OS 6.5137482 3.5745921
OS 6.5195131 3.5606745
OS 6.5286837 3.5487231
OS 6.540635 3.5395525
OS 6.5545527 3.5337876
OS 6.5694882 3.5318213
OS 6.5844237 3.5337876
OS 6.5983414 3.5395525
OS 6.6102927 3.5487231
OS 6.6194633 3.5606745
OS 6.6252282 3.5745921
OS 6.6271945 3.5895276
OS 6.6252282 3.6044631
OS 6.6194633 3.6183807
OS 6.6102927 3.6303321
OS 6.5983414 3.6395027
OS 6.5844237 3.6452676
OS 6.5694882 3.6472339
OE
SE
P 0.149508 2.830047 80 P 0 0 ;0=70,1=1
P 0.149508 3.853669 80 P 0 0 ;0=70,1=1
P 0.6538425 1.551063 79 P 0 0 ;0=69,1=1
P 0.6539669 2.5938902 79 P 0 0 ;0=69,1=1
P 0.6548425 0.790063 79 P 0 0 ;0=69,1=1
P 0.6548425 1.314063 79 P 0 0 ;0=69,1=1
P 0.6548425 1.839063 79 P 0 0 ;0=69,1=1
P 0.6548425 2.073063 79 P 0 0 ;0=69,1=1
P 0.6548425 2.365063 79 P 0 0 ;0=69,1=1
P 0.6558425 1.028063 79 P 0 0 ;0=69,1=1
P 0.9370078 2.3179133 79 P 0 0 ;0=69,1=1
P 0.988189 1.7175197 79 P 0 0 ;0=69,1=1
P 0.9901575 0.6870079 79 P 0 0 ;0=69,1=1
P 0.996063 1.1870079 79 P 0 0 ;0=69,1=1
P 0.9968357 2.256036 79 P 0 0 ;0=69,1=1
P 1.0048425 0.906063 79 P 0 0 ;0=69,1=1
P 1.0088425 1.430063 79 P 0 0 ;0=69,1=1
P 1.0098425 1.956063 79 P 0 0 ;0=69,1=1
P 1.0208425 2.481063 79 P 0 0 ;0=69,1=1
P 1.2428425 1.472063 79 P 0 0 ;0=69,1=1
P 1.2488425 2.000063 79 P 0 0 ;0=69,1=1
P 1.2568425 0.942063 79 P 0 0 ;0=69,1=1
P 1.2618425 2.482063 79 P 0 0 ;0=69,1=1
P 1.2948425 4.256063 79 P 0 0 ;0=69,1=1
P 1.3454724 4.1751969 79 P 0 0 ;0=69,1=1
P 1.3937008 1.8169291 79 P 0 0 ;0=69,1=1
P 1.4084645 3.980315 79 P 0 0 ;0=69,1=1
P 1.4408425 3.557063 79 P 0 0 ;0=69,1=1
P 1.4598425 3.147063 79 P 0 0 ;0=69,1=1
P 1.5498425 3.621063 79 P 0 0 ;0=69,1=1
P 1.5578425 4.229063 79 P 0 0 ;0=69,1=1
P 1.5679134 1.2854331 79 P 0 0 ;0=69,1=1
P 1.5682025 2.067703 79 P 0 0 ;0=69,1=1
P 1.5698819 4.1712599 79 P 0 0 ;0=69,1=1
P 1.5748425 3.596063 79 P 0 0 ;0=69,1=1
P 1.6198425 2.121063 79 P 0 0 ;0=69,1=1
P 1.6708425 1.595063 79 P 0 0 ;0=69,1=1
P 1.6708425 1.694063 79 P 0 0 ;0=69,1=1
P 1.6718425 1.399063 79 P 0 0 ;0=69,1=1
P 1.6718425 1.497063 79 P 0 0 ;0=69,1=1
P 1.6718425 1.792063 79 P 0 0 ;0=69,1=1
P 1.6748425 1.989063 79 P 0 0 ;0=69,1=1
P 1.6758425 1.891063 79 P 0 0 ;0=69,1=1
P 1.6918425 4.079063 79 P 0 0 ;0=69,1=1
P 1.7148425 1.595063 79 P 0 0 ;0=69,1=1
P 1.7168425 1.399063 79 P 0 0 ;0=69,1=1
P 1.7188425 1.497063 79 P 0 0 ;0=69,1=1
P 1.7188425 1.792063 79 P 0 0 ;0=69,1=1
P 1.7198425 1.536063 79 P 0 0 ;0=69,1=1
P 1.7218425 1.694063 79 P 0 0 ;0=69,1=1
P 1.7218425 1.890063 79 P 0 0 ;0=69,1=1
P 1.7218425 1.989063 79 P 0 0 ;0=69,1=1
P 1.7268425 4.329374 79 P 0 0 ;0=69,1=1
P 1.7498425 4.110063 79 P 0 0 ;0=69,1=1
P 1.7548425 2.126063 79 P 0 0 ;0=69,1=1
P 1.7548425 3.661063 79 P 0 0 ;0=69,1=1
P 1.7798425 4.156063 79 P 0 0 ;0=69,1=1
P 1.7888425 4.329374 79 P 0 0 ;0=69,1=1
P 1.7978425 0.355063 79 P 0 0 ;0=69,1=1
P 1.7982283 1.3041339 79 P 0 0 ;0=69,1=1
P 1.8227825 1.674003 79 P 0 0 ;0=69,1=1
P 1.8326771 0.2559055 79 P 0 0 ;0=69,1=1
P 1.8326771 0.2874016 79 P 0 0 ;0=69,1=1
P 1.8498425 3.701063 79 P 0 0 ;0=69,1=1
P 1.8523622 0.2559055 79 P 0 0 ;0=69,1=1
P 1.8523622 0.2874016 79 P 0 0 ;0=69,1=1
P 1.8720472 0.2559055 79 P 0 0 ;0=69,1=1
P 1.8720472 0.2874016 79 P 0 0 ;0=69,1=1
P 1.8799377 1.811803 79 P 0 0 ;0=69,1=1
P 1.8848425 2.071063 79 P 0 0 ;0=69,1=1
P 1.8848425 3.601063 79 P 0 0 ;0=69,1=1
P 1.8938425 1.693063 79 P 0 0 ;0=69,1=1
P 1.8973025 1.516523 79 P 0 0 ;0=69,1=1
P 1.9038425 4.018063 79 P 0 0 ;0=69,1=1
P 1.9161425 0.244763 79 P 0 0 ;0=69,1=1
P 2.0048425 1.336063 79 P 0 0 ;0=69,1=1
P 2.0048425 3.816063 79 P 0 0 ;0=69,1=1
P 2.0288425 1.361663 79 P 0 0 ;0=69,1=1
P 2.0298425 3.836063 79 P 0 0 ;0=69,1=1
P 2.0348425 0.246063 79 P 0 0 ;0=69,1=1
P 2.0598425 1.386063 79 P 0 0 ;0=69,1=1
P 2.0598425 3.871063 79 P 0 0 ;0=69,1=1
P 2.0767716 0.2559055 79 P 0 0 ;0=69,1=1
P 2.0767716 0.2874016 79 P 0 0 ;0=69,1=1
P 2.0838425 1.411663 79 P 0 0 ;0=69,1=1
P 2.0848425 3.896063 79 P 0 0 ;0=69,1=1
P 2.1122047 0.2559055 79 P 0 0 ;0=69,1=1
P 2.1122047 0.2874016 79 P 0 0 ;0=69,1=1
P 2.1398425 3.611063 79 P 0 0 ;0=69,1=1
P 2.1398425 3.738063 79 P 0 0 ;0=69,1=1
P 2.1460663 4.1037909 79 P 0 0 ;0=69,1=1
P 2.1468425 2.753063 79 P 0 0 ;0=69,1=1
P 2.1515748 0.2559055 79 P 0 0 ;0=69,1=1
P 2.1515748 0.2874016 79 P 0 0 ;0=69,1=1
P 2.2058425 3.200063 79 P 0 0 ;0=69,1=1
P 2.2068425 1.298063 79 P 0 0 ;0=69,1=1
P 2.2317425 2.584163 79 P 0 0 ;0=69,1=1
P 2.2348425 3.506063 79 P 0 0 ;0=69,1=1
P 2.2523425 2.613563 79 P 0 0 ;0=69,1=1
P 2.2538425 2.279063 79 P 0 0 ;0=69,1=1
P 2.253937 4.0866142 79 P 0 0 ;0=69,1=1
P 2.2548425 3.536063 79 P 0 0 ;0=69,1=1
P 2.2588425 3.741063 79 P 0 0 ;0=69,1=1
P 2.2598425 3.261063 79 P 0 0 ;0=69,1=1
P 2.2720325 2.463873 79 P 0 0 ;0=69,1=1
P 2.2748425 1.506063 79 P 0 0 ;0=69,1=1
P 2.2908425 4.217063 79 P 0 0 ;0=69,1=1
P 2.2998425 1.916063 79 P 0 0 ;0=69,1=1
P 2.3098425 0.246063 79 P 0 0 ;0=69,1=1
P 2.3114125 1.0900094 79 P 0 0 ;0=69,1=1
P 2.3118425 0.934063 79 P 0 0 ;0=69,1=1
P 2.3215354 2.586063 79 P 0 0 ;0=69,1=1
P 2.3215354 3.361063 79 P 0 0 ;0=69,1=1
P 2.3308425 2.215063 79 P 0 0 ;0=69,1=1
P 2.3503937 0.4055118 79 P 0 0 ;0=69,1=1
P 2.3533464 4.0177165 79 P 0 0 ;0=69,1=1
P 2.3848425 1.941063 79 P 0 0 ;0=69,1=1
P 2.3897638 0.4055118 79 P 0 0 ;0=69,1=1
P 2.3898425 3.481063 79 P 0 0 ;0=69,1=1
P 2.394685 2.7204724 79 P 0 0 ;0=69,1=1
P 2.4048425 2.412063 79 P 0 0 ;0=69,1=1
P 2.4098325 0.932053 79 P 0 0 ;0=69,1=1
P 2.4098325 1.088053 79 P 0 0 ;0=69,1=1
P 2.4098425 1.967063 79 P 0 0 ;0=69,1=1
P 2.4098425 2.283063 79 P 0 0 ;0=69,1=1
P 2.4098425 2.314063 79 P 0 0 ;0=69,1=1
P 2.4098425 2.579063 79 P 0 0 ;0=69,1=1
P 2.4133858 0.2795276 79 P 0 0 ;0=69,1=1
P 2.4138425 3.295063 79 P 0 0 ;0=69,1=1
P 2.4140551 3.1998504 79 P 0 0 ;0=69,1=1
P 2.4187174 3.1185066 79 P 0 0 ;0=69,1=1
P 2.4192759 2.7886295 79 P 0 0 ;0=69,1=1
P 2.4291925 2.621063 79 P 0 0 ;0=69,1=1
P 2.4348425 3.546063 79 P 0 0 ;0=69,1=1
P 2.4448819 0.2795276 79 P 0 0 ;0=69,1=1
P 2.4468425 1.437063 79 P 0 0 ;0=69,1=1
P 2.4470546 0.2425914 79 P 0 0 ;0=69,1=1
P 2.4508425 2.282063 79 P 0 0 ;0=69,1=1
P 2.462374 3.1722441 79 P 0 0 ;0=69,1=1
P 2.4698827 0.4109883 79 P 0 0 ;0=69,1=1
P 2.4738425 2.980063 79 P 0 0 ;0=69,1=1
P 2.4758425 2.291063 79 P 0 0 ;0=69,1=1
P 2.4758425 2.456063 79 P 0 0 ;0=69,1=1
P 2.4788425 0.937063 79 P 0 0 ;0=69,1=1
P 2.4888425 2.413063 79 P 0 0 ;0=69,1=1
P 2.4948425 2.661063 79 P 0 0 ;0=69,1=1
P 2.4948425 2.696063 79 P 0 0 ;0=69,1=1
P 2.4998425 2.236063 79 P 0 0 ;0=69,1=1
P 2.5028425 1.316063 79 P 0 0 ;0=69,1=1
P 2.5082625 0.931483 79 P 0 0 ;0=69,1=1
P 2.5088425 1.090063 79 P 0 0 ;0=69,1=1
P 2.511811 0.4055118 79 P 0 0 ;0=69,1=1
P 2.5258425 2.463063 79 P 0 0 ;0=69,1=1
P 2.531398 2.830047 80 P 0 0 ;0=70,1=1
P 2.531398 3.853669 80 P 0 0 ;0=70,1=1
P 2.5460625 0.244843 79 P 0 0 ;0=69,1=1
P 2.5498425 1.755063 79 P 0 0 ;0=69,1=1
P 2.5708425 4.283063 79 P 0 0 ;0=69,1=1
P 2.5758425 2.412063 79 P 0 0 ;0=69,1=1
P 2.5787402 0.2795276 79 P 0 0 ;0=69,1=1
P 2.5798425 1.790063 79 P 0 0 ;0=69,1=1
P 2.5798425 2.281063 79 P 0 0 ;0=69,1=1
P 2.5798425 3.486063 79 P 0 0 ;0=69,1=1
P 2.5818425 2.308063 79 P 0 0 ;0=69,1=1
P 2.5868425 2.569063 79 P 0 0 ;0=69,1=1
P 2.5908425 3.288063 79 P 0 0 ;0=69,1=1
P 2.5918425 3.1862205 79 P 0 0 ;0=69,1=1
P 2.5984252 0.7952756 79 P 0 0 ;0=69,1=1
P 2.5998425 2.436063 79 P 0 0 ;0=69,1=1
P 2.6048425 1.734063 79 P 0 0 ;0=69,1=1
P 2.6066825 0.931903 79 P 0 0 ;0=69,1=1
P 2.6068425 1.091063 79 P 0 0 ;0=69,1=1
P 2.6102362 0.2795276 79 P 0 0 ;0=69,1=1
P 2.6220472 0.976378 79 P 0 0 ;0=69,1=1
P 2.6248425 2.461063 79 P 0 0 ;0=69,1=1
P 2.6259843 0.7952756 79 P 0 0 ;0=69,1=1
P 2.6268425 1.770063 79 P 0 0 ;0=69,1=1
P 2.6318425 2.876063 79 P 0 0 ;0=69,1=1
P 2.6348425 3.406063 79 P 0 0 ;0=69,1=1
P 2.636874 0.2479055 79 P 0 0 ;0=69,1=1
P 2.6438425 1.616063 79 P 0 0 ;0=69,1=1
P 2.6458425 2.274063 79 P 0 0 ;0=69,1=1
P 2.6496063 0.976378 79 P 0 0 ;0=69,1=1
P 2.6653543 0.4055118 79 P 0 0 ;0=69,1=1
P 2.6653543 0.7952756 79 P 0 0 ;0=69,1=1
P 2.6658425 1.092063 79 P 0 0 ;0=69,1=1
P 2.6658425 2.291063 79 P 0 0 ;0=69,1=1
P 2.6668425 1.640063 79 P 0 0 ;0=69,1=1
P 2.6748425 3.501063 79 P 0 0 ;0=69,1=1
P 2.6798425 3.661063 79 P 0 0 ;0=69,1=1
P 2.6811024 0.976378 79 P 0 0 ;0=69,1=1
P 2.6858425 2.311063 79 P 0 0 ;0=69,1=1
P 2.6858425 2.568063 79 P 0 0 ;0=69,1=1
P 2.6929134 0.7952756 79 P 0 0 ;0=69,1=1
P 2.6929134 2.7214567 79 P 0 0 ;0=69,1=1
P 2.6948425 1.481063 79 P 0 0 ;0=69,1=1
P 2.7028425 2.289063 79 P 0 0 ;0=69,1=1
P 2.7047244 0.4055118 79 P 0 0 ;0=69,1=1
P 2.7086614 0.976378 79 P 0 0 ;0=69,1=1
P 2.7198425 1.591063 79 P 0 0 ;0=69,1=1
P 2.7224094 3.7860709 79 P 0 0 ;0=69,1=1
P 2.7244825 1.093063 79 P 0 0 ;0=69,1=1
P 2.7248425 3.521063 79 P 0 0 ;0=69,1=1
P 2.7248425 3.729063 79 P 0 0 ;0=69,1=1
P 2.7268425 2.293063 79 P 0 0 ;0=69,1=1
P 2.7322835 0.7952756 79 P 0 0 ;0=69,1=1
P 2.7401575 0.976378 79 P 0 0 ;0=69,1=1
P 2.74882 0.282312 79 P 0 0 ;0=69,1=1
P 2.7598425 0.7952756 79 P 0 0 ;0=69,1=1
P 2.7677165 0.976378 79 P 0 0 ;0=69,1=1
P 2.7748425 3.566063 79 P 0 0 ;0=69,1=1
P 2.7795276 0.2795276 79 P 0 0 ;0=69,1=1
P 2.7838425 2.429063 79 P 0 0 ;0=69,1=1
P 2.7838425 2.568063 79 P 0 0 ;0=69,1=1
P 2.7841625 1.094063 79 P 0 0 ;0=69,1=1
P 2.7992126 0.7952756 79 P 0 0 ;0=69,1=1
P 2.7992126 0.976378 79 P 0 0 ;0=69,1=1
P 2.7998425 3.616063 79 P 0 0 ;0=69,1=1
P 2.7999951 0.2519685 79 P 0 0 ;0=69,1=1
P 2.8038425 2.307063 79 P 0 0 ;0=69,1=1
P 2.8218425 2.601063 79 P 0 0 ;0=69,1=1
P 2.8219832 0.4078519 79 P 0 0 ;0=69,1=1
P 2.8267717 0.7952756 79 P 0 0 ;0=69,1=1
P 2.8267717 0.976378 79 P 0 0 ;0=69,1=1
P 2.8418425 2.263063 79 P 0 0 ;0=69,1=1
P 2.8428425 1.095063 79 P 0 0 ;0=69,1=1
P 2.8543307 0.4055118 79 P 0 0 ;0=69,1=1
P 2.8608425 3.787063 79 P 0 0 ;0=69,1=1
P 2.8622047 0.7952756 79 P 0 0 ;0=69,1=1
P 2.8718425 2.297063 79 P 0 0 ;0=69,1=1
P 2.8782843 0.2495967 79 P 0 0 ;0=69,1=1
P 2.8818425 2.566063 79 P 0 0 ;0=69,1=1
P 2.8888425 4.221063 79 P 0 0 ;0=69,1=1
P 2.8937008 0.7952756 79 P 0 0 ;0=69,1=1
P 2.8948425 1.561063 79 P 0 0 ;0=69,1=1
P 2.8948425 2.431063 79 P 0 0 ;0=69,1=1
P 2.9018425 1.095063 79 P 0 0 ;0=69,1=1
P 2.9054946 0.2795104 79 P 0 0 ;0=69,1=1
P 2.9198425 1.536063 79 P 0 0 ;0=69,1=1
P 2.9208425 2.428063 79 P 0 0 ;0=69,1=1
P 2.9338425 0.953063 79 P 0 0 ;0=69,1=1
P 2.9370079 0.2795276 79 P 0 0 ;0=69,1=1
P 2.9428425 2.286063 79 P 0 0 ;0=69,1=1
P 2.9488425 2.456063 79 P 0 0 ;0=69,1=1
P 2.9574751 0.2519685 79 P 0 0 ;0=69,1=1
P 2.9588425 2.621063 79 P 0 0 ;0=69,1=1
P 2.980457 0.4091539 79 P 0 0 ;0=69,1=1
P 2.9858425 2.287063 79 P 0 0 ;0=69,1=1
P 2.9933858 3.751063 79 P 0 0 ;0=69,1=1
P 3.0148425 3.831063 79 P 0 0 ;0=69,1=1
P 3.019685 0.4055118 79 P 0 0 ;0=69,1=1
P 3.0568817 1.811803 79 P 0 0 ;0=69,1=1
P 3.0688976 3.3956693 79 P 0 0 ;0=69,1=1
P 3.0974409 0.2519685 79 P 0 0 ;0=69,1=1
P 3.1830708 3.1358268 79 P 0 0 ;0=69,1=1
P 3.1889764 3.1870079 79 P 0 0 ;0=69,1=1
P 3.1972633 1.714063 79 P 0 0 ;0=69,1=1
P 3.1978425 2.970063 79 P 0 0 ;0=69,1=1
P 3.2198425 3.806063 79 P 0 0 ;0=69,1=1
P 3.2248425 1.6613472 79 P 0 0 ;0=69,1=1
P 3.2308425 3.235063 79 P 0 0 ;0=69,1=1
P 3.2398425 3.596063 79 P 0 0 ;0=69,1=1
P 3.2528425 1.661063 79 P 0 0 ;0=69,1=1
P 3.2636972 3.3039177 79 P 0 0 ;0=69,1=1
P 3.2698425 3.788063 79 P 0 0 ;0=69,1=1
P 3.2755905 3.1417323 79 P 0 0 ;0=69,1=1
P 3.277559 2.9635827 79 P 0 0 ;0=69,1=1
P 3.2988425 1.971063 79 P 0 0 ;0=69,1=1
P 3.3028425 3.344063 79 P 0 0 ;0=69,1=1
P 3.3291721 1.826063 79 P 0 0 ;0=69,1=1
P 3.3308425 3.301063 79 P 0 0 ;0=69,1=1
P 3.3428425 2.263063 79 P 0 0 ;0=69,1=1
P 3.3448425 2.996063 79 P 0 0 ;0=69,1=1
P 3.3588425 3.448063 79 P 0 0 ;0=69,1=1
P 3.3688425 3.050063 79 P 0 0 ;0=69,1=1
P 3.3708425 2.888063 79 P 0 0 ;0=69,1=1
P 3.3748425 3.273063 79 P 0 0 ;0=69,1=1
P 3.3798425 1.336063 79 P 0 0 ;0=69,1=1
P 3.3798425 1.386063 79 P 0 0 ;0=69,1=1
P 3.3928425 1.871063 79 P 0 0 ;0=69,1=1
P 3.3948425 3.447063 79 P 0 0 ;0=69,1=1
P 3.3958425 4.222063 79 P 0 0 ;0=69,1=1
P 3.4048425 1.363323 79 P 0 0 ;0=69,1=1
P 3.4068425 1.461063 79 P 0 0 ;0=69,1=1
P 3.4072822 1.411323 79 P 0 0 ;0=69,1=1
P 3.4108425 1.7136509 79 P 0 0 ;0=69,1=1
P 3.4138425 1.573063 79 P 0 0 ;0=69,1=1
P 3.4144661 1.805063 79 P 0 0 ;0=69,1=1
P 3.4248425 3.636063 79 P 0 0 ;0=69,1=1
P 3.4368425 3.457063 79 P 0 0 ;0=69,1=1
P 3.4392507 1.870938 79 P 0 0 ;0=69,1=1
P 3.4698425 3.456063 79 P 0 0 ;0=69,1=1
P 3.4918425 3.103063 79 P 0 0 ;0=69,1=1
P 3.4918425 3.297063 79 P 0 0 ;0=69,1=1
P 3.4988425 2.341063 79 P 0 0 ;0=69,1=1
P 3.5048425 4.086063 79 P 0 0 ;0=69,1=1
P 3.5298425 3.481063 79 P 0 0 ;0=69,1=1
P 3.5318425 3.660063 79 P 0 0 ;0=69,1=1
P 3.5398425 3.806063 79 P 0 0 ;0=69,1=1
P 3.542865 3.3190405 79 P 0 0 ;0=69,1=1
P 3.5498425 1.413063 79 P 0 0 ;0=69,1=1
P 3.5498425 1.441063 79 P 0 0 ;0=69,1=1
P 3.5548425 1.841063 79 P 0 0 ;0=69,1=1
P 3.5548425 1.891063 79 P 0 0 ;0=69,1=1
P 3.5548425 1.941063 79 P 0 0 ;0=69,1=1
P 3.5548425 1.991063 79 P 0 0 ;0=69,1=1
P 3.5718425 2.033063 79 P 0 0 ;0=69,1=1
P 3.5718425 2.058063 79 P 0 0 ;0=69,1=1
P 3.5898425 1.711063 79 P 0 0 ;0=69,1=1
P 3.5908425 1.662063 79 P 0 0 ;0=69,1=1
P 3.5948425 1.514063 79 P 0 0 ;0=69,1=1
P 3.6038425 0.682063 79 P 0 0 ;0=69,1=1
P 3.6228425 3.486063 79 P 0 0 ;0=69,1=1
P 3.6238425 2.587063 79 P 0 0 ;0=69,1=1
P 3.6428425 0.636063 79 P 0 0 ;0=69,1=1
P 3.6538425 3.293063 79 P 0 0 ;0=69,1=1
P 3.6998425 3.751063 79 P 0 0 ;0=69,1=1
P 3.6998425 3.836063 79 P 0 0 ;0=69,1=1
P 3.7178425 3.072063 79 P 0 0 ;0=69,1=1
P 3.7188425 1.713063 79 P 0 0 ;0=69,1=1
P 3.7198425 1.766063 79 P 0 0 ;0=69,1=1
P 3.7198425 1.921063 79 P 0 0 ;0=69,1=1
P 3.7198425 1.996063 79 P 0 0 ;0=69,1=1
P 3.7248425 1.675063 79 P 0 0 ;0=69,1=1
P 3.7328425 1.418063 79 P 0 0 ;0=69,1=1
P 3.7448425 3.261063 79 P 0 0 ;0=69,1=1
P 3.7448425 3.342063 79 P 0 0 ;0=69,1=1
P 3.7738632 1.6661021 79 P 0 0 ;0=69,1=1
P 3.7778425 4.023063 79 P 0 0 ;0=69,1=1
P 3.7998425 3.201063 79 P 0 0 ;0=69,1=1
P 3.8038425 1.691063 79 P 0 0 ;0=69,1=1
P 3.8048425 1.840063 79 P 0 0 ;0=69,1=1
P 3.8068425 3.235063 79 P 0 0 ;0=69,1=1
P 3.8298425 3.176063 79 P 0 0 ;0=69,1=1
P 3.8298425 3.806063 79 P 0 0 ;0=69,1=1
P 3.8308425 3.762063 79 P 0 0 ;0=69,1=1
P 3.8348425 1.481063 79 P 0 0 ;0=69,1=1
P 3.8548425 3.151063 79 P 0 0 ;0=69,1=1
P 3.8648425 1.511063 79 P 0 0 ;0=69,1=1
P 3.8808425 3.109063 79 P 0 0 ;0=69,1=1
P 3.8948425 1.566063 79 P 0 0 ;0=69,1=1
P 3.9248425 1.536063 79 P 0 0 ;0=69,1=1
P 3.9398425 3.121063 79 P 0 0 ;0=69,1=1
P 3.9448425 1.816063 79 P 0 0 ;0=69,1=1
P 3.9608425 2.724063 79 P 0 0 ;0=69,1=1
P 3.9688425 1.671063 79 P 0 0 ;0=69,1=1
P 3.9698425 1.552063 79 P 0 0 ;0=69,1=1
P 3.9948425 1.551063 79 P 0 0 ;0=69,1=1
P 3.9968425 1.711063 79 P 0 0 ;0=69,1=1
P 4.0348425 1.546063 79 P 0 0 ;0=69,1=1
P 4.0398425 2.406063 79 P 0 0 ;0=69,1=1
P 4.0398425 3.784063 79 P 0 0 ;0=69,1=1
P 4.0498425 3.665063 79 P 0 0 ;0=69,1=1
P 4.0648425 1.511063 79 P 0 0 ;0=69,1=1
P 4.0648425 1.796063 79 P 0 0 ;0=69,1=1
P 4.0648425 2.722063 79 P 0 0 ;0=69,1=1
P 4.0688425 3.135063 79 P 0 0 ;0=69,1=1
P 4.0858425 3.892063 79 P 0 0 ;0=69,1=1
P 4.1148425 3.135063 79 P 0 0 ;0=69,1=1
P 4.1203866 3.5941508 79 P 0 0 ;0=69,1=1
P 4.1318425 1.686063 79 P 0 0 ;0=69,1=1
P 4.1348425 1.651063 79 P 0 0 ;0=69,1=1
P 4.1348425 1.751063 79 P 0 0 ;0=69,1=1
P 4.1513063 1.6236232 79 P 0 0 ;0=69,1=1
P 4.1528425 3.135063 79 P 0 0 ;0=69,1=1
P 4.1798425 1.601063 79 P 0 0 ;0=69,1=1
P 4.1948425 3.884063 79 P 0 0 ;0=69,1=1
P 4.2088425 3.135063 79 P 0 0 ;0=69,1=1
P 4.2348425 2.725063 79 P 0 0 ;0=69,1=1
P 4.2548425 3.776063 79 P 0 0 ;0=69,1=1
P 4.2728425 3.135063 79 P 0 0 ;0=69,1=1
P 4.3338425 3.135063 79 P 0 0 ;0=69,1=1
P 4.3398425 2.725063 79 P 0 0 ;0=69,1=1
P 4.3878425 4.206063 79 P 0 0 ;0=69,1=1
P 4.4318425 3.135063 79 P 0 0 ;0=69,1=1
P 4.4778425 3.135063 79 P 0 0 ;0=69,1=1
P 4.5036614 2.7898819 79 P 0 0 ;0=69,1=1
P 4.7547119 4.1159324 79 P 0 0 ;0=69,1=1
P 4.7942913 2.8080709 79 P 0 0 ;0=69,1=1
P 4.9108425 4.203063 79 P 0 0 ;0=69,1=1
P 5.2670079 4.0888976 79 P 0 0 ;0=69,1=1
P 5.2748425 3.511063 79 P 0 0 ;0=69,1=1
P 5.5778425 2.214063 79 P 0 0 ;0=69,1=1
P 5.6348425 2.236063 79 P 0 0 ;0=69,1=1
P 5.6768425 3.546063 79 P 0 0 ;0=69,1=1
P 5.7338425 3.556063 79 P 0 0 ;0=69,1=1
P 5.9948425 3.552063 79 P 0 0 ;0=69,1=1
P 6.0048425 2.434063 79 P 0 0 ;0=69,1=1
P 6.0488425 2.171063 79 P 0 0 ;0=69,1=1
P 6.253937 2.9094488 79 P 0 0 ;0=69,1=1
P 6.2748425 2.391063 79 P 0 0 ;0=69,1=1
P 6.2824161 3.226063 79 P 0 0 ;0=69,1=1
P 6.2848425 2.501063 79 P 0 0 ;0=69,1=1
P 6.2948425 3.701063 79 P 0 0 ;0=69,1=1
P 6.3048425 3.121063 79 P 0 0 ;0=69,1=1
P 6.3094161 3.199063 79 P 0 0 ;0=69,1=1
P 6.3348425 3.266063 79 P 0 0 ;0=69,1=1
P 6.3398425 3.151063 79 P 0 0 ;0=69,1=1
P 6.3547483 3.3311384 79 P 0 0 ;0=69,1=1
P 6.3720472 2.9094488 79 P 0 0 ;0=69,1=1
P 6.3958425 2.111063 79 P 0 0 ;0=69,1=1
P 6.3968425 2.556063 79 P 0 0 ;0=69,1=1
P 6.3978425 2.501063 79 P 0 0 ;0=69,1=1
P 6.3978425 2.610063 79 P 0 0 ;0=69,1=1
P 6.3988425 2.453063 79 P 0 0 ;0=69,1=1
P 6.3988425 2.657063 79 P 0 0 ;0=69,1=1
P 6.4098425 3.371063 79 P 0 0 ;0=69,1=1
P 6.4248425 2.181063 79 P 0 0 ;0=69,1=1
P 6.4398425 3.191063 79 P 0 0 ;0=69,1=1
P 6.4448425 3.291063 79 P 0 0 ;0=69,1=1
P 6.4475772 3.396063 79 P 0 0 ;0=69,1=1
P 6.4568425 3.009063 79 P 0 0 ;0=69,1=1
P 6.4768425 3.231063 79 P 0 0 ;0=69,1=1
P 6.4798425 3.426063 79 P 0 0 ;0=69,1=1
P 6.5098425 3.456063 79 P 0 0 ;0=69,1=1
P 6.5488425 1.531063 79 P 0 0 ;0=69,1=1
P 6.6018425 1.777063 79 P 0 0 ;0=69,1=1
P 6.6028425 1.612063 79 P 0 0 ;0=69,1=1
P 6.6028425 1.672063 79 P 0 0 ;0=69,1=1
P 6.6028425 1.722063 79 P 0 0 ;0=69,1=1
P 6.6078425 2.176063 79 P 0 0 ;0=69,1=1
P 6.6268425 3.032063 79 P 0 0 ;0=69,1=1
P 6.6288425 1.372063 79 P 0 0 ;0=69,1=1
P 6.6476378 3.1299213 79 P 0 0 ;0=69,1=1
P 6.6488425 3.341063 79 P 0 0 ;0=69,1=1
P 6.6858425 1.828063 79 P 0 0 ;0=69,1=1
P 6.6998425 1.881063 79 P 0 0 ;0=69,1=1
P 6.8448425 1.661063 79 P 0 0 ;0=69,1=1
P 6.9498425 2.095063 79 P 0 0 ;0=69,1=1
P 6.9744094 1.9399606 79 P 0 0 ;0=69,1=1

### steps/pcb/layers/top_overlay/features
#Layer_Color=65535
#
#Feature symbol names
#
$0 r3.937
$1 r1
$2 r9.8425
$3 r23.622
$4 r10
$5 r7.874
$6 r15.748
$7 r15.75
$8 r6
$9 r4.7244
$10 r8
$11 r7
$12 r5
$13 r5.91
$14 r7.9921
$15 r9
$16 rect25x10

#
#Feature attribute names
#
@0 .nomenclature
@1 .string
@2 .string_angle

#
#Feature attribute text strings
#
&0 1
&1 2
&2 3
&3 4
&4 IC?
&5 R36
&6 JP2
&7 JP1
&8 R16
&9 R15
&10 R14
&11 R17
&12 U3
&13 U10AL
&14 BT1
&15 C72
&16 C73
&17 C74
&18 C75
&19 C76
&20 C77
&21 C78
&22 C79
&23 C80
&24 C81
&25 C82
&26 C83
&27 C84
&28 C85
&29 C86
&30 C91
&31 C92
&32 R42
&33 R43
&34 U16
&35 J4
&36 R5
&37 X1
&38 U13
&39 U11
&40 U10
&41 U9
&42 U8
&43 U6
&44 U5
&45 U2
&46 U1
&47 SW1
&48 S6
&49 S5
&50 R35
&51 R34
&52 R33
&53 R32
&54 R31
&55 R30
&56 R29
&57 R28
&58 R27
&59 R26
&60 R25
&61 R24
&62 R23
&63 R22
&64 R21
&65 R20
&66 R19
&67 R18
&68 R9
&69 R8
&70 R7
&71 R6
&72 R4
&73 R3
&74 R2
&75 R1
&76 P2
&77 P1
&78 L2
&79 L1
&80 J3
&81 J2
&82 J1
&83 FB3
&84 FB2
&85 F1
&86 D18
&87 D17
&88 D16
&89 D15
&90 D14
&91 D13
&92 D12
&93 D11
&94 D10
&95 D9
&96 D8
&97 D7
&98 D6
&99 D5
&100 D4
&101 D3
&102 D2
&103 D1
&104 C67
&105 C66
&106 C65
&107 C63
&108 C62
&109 C61
&110 C60
&111 C59
&112 C58
&113 C57
&114 C56
&115 C55
&116 C54
&117 C22
&118 C21
&119 C20
&120 C19
&121 C18
&122 C17
&123 C16
&124 C15
&125 C14
&126 C13
&127 C12
&128 C11
&129 C10
&130 C9
&131 C8
&132 C7
&133 C6
&134 C5
&135 C4
&136 C3
&137 C2
&138 C1
&139 AN8
&140 AN7
&141 AN6
&142 AN5
&143 AN4
&144 AN3
&145 AN2
&146 AN1

#
#Layer features
#
A 0.2105315 2.8299213 0.2105315 2.8299213 0.1495079 2.8299213 4 P 0 N
A 0.2105315 3.8535433 0.2105315 3.8535433 0.1495079 3.8535433 4 P 0 N
A 0.6182677 4.1758662 0.6182677 4.1758662 0.6162992 4.1758662 0 P 0 N
A 0.8199343 4.1758662 0.8199343 4.1758662 0.8179658 4.1758662 0 P 0 N
A 1.0216009 4.1758662 1.0216009 4.1758662 1.0196324 4.1758662 0 P 0 N
A 1.2170866 0.8224016 1.2170866 0.8224016 1.2121653 0.8224016 2 P 0 N
A 1.2170866 1.3474016 1.2170866 1.3474016 1.2121653 1.3474016 2 P 0 N
A 1.2170866 1.8724016 1.2170866 1.8724016 1.2121653 1.8724016 2 P 0 N
A 1.2170866 2.3974016 1.2170866 2.3974016 1.2121653 2.3974016 2 P 0 N
A 1.2232675 4.1758662 1.2232675 4.1758662 1.221299 4.1758662 0 P 0 N
A 1.6364803 4.2300748 1.6364803 4.2300748 1.631559 4.2300748 2 P 0 N
A 1.7270314 4.1711181 1.7270314 4.1711181 1.7152204 4.1711181 3 P 0 N
A 1.7712204 0.4310709 1.6275196 0.4310709 1.69937 0.4310709 0 P 0 N
A 1.8427125 1.318673 1.8427125 1.318673 1.8348325 1.318673 7 P 0 N
A 2.2198525 2.300533 2.2198525 2.300533 2.2119725 2.300533 7 P 0 N
A 2.5924212 2.8299213 2.5924212 2.8299213 2.5313976 2.8299213 4 P 0 N
A 2.5924212 3.8535433 2.5924212 3.8535433 2.5313976 3.8535433 4 P 0 N
A 2.7618111 3.3206693 2.7618111 3.3206693 2.7568898 3.3206693 2 P 0 N
A 2.7818505 3.7503543 2.7818505 3.7503543 2.7769292 3.7503543 2 P 0 N
A 2.863189 3.2795275 2.863189 3.2795275 2.851378 3.2795275 3 P 0 N
A 2.8698425 3.8611023 2.8698425 3.8611023 2.8448425 3.8611023 5 P 0 N
A 2.8968505 3.7503543 2.8968505 3.7503543 2.8919292 3.7503543 2 P 0 N
A 2.9895825 1.096593 2.9895825 1.096593 2.9817025 1.096593 7 P 0 N
A 3.2470472 2.8661417 3.2509842 2.8661417 3.2490157 2.8661417 0 P 0 N
A 3.2509842 2.8661417 3.2470472 2.8661417 3.2490157 2.8661417 0 P 0 N
A 3.3068505 3.7503543 3.3068505 3.7503543 3.3019292 3.7503543 2 P 0 N
A 3.4416225 2.088353 3.4416225 2.088353 3.4337425 2.088353 7 P 0 N
A 3.5318505 3.7503543 3.5318505 3.7503543 3.5269292 3.7503543 2 P 0 N
A 3.5632677 3.7058662 3.5632677 3.7058662 3.5612992 3.7058662 0 P 0 N
A 3.6203543 3.9312598 3.6203543 3.9312598 3.6183858 3.9312598 0 P 0 N
A 3.7774803 3.8890748 3.7774803 3.8890748 3.772559 3.8890748 2 P 0 N
A 3.8680314 3.8301181 3.8680314 3.8301181 3.8562204 3.8301181 3 P 0 N
A 4.1298072 1.5996232 4.1298072 1.5996232 4.1248072 1.5996232 4 P 0 N
A 4.2559055 3.6318898 4.2559055 3.6318898 4.253937 3.6318898 0 P 0 N
A 4.3326772 0.8338582 4.3326772 0.8338582 4.3277559 0.8338582 2 P 0 N
A 5.8811023 3.7335433 5.8811023 3.7335433 5.8791338 3.7335433 0 P 0 N
A 6.1277165 3.7411023 6.1277165 3.7411023 6.1198425 3.7411023 6 P 0 N
A 6.1911023 3.7335433 6.1911023 3.7335433 6.1891338 3.7335433 0 P 0 N
A 6.1961023 3.5985433 6.1961023 3.5985433 6.1941338 3.5985433 0 P 0 N
A 6.6798425 3.131063 6.6798425 3.131063 6.6748425 3.131063 4 P 0 N
L -0.0001175 0.177913 0.5908825 0.177913 1 P 0
L -0.0004331 0.1781182 0.5901181 0.1781182 0 P 0
L 0.0180118 2.7167323 0.0180118 3.9667323 4 P 0
L 0.0180118 2.7167323 2.6628937 2.7167323 4 P 0
L 0.0180118 3.9667323 2.6628937 3.9667323 4 P 0
L 0.0298425 0.766063 0.0698425 0.726063 11 P 0
L 0.0298425 1.046063 0.0698425 1.086063 11 P 0
L 0.0298425 1.291063 0.0698425 1.251063 11 P 0
L 0.0298425 1.571063 0.0698425 1.611063 11 P 0
L 0.0298425 1.816063 0.0698425 1.776063 11 P 0
L 0.0298425 2.096063 0.0698425 2.136063 11 P 0
L 0.0298425 2.341063 0.0698425 2.301063 11 P 0
L 0.0298425 2.621063 0.0698425 2.661063 11 P 0
L 0.0698425 0.726063 0.0998425 0.726063 11 P 0
L 0.0698425 1.086063 0.0998425 1.086063 11 P 0
L 0.0698425 1.251063 0.0998425 1.251063 11 P 0
L 0.0698425 1.611063 0.0998425 1.611063 11 P 0
L 0.0698425 1.776063 0.0998425 1.776063 11 P 0
L 0.0698425 2.136063 0.0998425 2.136063 11 P 0
L 0.0698425 2.301063 0.0998425 2.301063 11 P 0
L 0.0698425 2.661063 0.0998425 2.661063 11 P 0
L 0.0998425 0.726063 0.3798425 0.726063 11 P 0
L 0.0998425 1.086063 0.3798425 1.086063 11 P 0
L 0.0998425 1.251063 0.3798425 1.251063 11 P 0
L 0.0998425 1.611063 0.3798425 1.611063 11 P 0
L 0.0998425 1.776063 0.3798425 1.776063 11 P 0
L 0.0998425 2.136063 0.3798425 2.136063 11 P 0
L 0.0998425 2.301063 0.3798425 2.301063 11 P 0
L 0.0998425 2.661063 0.3798425 2.661063 11 P 0
L 0.3798425 0.726063 0.3798425 0.806063 11 P 0
L 0.3798425 1.006063 0.3798425 1.086063 11 P 0
L 0.3798425 1.251063 0.3798425 1.331063 11 P 0
L 0.3798425 1.531063 0.3798425 1.611063 11 P 0
L 0.3798425 1.776063 0.3798425 1.856063 11 P 0
L 0.3798425 2.056063 0.3798425 2.136063 11 P 0
L 0.3798425 2.301063 0.3798425 2.381063 11 P 0
L 0.3798425 2.581063 0.3798425 2.661063 11 P 0
L 0.4048619 0.7285703 0.4048619 0.7485638 15 P 0 ;0,1=143,2=0.000000
L 0.4048619 0.7485638 0.4148587 0.7585606 15 P 0 ;0,1=143,2=0.000000
L 0.4048619 1.7755703 0.4048619 1.7955638 15 P 0 ;0,1=145,2=0.000000
L 0.4048619 1.7955638 0.4148587 1.8055606 15 P 0 ;0,1=145,2=0.000000
L 0.4063594 2.3015703 0.4063594 2.3215638 15 P 0 ;0,1=146,2=0.000000
L 0.4063594 2.3215638 0.4163562 2.3315606 15 P 0 ;0,1=146,2=0.000000
L 0.4068619 1.2525703 0.4068619 1.2725638 15 P 0 ;0,1=144,2=0.000000
L 0.4068619 1.2725638 0.4168587 1.2825606 15 P 0 ;0,1=144,2=0.000000
L 0.4148587 0.7585606 0.4248554 0.7485638 15 P 0 ;0,1=143,2=0.000000
L 0.4148587 1.8055606 0.4248554 1.7955638 15 P 0 ;0,1=145,2=0.000000
L 0.4163562 2.3315606 0.4263529 2.3215638 15 P 0 ;0,1=146,2=0.000000
L 0.4168587 1.2825606 0.4268554 1.2725638 15 P 0 ;0,1=144,2=0.000000
L 0.4248554 0.7285703 0.4248554 0.7435655 15 P 0 ;0,1=143,2=0.000000
L 0.4248554 0.7435655 0.4048619 0.7435655 15 P 0 ;0,1=143,2=0.000000
L 0.4248554 0.7485638 0.4248554 0.7285703 15 P 0 ;0,1=143,2=0.000000
L 0.4248554 1.7755703 0.4248554 1.7905655 15 P 0 ;0,1=145,2=0.000000
L 0.4248554 1.7905655 0.4048619 1.7905655 15 P 0 ;0,1=145,2=0.000000
L 0.4248554 1.7955638 0.4248554 1.7755703 15 P 0 ;0,1=145,2=0.000000
L 0.4263529 2.3015703 0.4263529 2.3165655 15 P 0 ;0,1=146,2=0.000000
L 0.4263529 2.3165655 0.4063594 2.3165655 15 P 0 ;0,1=146,2=0.000000
L 0.4263529 2.3215638 0.4263529 2.3015703 15 P 0 ;0,1=146,2=0.000000
L 0.4268554 1.2525703 0.4268554 1.2675655 15 P 0 ;0,1=144,2=0.000000
L 0.4268554 1.2675655 0.4068619 1.2675655 15 P 0 ;0,1=144,2=0.000000
L 0.4268554 1.2725638 0.4268554 1.2525703 15 P 0 ;0,1=144,2=0.000000
L 0.4348522 0.7285703 0.4348522 0.7585606 15 P 0 ;0,1=143,2=0.000000
L 0.4348522 0.7585606 0.4548457 0.7285703 15 P 0 ;0,1=143,2=0.000000
L 0.4348522 1.7755703 0.4348522 1.8055606 15 P 0 ;0,1=145,2=0.000000
L 0.4348522 1.8055606 0.4548457 1.7755703 15 P 0 ;0,1=145,2=0.000000
L 0.4363497 2.3015703 0.4363497 2.3315606 15 P 0 ;0,1=146,2=0.000000
L 0.4363497 2.3315606 0.4563432 2.3015703 15 P 0 ;0,1=146,2=0.000000
L 0.4368522 1.2525703 0.4368522 1.2825606 15 P 0 ;0,1=144,2=0.000000
L 0.4368522 1.2825606 0.4568457 1.2525703 15 P 0 ;0,1=144,2=0.000000
L 0.4548457 0.7285703 0.4548457 0.7585606 15 P 0 ;0,1=143,2=0.000000
L 0.4548457 1.7755703 0.4548457 1.8055606 15 P 0 ;0,1=145,2=0.000000
L 0.4563432 2.3015703 0.4563432 2.3315606 15 P 0 ;0,1=146,2=0.000000
L 0.4568457 1.2525703 0.4568457 1.2825606 15 P 0 ;0,1=144,2=0.000000
L 0.4648425 0.7435655 0.484836 0.7435655 15 P 0 ;0,1=143,2=0.000000
L 0.4648425 1.7755703 0.484836 1.7955638 15 P 0 ;0,1=145,2=0.000000
L 0.46634 2.3015703 0.4763368 2.3015703 15 P 0 ;0,1=146,2=0.000000
L 0.4668425 1.2775622 0.4718409 1.2825606 15 P 0 ;0,1=144,2=0.000000
L 0.4698409 1.8055606 0.4648425 1.8005622 15 P 0 ;0,1=145,2=0.000000
L 0.4713384 2.3015703 0.4713384 2.3315606 15 P 0 ;0,1=146,2=0.000000
L 0.4713384 2.3315606 0.46634 2.3265622 15 P 0 ;0,1=146,2=0.000000
L 0.4718409 1.2525703 0.4668425 1.2575687 15 P 0 ;0,1=144,2=0.000000
L 0.4718409 1.2825606 0.4818377 1.2825606 15 P 0 ;0,1=144,2=0.000000
L 0.4763368 2.3015703 0.4713384 2.3015703 15 P 0 ;0,1=146,2=0.000000
L 0.4768393 1.2675655 0.4818377 1.2675655 15 P 0 ;0,1=144,2=0.000000
L 0.4798377 0.7285703 0.4798377 0.7585606 15 P 0 ;0,1=143,2=0.000000
L 0.4798377 0.7585606 0.4648425 0.7435655 15 P 0 ;0,1=143,2=0.000000
L 0.4798377 1.8055606 0.4698409 1.8055606 15 P 0 ;0,1=145,2=0.000000
L 0.4818377 1.2525703 0.4718409 1.2525703 15 P 0 ;0,1=144,2=0.000000
L 0.4818377 1.2675655 0.4768393 1.2675655 15 P 0 ;0,1=144,2=0.000000
L 0.4818377 1.2675655 0.486836 1.2625671 15 P 0 ;0,1=144,2=0.000000
L 0.4818377 1.2825606 0.486836 1.2775622 15 P 0 ;0,1=144,2=0.000000
L 0.484836 1.7755703 0.4648425 1.7755703 15 P 0 ;0,1=145,2=0.000000
L 0.484836 1.7955638 0.484836 1.8005622 15 P 0 ;0,1=145,2=0.000000
L 0.484836 1.8005622 0.4798377 1.8055606 15 P 0 ;0,1=145,2=0.000000
L 0.486836 1.2575687 0.4818377 1.2525703 15 P 0 ;0,1=144,2=0.000000
L 0.486836 1.2625671 0.486836 1.2575687 15 P 0 ;0,1=144,2=0.000000
L 0.486836 1.2725638 0.4818377 1.2675655 15 P 0 ;0,1=144,2=0.000000
L 0.486836 1.2775622 0.486836 1.2725638 15 P 0 ;0,1=144,2=0.000000
L 0.5368425 1.062063 0.5368425 1.0820565 15 P 0 ;0,1=139,2=0.000000
L 0.5368425 1.0820565 0.5468393 1.0920533 15 P 0 ;0,1=139,2=0.000000
L 0.5368425 1.587063 0.5368425 1.6070565 15 P 0 ;0,1=140,2=0.000000
L 0.5368425 1.6070565 0.5468393 1.6170533 15 P 0 ;0,1=140,2=0.000000
L 0.5368425 2.112063 0.5368425 2.1320565 15 P 0 ;0,1=142,2=0.000000
L 0.5368425 2.1320565 0.5468393 2.1420533 15 P 0 ;0,1=142,2=0.000000
L 0.5368425 2.637063 0.5368425 2.6570565 15 P 0 ;0,1=141,2=0.000000
L 0.5368425 2.6570565 0.5468393 2.6670533 15 P 0 ;0,1=141,2=0.000000
L 0.5468393 1.0920533 0.556836 1.0820565 15 P 0 ;0,1=139,2=0.000000
L 0.5468393 1.6170533 0.556836 1.6070565 15 P 0 ;0,1=140,2=0.000000
L 0.5468393 2.1420533 0.556836 2.1320565 15 P 0 ;0,1=142,2=0.000000
L 0.5468393 2.6670533 0.556836 2.6570565 15 P 0 ;0,1=141,2=0.000000
L 0.556836 1.062063 0.556836 1.0770582 15 P 0 ;0,1=139,2=0.000000
L 0.556836 1.0770582 0.5368425 1.0770582 15 P 0 ;0,1=139,2=0.000000
L 0.556836 1.0820565 0.556836 1.062063 15 P 0 ;0,1=139,2=0.000000
L 0.556836 1.587063 0.556836 1.6020582 15 P 0 ;0,1=140,2=0.000000
L 0.556836 1.6020582 0.5368425 1.6020582 15 P 0 ;0,1=140,2=0.000000
L 0.556836 1.6070565 0.556836 1.587063 15 P 0 ;0,1=140,2=0.000000
L 0.556836 2.112063 0.556836 2.1270582 15 P 0 ;0,1=142,2=0.000000
L 0.556836 2.1270582 0.5368425 2.1270582 15 P 0 ;0,1=142,2=0.000000
L 0.556836 2.1320565 0.556836 2.112063 15 P 0 ;0,1=142,2=0.000000
L 0.556836 2.637063 0.556836 2.6520582 15 P 0 ;0,1=141,2=0.000000
L 0.556836 2.6520582 0.5368425 2.6520582 15 P 0 ;0,1=141,2=0.000000
L 0.556836 2.6570565 0.556836 2.637063 15 P 0 ;0,1=141,2=0.000000
L 0.5583449 3.9980824 0.5583449 4.0130776 15 P 0 ;0,1=57,2=90.000000
L 0.5583449 4.0130776 0.5633433 4.0180759 15 P 0 ;0,1=57,2=90.000000
L 0.5583449 4.0330711 0.5633433 4.0280727 15 P 0 ;0,1=57,2=90.000000
L 0.5583449 4.0430679 0.5583449 4.0330711 15 P 0 ;0,1=57,2=90.000000
L 0.5583449 4.0630614 0.5583449 4.0730582 15 P 0 ;0,1=57,2=90.000000
L 0.5583449 4.0730582 0.5633433 4.0780565 15 P 0 ;0,1=57,2=90.000000
L 0.5613449 4.1783287 0.5913352 4.1783287 15 P 0 ;0,1=93,2=90.000000
L 0.5613449 4.1933239 0.5613449 4.1783287 15 P 0 ;0,1=93,2=90.000000
L 0.5613449 4.2133174 0.5663433 4.208319 15 P 0 ;0,1=93,2=90.000000
L 0.5613449 4.2383093 0.5663433 4.2333109 15 P 0 ;0,1=93,2=90.000000
L 0.5633433 4.0180759 0.57334 4.0180759 15 P 0 ;0,1=57,2=90.000000
L 0.5633433 4.0480662 0.5583449 4.0430679 15 P 0 ;0,1=57,2=90.000000
L 0.5633433 4.058063 0.5583449 4.0630614 15 P 0 ;0,1=57,2=90.000000
L 0.5633433 4.0780565 0.5683417 4.0780565 15 P 0 ;0,1=57,2=90.000000
L 0.5663433 4.1983222 0.5613449 4.1933239 15 P 0 ;0,1=93,2=90.000000
L 0.5668328 1.062063 0.5668328 1.0920533 15 P 0 ;0,1=139,2=0.000000
L 0.5668328 1.0920533 0.5868263 1.062063 15 P 0 ;0,1=139,2=0.000000
L 0.5668328 1.587063 0.5668328 1.6170533 15 P 0 ;0,1=140,2=0.000000
L 0.5668328 1.6170533 0.5868263 1.587063 15 P 0 ;0,1=140,2=0.000000
L 0.5668328 2.112063 0.5668328 2.1420533 15 P 0 ;0,1=142,2=0.000000
L 0.5668328 2.1420533 0.5868263 2.112063 15 P 0 ;0,1=142,2=0.000000
L 0.5668328 2.637063 0.5668328 2.6670533 15 P 0 ;0,1=141,2=0.000000
L 0.5668328 2.6670533 0.5868263 2.637063 15 P 0 ;0,1=141,2=0.000000
L 0.5683417 4.0480662 0.5633433 4.0480662 15 P 0 ;0,1=57,2=90.000000
L 0.5683417 4.058063 0.5633433 4.058063 15 P 0 ;0,1=57,2=90.000000
L 0.5683417 4.0780565 0.57334 4.0730582 15 P 0 ;0,1=57,2=90.000000
L 0.57334 4.0180759 0.5783384 4.0130776 15 P 0 ;0,1=57,2=90.000000
L 0.57334 4.0630614 0.5683417 4.058063 15 P 0 ;0,1=57,2=90.000000
L 0.57334 4.0630614 0.57334 4.0730582 15 P 0 ;0,1=57,2=90.000000
L 0.57334 4.0730582 0.5783384 4.0780565 15 P 0 ;0,1=57,2=90.000000
L 0.5783384 4.0080792 0.5883352 4.0180759 15 P 0 ;0,1=57,2=90.000000
L 0.5783384 4.0130776 0.5783384 3.9980824 15 P 0 ;0,1=57,2=90.000000
L 0.5783384 4.058063 0.57334 4.0630614 15 P 0 ;0,1=57,2=90.000000
L 0.5783384 4.0780565 0.5833368 4.0780565 15 P 0 ;0,1=57,2=90.000000
L 0.5833368 4.058063 0.5783384 4.058063 15 P 0 ;0,1=57,2=90.000000
L 0.5833368 4.0780565 0.5883352 4.0730582 15 P 0 ;0,1=57,2=90.000000
L 0.5863368 4.1983222 0.5663433 4.1983222 15 P 0 ;0,1=93,2=90.000000
L 0.5868263 1.062063 0.5868263 1.0920533 15 P 0 ;0,1=139,2=0.000000
L 0.5868263 1.587063 0.5868263 1.6170533 15 P 0 ;0,1=140,2=0.000000
L 0.5868263 2.112063 0.5868263 2.1420533 15 P 0 ;0,1=142,2=0.000000
L 0.5868263 2.637063 0.5868263 2.6670533 15 P 0 ;0,1=141,2=0.000000
L 0.5883352 3.9980824 0.5583449 3.9980824 15 P 0 ;0,1=57,2=90.000000
L 0.5883352 4.0280727 0.5683417 4.0480662 15 P 0 ;0,1=57,2=90.000000
L 0.5883352 4.0480662 0.5883352 4.0280727 15 P 0 ;0,1=57,2=90.000000
L 0.5883352 4.0630614 0.5833368 4.058063 15 P 0 ;0,1=57,2=90.000000
L 0.5883352 4.0730582 0.5883352 4.0630614 15 P 0 ;0,1=57,2=90.000000
L 0.5901181 0.1781182 0.5901181 0.5029213 0 P 0
L 0.5901181 0.5029213 1.312559 0.5029213 0 P 0
L 0.5908825 0.177913 0.5908825 0.502913 1 P 0
L 0.5913352 4.1783287 0.5913352 4.1933239 15 P 0 ;0,1=93,2=90.000000
L 0.5913352 4.1933239 0.5863368 4.1983222 15 P 0 ;0,1=93,2=90.000000
L 0.5913352 4.208319 0.5913352 4.2183158 15 P 0 ;0,1=93,2=90.000000
L 0.5913352 4.2133174 0.5613449 4.2133174 15 P 0 ;0,1=93,2=90.000000
L 0.5913352 4.2183158 0.5913352 4.2133174 15 P 0 ;0,1=93,2=90.000000
L 0.5913352 4.2333109 0.5913352 4.2433077 15 P 0 ;0,1=93,2=90.000000
L 0.5913352 4.2383093 0.5613449 4.2383093 15 P 0 ;0,1=93,2=90.000000
L 0.5913352 4.2433077 0.5913352 4.2383093 15 P 0 ;0,1=93,2=90.000000
L 0.5968231 1.0670614 0.5968231 1.0720598 15 P 0 ;0,1=139,2=0.000000
L 0.5968231 1.0720598 0.6018215 1.0770582 15 P 0 ;0,1=139,2=0.000000
L 0.5968231 1.0820565 0.5968231 1.0870549 15 P 0 ;0,1=139,2=0.000000
L 0.5968231 1.0870549 0.6018215 1.0920533 15 P 0 ;0,1=139,2=0.000000
L 0.5968231 1.5920614 0.5968231 1.587063 15 P 0 ;0,1=140,2=0.000000
L 0.5968231 1.6170533 0.6168166 1.6170533 15 P 0 ;0,1=140,2=0.000000
L 0.5968231 2.1270582 0.6068199 2.1320565 15 P 0 ;0,1=142,2=0.000000
L 0.5968231 2.1420533 0.5968231 2.1270582 15 P 0 ;0,1=142,2=0.000000
L 0.5968231 2.6420614 0.6018215 2.637063 15 P 0 ;0,1=141,2=0.000000
L 0.5968231 2.6520582 0.5968231 2.6420614 15 P 0 ;0,1=141,2=0.000000
L 0.6018215 1.062063 0.5968231 1.0670614 15 P 0 ;0,1=139,2=0.000000
L 0.6018215 1.0770582 0.5968231 1.0820565 15 P 0 ;0,1=139,2=0.000000
L 0.6018215 1.0770582 0.6118183 1.0770582 15 P 0 ;0,1=139,2=0.000000
L 0.6018215 1.0920533 0.6118183 1.0920533 15 P 0 ;0,1=139,2=0.000000
L 0.6018215 2.112063 0.5968231 2.1170614 15 P 0 ;0,1=142,2=0.000000
L 0.6018215 2.637063 0.6118183 2.637063 15 P 0 ;0,1=141,2=0.000000
L 0.6068199 2.1320565 0.6118183 2.1320565 15 P 0 ;0,1=142,2=0.000000
L 0.6068199 2.6620549 0.5968231 2.6520582 15 P 0 ;0,1=141,2=0.000000
L 0.6118183 1.062063 0.6018215 1.062063 15 P 0 ;0,1=139,2=0.000000
L 0.6118183 1.0770582 0.6168166 1.0720598 15 P 0 ;0,1=139,2=0.000000
L 0.6118183 1.0920533 0.6168166 1.0870549 15 P 0 ;0,1=139,2=0.000000
L 0.6118183 2.112063 0.6018215 2.112063 15 P 0 ;0,1=142,2=0.000000
L 0.6118183 2.1320565 0.6168166 2.1270582 15 P 0 ;0,1=142,2=0.000000
L 0.6118183 2.637063 0.6168166 2.6420614 15 P 0 ;0,1=141,2=0.000000
L 0.6118183 2.6520582 0.5968231 2.6520582 15 P 0 ;0,1=141,2=0.000000
L 0.6168166 1.0670614 0.6118183 1.062063 15 P 0 ;0,1=139,2=0.000000
L 0.6168166 1.0720598 0.6168166 1.0670614 15 P 0 ;0,1=139,2=0.000000
L 0.6168166 1.0820565 0.6118183 1.0770582 15 P 0 ;0,1=139,2=0.000000
L 0.6168166 1.0870549 0.6168166 1.0820565 15 P 0 ;0,1=139,2=0.000000
L 0.6168166 1.6120549 0.5968231 1.5920614 15 P 0 ;0,1=140,2=0.000000
L 0.6168166 1.6170533 0.6168166 1.6120549 15 P 0 ;0,1=140,2=0.000000
L 0.6168166 2.1170614 0.6118183 2.112063 15 P 0 ;0,1=142,2=0.000000
L 0.6168166 2.1270582 0.6168166 2.1170614 15 P 0 ;0,1=142,2=0.000000
L 0.6168166 2.1420533 0.5968231 2.1420533 15 P 0 ;0,1=142,2=0.000000
L 0.6168166 2.6420614 0.6168166 2.6470598 15 P 0 ;0,1=141,2=0.000000
L 0.6168166 2.6470598 0.6118183 2.6520582 15 P 0 ;0,1=141,2=0.000000
L 0.6168166 2.6670533 0.6068199 2.6620549 15 P 0 ;0,1=141,2=0.000000
L 0.6192835 4.066063 0.6586535 4.066063 8 P 0
L 0.7593449 3.9980824 0.7593449 4.0130776 15 P 0 ;0,1=56,2=90.000000
L 0.7593449 4.0130776 0.7643433 4.0180759 15 P 0 ;0,1=56,2=90.000000
L 0.7593449 4.0330711 0.7643433 4.0280727 15 P 0 ;0,1=56,2=90.000000
L 0.7593449 4.0430679 0.7593449 4.0330711 15 P 0 ;0,1=56,2=90.000000
L 0.7593449 4.0630614 0.7643433 4.058063 15 P 0 ;0,1=56,2=90.000000
L 0.7593449 4.0730582 0.7593449 4.0630614 15 P 0 ;0,1=56,2=90.000000
L 0.7643433 4.0180759 0.77434 4.0180759 15 P 0 ;0,1=56,2=90.000000
L 0.7643433 4.0480662 0.7593449 4.0430679 15 P 0 ;0,1=56,2=90.000000
L 0.7643433 4.058063 0.7693417 4.058063 15 P 0 ;0,1=56,2=90.000000
L 0.7643433 4.0780565 0.7593449 4.0730582 15 P 0 ;0,1=56,2=90.000000
L 0.7643449 4.1688312 0.7943352 4.1688312 15 P 0 ;0,1=92,2=90.000000
L 0.7643449 4.1838264 0.7643449 4.1688312 15 P 0 ;0,1=92,2=90.000000
L 0.7643449 4.2038199 0.7693433 4.1988215 15 P 0 ;0,1=92,2=90.000000
L 0.7643449 4.2288118 0.7693433 4.2238134 15 P 0 ;0,1=92,2=90.000000
L 0.7643449 4.2388086 0.7643449 4.2288118 15 P 0 ;0,1=92,2=90.000000
L 0.7693417 4.0480662 0.7643433 4.0480662 15 P 0 ;0,1=56,2=90.000000
L 0.7693417 4.058063 0.77434 4.0630614 15 P 0 ;0,1=56,2=90.000000
L 0.7693433 4.1888247 0.7643449 4.1838264 15 P 0 ;0,1=92,2=90.000000
L 0.7693433 4.2438069 0.7643449 4.2388086 15 P 0 ;0,1=92,2=90.000000
L 0.77434 4.0180759 0.7793384 4.0130776 15 P 0 ;0,1=56,2=90.000000
L 0.77434 4.0630614 0.77434 4.0780565 15 P 0 ;0,1=56,2=90.000000
L 0.7743417 4.2438069 0.7693433 4.2438069 15 P 0 ;0,1=92,2=90.000000
L 0.7793384 4.0080792 0.7893352 4.0180759 15 P 0 ;0,1=56,2=90.000000
L 0.7793384 4.0130776 0.7793384 3.9980824 15 P 0 ;0,1=56,2=90.000000
L 0.7843368 4.058063 0.7893352 4.0630614 15 P 0 ;0,1=56,2=90.000000
L 0.7843368 4.0780565 0.7643433 4.0780565 15 P 0 ;0,1=56,2=90.000000
L 0.7893352 3.9980824 0.7593449 3.9980824 15 P 0 ;0,1=56,2=90.000000
L 0.7893352 4.0280727 0.7693417 4.0480662 15 P 0 ;0,1=56,2=90.000000
L 0.7893352 4.0480662 0.7893352 4.0280727 15 P 0 ;0,1=56,2=90.000000
L 0.7893352 4.0630614 0.7893352 4.0730582 15 P 0 ;0,1=56,2=90.000000
L 0.7893352 4.0730582 0.7843368 4.0780565 15 P 0 ;0,1=56,2=90.000000
L 0.7893368 4.1888247 0.7693433 4.1888247 15 P 0 ;0,1=92,2=90.000000
L 0.7943352 4.1688312 0.7943352 4.1838264 15 P 0 ;0,1=92,2=90.000000
L 0.7943352 4.1838264 0.7893368 4.1888247 15 P 0 ;0,1=92,2=90.000000
L 0.7943352 4.1988215 0.7943352 4.2088183 15 P 0 ;0,1=92,2=90.000000
L 0.7943352 4.2038199 0.7643449 4.2038199 15 P 0 ;0,1=92,2=90.000000
L 0.7943352 4.2088183 0.7943352 4.2038199 15 P 0 ;0,1=92,2=90.000000
L 0.7943352 4.2238134 0.7743417 4.2438069 15 P 0 ;0,1=92,2=90.000000
L 0.7943352 4.2438069 0.7943352 4.2238134 15 P 0 ;0,1=92,2=90.000000
L 0.8209501 4.066063 0.8603201 4.066063 8 P 0
L 0.8818425 1.071063 0.8968377 1.071063 15 P 0 ;0,1=86,2=0.000000
L 0.8818425 1.1010533 0.8818425 1.071063 15 P 0 ;0,1=86,2=0.000000
L 0.8818425 1.596063 0.8968377 1.596063 15 P 0 ;0,1=87,2=0.000000
L 0.8818425 1.6260533 0.8818425 1.596063 15 P 0 ;0,1=87,2=0.000000
L 0.8818425 2.121063 0.8968377 2.121063 15 P 0 ;0,1=89,2=0.000000
L 0.8818425 2.1510533 0.8818425 2.121063 15 P 0 ;0,1=89,2=0.000000
L 0.8818425 2.646063 0.8968377 2.646063 15 P 0 ;0,1=88,2=0.000000
L 0.8818425 2.6760533 0.8818425 2.646063 15 P 0 ;0,1=88,2=0.000000
L 0.8918425 0.772063 0.8918425 0.8020533 4 P 0 ;0,1=5,2=0.000000
L 0.8918425 0.8020533 0.9068377 0.8020533 4 P 0 ;0,1=5,2=0.000000
L 0.8968377 1.071063 0.901836 1.0760614 15 P 0 ;0,1=86,2=0.000000
L 0.8968377 1.1010533 0.8818425 1.1010533 15 P 0 ;0,1=86,2=0.000000
L 0.8968377 1.596063 0.901836 1.6010614 15 P 0 ;0,1=87,2=0.000000
L 0.8968377 1.6260533 0.8818425 1.6260533 15 P 0 ;0,1=87,2=0.000000
L 0.8968377 2.121063 0.901836 2.1260614 15 P 0 ;0,1=89,2=0.000000
L 0.8968377 2.1510533 0.8818425 2.1510533 15 P 0 ;0,1=89,2=0.000000
L 0.8968377 2.646063 0.901836 2.6510614 15 P 0 ;0,1=88,2=0.000000
L 0.8968377 2.6760533 0.8818425 2.6760533 15 P 0 ;0,1=88,2=0.000000
L 0.901836 1.0760614 0.901836 1.0960549 15 P 0 ;0,1=86,2=0.000000
L 0.901836 1.0960549 0.8968377 1.1010533 15 P 0 ;0,1=86,2=0.000000
L 0.901836 1.6010614 0.901836 1.6210549 15 P 0 ;0,1=87,2=0.000000
L 0.901836 1.6210549 0.8968377 1.6260533 15 P 0 ;0,1=87,2=0.000000
L 0.901836 2.1260614 0.901836 2.1460549 15 P 0 ;0,1=89,2=0.000000
L 0.901836 2.1460549 0.8968377 2.1510533 15 P 0 ;0,1=89,2=0.000000
L 0.901836 2.6510614 0.901836 2.6710549 15 P 0 ;0,1=88,2=0.000000
L 0.901836 2.6710549 0.8968377 2.6760533 15 P 0 ;0,1=88,2=0.000000
L 0.9018393 0.7820598 0.911836 0.772063 4 P 0 ;0,1=5,2=0.000000
L 0.9031102 0.7820472 0.9031102 0.8283071 5 P 0
L 0.9031102 0.7820472 1.1865748 0.7820472 5 P 0
L 0.9031102 0.9838189 0.9031102 1.0300787 5 P 0
L 0.9031102 1.0300787 1.1865748 1.0300787 5 P 0
L 0.9031102 1.3070472 0.9031102 1.3533071 5 P 0
L 0.9031102 1.3070472 1.1865748 1.3070472 5 P 0
L 0.9031102 1.5088189 0.9031102 1.5550787 5 P 0
L 0.9031102 1.5550787 1.1865748 1.5550787 5 P 0
L 0.9031102 1.8320472 0.9031102 1.8783071 5 P 0
L 0.9031102 1.8320472 1.1865748 1.8320472 5 P 0
L 0.9031102 2.0338189 0.9031102 2.0800787 5 P 0
L 0.9031102 2.0800787 1.1865748 2.0800787 5 P 0
L 0.9031102 2.3570472 0.9031102 2.4033071 5 P 0
L 0.9031102 2.3570472 1.1865748 2.3570472 5 P 0
L 0.9031102 2.5588189 0.9031102 2.6050787 5 P 0
L 0.9031102 2.6050787 1.1865748 2.6050787 5 P 0
L 0.9068377 0.7820598 0.8918425 0.7820598 4 P 0 ;0,1=5,2=0.000000
L 0.9068377 0.8020533 0.911836 0.7970549 4 P 0 ;0,1=5,2=0.000000
L 0.9118328 1.071063 0.9218296 1.071063 15 P 0 ;0,1=86,2=0.000000
L 0.9118328 1.596063 0.9218296 1.596063 15 P 0 ;0,1=87,2=0.000000
L 0.9118328 2.121063 0.9218296 2.121063 15 P 0 ;0,1=89,2=0.000000
L 0.9118328 2.646063 0.9218296 2.646063 15 P 0 ;0,1=88,2=0.000000
L 0.911836 0.7870582 0.9068377 0.7820598 4 P 0 ;0,1=5,2=0.000000
L 0.911836 0.7970549 0.911836 0.7870582 4 P 0 ;0,1=5,2=0.000000
L 0.9168312 1.071063 0.9168312 1.1010533 15 P 0 ;0,1=86,2=0.000000
L 0.9168312 1.1010533 0.9118328 1.0960549 15 P 0 ;0,1=86,2=0.000000
L 0.9168312 1.596063 0.9168312 1.6260533 15 P 0 ;0,1=87,2=0.000000
L 0.9168312 1.6260533 0.9118328 1.6210549 15 P 0 ;0,1=87,2=0.000000
L 0.9168312 2.121063 0.9168312 2.1510533 15 P 0 ;0,1=89,2=0.000000
L 0.9168312 2.1510533 0.9118328 2.1460549 15 P 0 ;0,1=89,2=0.000000
L 0.9168312 2.646063 0.9168312 2.6760533 15 P 0 ;0,1=88,2=0.000000
L 0.9168312 2.6760533 0.9118328 2.6710549 15 P 0 ;0,1=88,2=0.000000
L 0.9218296 1.071063 0.9168312 1.071063 15 P 0 ;0,1=86,2=0.000000
L 0.9218296 1.596063 0.9168312 1.596063 15 P 0 ;0,1=87,2=0.000000
L 0.9218296 2.121063 0.9168312 2.121063 15 P 0 ;0,1=89,2=0.000000
L 0.9218296 2.646063 0.9168312 2.646063 15 P 0 ;0,1=88,2=0.000000
L 0.9218328 0.7970549 0.9268312 0.8020533 4 P 0 ;0,1=5,2=0.000000
L 0.922244 1.7332677 0.9379921 1.7332677 5 P 0
L 0.922244 1.7608268 0.9379921 1.7608268 5 P 0
L 0.9232282 0.7047243 0.9389763 0.7047243 5 P 0
L 0.9232282 0.7322834 0.9389763 0.7322834 5 P 0
L 0.926181 1.2106299 0.9419291 1.2106299 5 P 0
L 0.926181 1.238189 0.9419291 1.238189 5 P 0
L 0.9268312 0.772063 0.9218328 0.7770614 4 P 0 ;0,1=5,2=0.000000
L 0.9268312 0.8020533 0.936828 0.8020533 4 P 0 ;0,1=5,2=0.000000
L 0.930118 2.2706692 0.9458661 2.2706692 5 P 0
L 0.930118 2.2982283 0.9458661 2.2982283 5 P 0
L 0.9318296 0.7870582 0.936828 0.7870582 4 P 0 ;0,1=5,2=0.000000
L 0.9368247 1.0760614 0.9368247 1.0810598 15 P 0 ;0,1=86,2=0.000000
L 0.9368247 1.0810598 0.9418231 1.0860582 15 P 0 ;0,1=86,2=0.000000
L 0.9368247 1.0910565 0.9368247 1.0960549 15 P 0 ;0,1=86,2=0.000000
L 0.9368247 1.0960549 0.9418231 1.1010533 15 P 0 ;0,1=86,2=0.000000
L 0.9368247 1.6010614 0.9368247 1.596063 15 P 0 ;0,1=87,2=0.000000
L 0.9368247 1.6260533 0.9568182 1.6260533 15 P 0 ;0,1=87,2=0.000000
L 0.9368247 2.1360582 0.9468215 2.1410565 15 P 0 ;0,1=89,2=0.000000
L 0.9368247 2.1510533 0.9368247 2.1360582 15 P 0 ;0,1=89,2=0.000000
L 0.9368247 2.6510614 0.9418231 2.646063 15 P 0 ;0,1=88,2=0.000000
L 0.9368247 2.6610582 0.9368247 2.6510614 15 P 0 ;0,1=88,2=0.000000
L 0.936828 0.772063 0.9268312 0.772063 4 P 0 ;0,1=5,2=0.000000
L 0.936828 0.7870582 0.9318296 0.7870582 4 P 0 ;0,1=5,2=0.000000
L 0.936828 0.7870582 0.9418263 0.7820598 4 P 0 ;0,1=5,2=0.000000
L 0.936828 0.8020533 0.9418263 0.7970549 4 P 0 ;0,1=5,2=0.000000
L 0.9418231 1.071063 0.9368247 1.0760614 15 P 0 ;0,1=86,2=0.000000
L 0.9418231 1.0860582 0.9368247 1.0910565 15 P 0 ;0,1=86,2=0.000000
L 0.9418231 1.0860582 0.9518199 1.0860582 15 P 0 ;0,1=86,2=0.000000
L 0.9418231 1.1010533 0.9518199 1.1010533 15 P 0 ;0,1=86,2=0.000000
L 0.9418231 2.121063 0.9368247 2.1260614 15 P 0 ;0,1=89,2=0.000000
L 0.9418231 2.646063 0.9518199 2.646063 15 P 0 ;0,1=88,2=0.000000
L 0.9418263 0.7770614 0.936828 0.772063 4 P 0 ;0,1=5,2=0.000000
L 0.9418263 0.7820598 0.9418263 0.7770614 4 P 0 ;0,1=5,2=0.000000
L 0.9418263 0.7920565 0.936828 0.7870582 4 P 0 ;0,1=5,2=0.000000
L 0.9418263 0.7970549 0.9418263 0.7920565 4 P 0 ;0,1=5,2=0.000000
L 0.9468215 2.1410565 0.9518199 2.1410565 15 P 0 ;0,1=89,2=0.000000
L 0.9468215 2.6710549 0.9368247 2.6610582 15 P 0 ;0,1=88,2=0.000000
L 0.9518199 1.071063 0.9418231 1.071063 15 P 0 ;0,1=86,2=0.000000
L 0.9518199 1.0860582 0.9568182 1.0810598 15 P 0 ;0,1=86,2=0.000000
L 0.9518199 1.1010533 0.9568182 1.0960549 15 P 0 ;0,1=86,2=0.000000
L 0.9518199 2.121063 0.9418231 2.121063 15 P 0 ;0,1=89,2=0.000000
L 0.9518199 2.1410565 0.9568182 2.1360582 15 P 0 ;0,1=89,2=0.000000
L 0.9518199 2.646063 0.9568182 2.6510614 15 P 0 ;0,1=88,2=0.000000
L 0.9518199 2.6610582 0.9368247 2.6610582 15 P 0 ;0,1=88,2=0.000000
L 0.9518231 0.7770614 0.9568215 0.772063 4 P 0 ;0,1=5,2=0.000000
L 0.9518231 0.7870582 0.9518231 0.7770614 4 P 0 ;0,1=5,2=0.000000
L 0.9568182 1.0760614 0.9518199 1.071063 15 P 0 ;0,1=86,2=0.000000
L 0.9568182 1.0810598 0.9568182 1.0760614 15 P 0 ;0,1=86,2=0.000000
L 0.9568182 1.0910565 0.9518199 1.0860582 15 P 0 ;0,1=86,2=0.000000
L 0.9568182 1.0960549 0.9568182 1.0910565 15 P 0 ;0,1=86,2=0.000000
L 0.9568182 1.6210549 0.9368247 1.6010614 15 P 0 ;0,1=87,2=0.000000
L 0.9568182 1.6260533 0.9568182 1.6210549 15 P 0 ;0,1=87,2=0.000000
L 0.9568182 2.1260614 0.9518199 2.121063 15 P 0 ;0,1=89,2=0.000000
L 0.9568182 2.1360582 0.9568182 2.1260614 15 P 0 ;0,1=89,2=0.000000
L 0.9568182 2.1510533 0.9368247 2.1510533 15 P 0 ;0,1=89,2=0.000000
L 0.9568182 2.6510614 0.9568182 2.6560598 15 P 0 ;0,1=88,2=0.000000
L 0.9568182 2.6560598 0.9518199 2.6610582 15 P 0 ;0,1=88,2=0.000000
L 0.9568182 2.6760533 0.9468215 2.6710549 15 P 0 ;0,1=88,2=0.000000
L 0.9568215 0.772063 0.9668183 0.772063 4 P 0 ;0,1=5,2=0.000000
L 0.9603449 4.1648312 0.9903352 4.1648312 15 P 0 ;0,1=91,2=90.000000
L 0.9603449 4.1798264 0.9603449 4.1648312 15 P 0 ;0,1=91,2=90.000000
L 0.9603449 4.1998199 0.9653433 4.1948215 15 P 0 ;0,1=91,2=90.000000
L 0.9603449 4.2248118 0.9603449 4.2348086 15 P 0 ;0,1=91,2=90.000000
L 0.9603449 4.2348086 0.9653433 4.2398069 15 P 0 ;0,1=91,2=90.000000
L 0.9618199 0.7970549 0.9518231 0.7870582 4 P 0 ;0,1=5,2=0.000000
L 0.9633449 4.0040824 0.9633449 4.0190776 15 P 0 ;0,1=55,2=90.000000
L 0.9633449 4.0190776 0.9683433 4.0240759 15 P 0 ;0,1=55,2=90.000000
L 0.9633449 4.0390711 0.9633449 4.0490679 15 P 0 ;0,1=55,2=90.000000
L 0.9633449 4.0490679 0.9683433 4.0540662 15 P 0 ;0,1=55,2=90.000000
L 0.9633449 4.0690614 0.9633449 4.0790582 15 P 0 ;0,1=55,2=90.000000
L 0.9633449 4.0790582 0.9683433 4.0840565 15 P 0 ;0,1=55,2=90.000000
L 0.9653433 4.1848247 0.9603449 4.1798264 15 P 0 ;0,1=91,2=90.000000
L 0.9653433 4.2198134 0.9603449 4.2248118 15 P 0 ;0,1=91,2=90.000000
L 0.9653433 4.2398069 0.9703417 4.2398069 15 P 0 ;0,1=91,2=90.000000
L 0.9668183 0.772063 0.9718166 0.7770614 4 P 0 ;0,1=5,2=0.000000
L 0.9668183 0.7870582 0.9518231 0.7870582 4 P 0 ;0,1=5,2=0.000000
L 0.9683433 4.0240759 0.97834 4.0240759 15 P 0 ;0,1=55,2=90.000000
L 0.9683433 4.0340727 0.9633449 4.0390711 15 P 0 ;0,1=55,2=90.000000
L 0.9683433 4.0540662 0.9733417 4.0540662 15 P 0 ;0,1=55,2=90.000000
L 0.9683433 4.064063 0.9633449 4.0690614 15 P 0 ;0,1=55,2=90.000000
L 0.9683433 4.0840565 0.9883368 4.0840565 15 P 0 ;0,1=55,2=90.000000
L 0.9703417 4.2398069 0.97534 4.2348086 15 P 0 ;0,1=91,2=90.000000
L 0.9718166 0.7770614 0.9718166 0.7820598 4 P 0 ;0,1=5,2=0.000000
L 0.9718166 0.7820598 0.9668183 0.7870582 4 P 0 ;0,1=5,2=0.000000
L 0.9718166 0.8020533 0.9618199 0.7970549 4 P 0 ;0,1=5,2=0.000000
L 0.9733417 4.0540662 0.97834 4.0490679 15 P 0 ;0,1=55,2=90.000000
L 0.97534 4.2298102 0.97534 4.2348086 15 P 0 ;0,1=91,2=90.000000
L 0.97534 4.2348086 0.97534 4.2298102 15 P 0 ;0,1=91,2=90.000000
L 0.97534 4.2348086 0.9803384 4.2398069 15 P 0 ;0,1=91,2=90.000000
L 0.97834 4.0240759 0.9833384 4.0190776 15 P 0 ;0,1=55,2=90.000000
L 0.97834 4.0440695 0.97834 4.0490679 15 P 0 ;0,1=55,2=90.000000
L 0.97834 4.0490679 0.97834 4.0440695 15 P 0 ;0,1=55,2=90.000000
L 0.97834 4.0490679 0.9833384 4.0540662 15 P 0 ;0,1=55,2=90.000000
L 0.9803384 4.2398069 0.9853368 4.2398069 15 P 0 ;0,1=91,2=90.000000
L 0.9833384 4.0140792 0.9933352 4.0240759 15 P 0 ;0,1=55,2=90.000000
L 0.9833384 4.0190776 0.9833384 4.0040824 15 P 0 ;0,1=55,2=90.000000
L 0.9833384 4.0540662 0.9883368 4.0540662 15 P 0 ;0,1=55,2=90.000000
L 0.9853368 4.1848247 0.9653433 4.1848247 15 P 0 ;0,1=91,2=90.000000
L 0.9853368 4.2398069 0.9903352 4.2348086 15 P 0 ;0,1=91,2=90.000000
L 0.9883368 4.0540662 0.9933352 4.0490679 15 P 0 ;0,1=55,2=90.000000
L 0.9883368 4.064063 0.9683433 4.064063 15 P 0 ;0,1=55,2=90.000000
L 0.9883368 4.0840565 0.9933352 4.0790582 15 P 0 ;0,1=55,2=90.000000
L 0.9903352 4.1648312 0.9903352 4.1798264 15 P 0 ;0,1=91,2=90.000000
L 0.9903352 4.1798264 0.9853368 4.1848247 15 P 0 ;0,1=91,2=90.000000
L 0.9903352 4.1948215 0.9903352 4.2048183 15 P 0 ;0,1=91,2=90.000000
L 0.9903352 4.1998199 0.9603449 4.1998199 15 P 0 ;0,1=91,2=90.000000
L 0.9903352 4.2048183 0.9903352 4.1998199 15 P 0 ;0,1=91,2=90.000000
L 0.9903352 4.2248118 0.9853368 4.2198134 15 P 0 ;0,1=91,2=90.000000
L 0.9903352 4.2348086 0.9903352 4.2248118 15 P 0 ;0,1=91,2=90.000000
L 0.9933352 4.0040824 0.9633449 4.0040824 15 P 0 ;0,1=55,2=90.000000
L 0.9933352 4.0390711 0.9883368 4.0340727 15 P 0 ;0,1=55,2=90.000000
L 0.9933352 4.0490679 0.9933352 4.0390711 15 P 0 ;0,1=55,2=90.000000
L 0.9933352 4.0690614 0.9883368 4.064063 15 P 0 ;0,1=55,2=90.000000
L 0.9933352 4.0790582 0.9933352 4.0690614 15 P 0 ;0,1=55,2=90.000000
L 1.0226167 4.066063 1.0619867 4.066063 8 P 0
L 1.0481421 1.2182725 1.0481421 1.2482628 4 P 0 ;0,1=8,2=0.000000
L 1.0481421 1.2482628 1.0631373 1.2482628 4 P 0 ;0,1=8,2=0.000000
L 1.0581389 1.2282693 1.0681356 1.2182725 4 P 0 ;0,1=8,2=0.000000
L 1.0631373 1.2282693 1.0481421 1.2282693 4 P 0 ;0,1=8,2=0.000000
L 1.0631373 1.2482628 1.0681356 1.2432644 4 P 0 ;0,1=8,2=0.000000
L 1.0681356 1.2332677 1.0631373 1.2282693 4 P 0 ;0,1=8,2=0.000000
L 1.0681356 1.2432644 1.0681356 1.2332677 4 P 0 ;0,1=8,2=0.000000
L 1.0697956 1.7320522 1.0697956 1.7620425 4 P 0 ;0,1=9,2=0.000000
L 1.0697956 1.7620425 1.0847908 1.7620425 4 P 0 ;0,1=9,2=0.000000
L 1.0697956 2.2694537 1.0697956 2.299444 4 P 0 ;0,1=10,2=0.000000
L 1.0697956 2.299444 1.0847908 2.299444 4 P 0 ;0,1=10,2=0.000000
L 1.0781324 1.2182725 1.0881292 1.2182725 4 P 0 ;0,1=8,2=0.000000
L 1.0797924 1.742049 1.0897891 1.7320522 4 P 0 ;0,1=9,2=0.000000
L 1.0797924 2.2794505 1.0897891 2.2694537 4 P 0 ;0,1=10,2=0.000000
L 1.0831308 1.2182725 1.0831308 1.2482628 4 P 0 ;0,1=8,2=0.000000
L 1.0831308 1.2482628 1.0781324 1.2432644 4 P 0 ;0,1=8,2=0.000000
L 1.0847908 1.742049 1.0697956 1.742049 4 P 0 ;0,1=9,2=0.000000
L 1.0847908 1.7620425 1.0897891 1.7570441 4 P 0 ;0,1=9,2=0.000000
L 1.0847908 2.2794505 1.0697956 2.2794505 4 P 0 ;0,1=10,2=0.000000
L 1.0847908 2.299444 1.0897891 2.2944456 4 P 0 ;0,1=10,2=0.000000
L 1.0881292 1.2182725 1.0831308 1.2182725 4 P 0 ;0,1=8,2=0.000000
L 1.0897891 1.7470474 1.0847908 1.742049 4 P 0 ;0,1=9,2=0.000000
L 1.0897891 1.7570441 1.0897891 1.7470474 4 P 0 ;0,1=9,2=0.000000
L 1.0897891 2.2844489 1.0847908 2.2794505 4 P 0 ;0,1=10,2=0.000000
L 1.0897891 2.2944456 1.0897891 2.2844489 4 P 0 ;0,1=10,2=0.000000
L 1.0997859 1.7320522 1.1097827 1.7320522 4 P 0 ;0,1=9,2=0.000000
L 1.0997859 2.2694537 1.1097827 2.2694537 4 P 0 ;0,1=10,2=0.000000
L 1.1031243 1.2232709 1.1081227 1.2182725 4 P 0 ;0,1=8,2=0.000000
L 1.1031243 1.2332677 1.1031243 1.2232709 4 P 0 ;0,1=8,2=0.000000
L 1.1047843 1.7320522 1.1047843 1.7620425 4 P 0 ;0,1=9,2=0.000000
L 1.1047843 1.7620425 1.0997859 1.7570441 4 P 0 ;0,1=9,2=0.000000
L 1.1047843 2.2694537 1.1047843 2.299444 4 P 0 ;0,1=10,2=0.000000
L 1.1047843 2.299444 1.0997859 2.2944456 4 P 0 ;0,1=10,2=0.000000
L 1.1081227 1.2182725 1.1181195 1.2182725 4 P 0 ;0,1=8,2=0.000000
L 1.1097827 1.7320522 1.1047843 1.7320522 4 P 0 ;0,1=9,2=0.000000
L 1.1097827 2.2694537 1.1047843 2.2694537 4 P 0 ;0,1=10,2=0.000000
L 1.1131211 1.2432644 1.1031243 1.2332677 4 P 0 ;0,1=8,2=0.000000
L 1.1181195 1.2182725 1.1231178 1.2232709 4 P 0 ;0,1=8,2=0.000000
L 1.1181195 1.2332677 1.1031243 1.2332677 4 P 0 ;0,1=8,2=0.000000
L 1.1231178 1.2232709 1.1231178 1.2282693 4 P 0 ;0,1=8,2=0.000000
L 1.1231178 1.2282693 1.1181195 1.2332677 4 P 0 ;0,1=8,2=0.000000
L 1.1231178 1.2482628 1.1131211 1.2432644 4 P 0 ;0,1=8,2=0.000000
L 1.1247778 1.7470474 1.1347746 1.7520457 4 P 0 ;0,1=9,2=0.000000
L 1.1247778 1.7620425 1.1247778 1.7470474 4 P 0 ;0,1=9,2=0.000000
L 1.1247778 2.2844489 1.1447713 2.2844489 4 P 0 ;0,1=10,2=0.000000
L 1.1297762 1.7320522 1.1247778 1.7370506 4 P 0 ;0,1=9,2=0.000000
L 1.1347746 1.7520457 1.139773 1.7520457 4 P 0 ;0,1=9,2=0.000000
L 1.139773 1.7320522 1.1297762 1.7320522 4 P 0 ;0,1=9,2=0.000000
L 1.139773 1.7520457 1.1447713 1.7470474 4 P 0 ;0,1=9,2=0.000000
L 1.139773 2.2694537 1.139773 2.299444 4 P 0 ;0,1=10,2=0.000000
L 1.139773 2.299444 1.1247778 2.2844489 4 P 0 ;0,1=10,2=0.000000
L 1.1447713 1.7370506 1.139773 1.7320522 4 P 0 ;0,1=9,2=0.000000
L 1.1447713 1.7470474 1.1447713 1.7370506 4 P 0 ;0,1=9,2=0.000000
L 1.1447713 1.7620425 1.1247778 1.7620425 4 P 0 ;0,1=9,2=0.000000
L 1.1623449 4.1678312 1.1923352 4.1678312 15 P 0 ;0,1=90,2=90.000000
L 1.1623449 4.1828264 1.1623449 4.1678312 15 P 0 ;0,1=90,2=90.000000
L 1.1623449 4.2028199 1.1673433 4.1978215 15 P 0 ;0,1=90,2=90.000000
L 1.1623449 4.2378086 1.17734 4.2228134 15 P 0 ;0,1=90,2=90.000000
L 1.1673433 4.1878247 1.1623449 4.1828264 15 P 0 ;0,1=90,2=90.000000
L 1.1683449 4.0135799 1.1683449 4.0285751 15 P 0 ;0,1=54,2=90.000000
L 1.1683449 4.0285751 1.1733433 4.0335734 15 P 0 ;0,1=54,2=90.000000
L 1.1683449 4.0485686 1.1683449 4.0585654 15 P 0 ;0,1=54,2=90.000000
L 1.1683449 4.0585654 1.1733433 4.0635637 15 P 0 ;0,1=54,2=90.000000
L 1.1683449 4.0785589 1.1733433 4.0735605 15 P 0 ;0,1=54,2=90.000000
L 1.1733433 4.0335734 1.18334 4.0335734 15 P 0 ;0,1=54,2=90.000000
L 1.1733433 4.0435702 1.1683449 4.0485686 15 P 0 ;0,1=54,2=90.000000
L 1.1733433 4.0635637 1.1783417 4.0635637 15 P 0 ;0,1=54,2=90.000000
L 1.17734 4.2228134 1.17734 4.2428069 15 P 0 ;0,1=90,2=90.000000
L 1.1783417 4.0635637 1.18334 4.0585654 15 P 0 ;0,1=54,2=90.000000
L 1.18334 4.0335734 1.1883384 4.0285751 15 P 0 ;0,1=54,2=90.000000
L 1.18334 4.053567 1.18334 4.0585654 15 P 0 ;0,1=54,2=90.000000
L 1.18334 4.0585654 1.18334 4.053567 15 P 0 ;0,1=54,2=90.000000
L 1.18334 4.0585654 1.1883384 4.0635637 15 P 0 ;0,1=54,2=90.000000
L 1.1865748 0.7820472 1.1865748 0.8283071 5 P 0
L 1.1865748 0.9838189 1.1865748 1.0300787 5 P 0
L 1.1865748 1.3070472 1.1865748 1.3533071 5 P 0
L 1.1865748 1.5088189 1.1865748 1.5550787 5 P 0
L 1.1865748 1.8320472 1.1865748 1.8783071 5 P 0
L 1.1865748 2.0338189 1.1865748 2.0800787 5 P 0
L 1.1865748 2.3570472 1.1865748 2.4033071 5 P 0
L 1.1865748 2.5588189 1.1865748 2.6050787 5 P 0
L 1.1873368 4.1878247 1.1673433 4.1878247 15 P 0 ;0,1=90,2=90.000000
L 1.1883384 4.0235767 1.1983352 4.0335734 15 P 0 ;0,1=54,2=90.000000
L 1.1883384 4.0285751 1.1883384 4.0135799 15 P 0 ;0,1=54,2=90.000000
L 1.1883384 4.0635637 1.1933368 4.0635637 15 P 0 ;0,1=54,2=90.000000
L 1.1923352 4.1678312 1.1923352 4.1828264 15 P 0 ;0,1=90,2=90.000000
L 1.1923352 4.1828264 1.1873368 4.1878247 15 P 0 ;0,1=90,2=90.000000
L 1.1923352 4.1978215 1.1923352 4.2078183 15 P 0 ;0,1=90,2=90.000000
L 1.1923352 4.2028199 1.1623449 4.2028199 15 P 0 ;0,1=90,2=90.000000
L 1.1923352 4.2078183 1.1923352 4.2028199 15 P 0 ;0,1=90,2=90.000000
L 1.1923352 4.2378086 1.1623449 4.2378086 15 P 0 ;0,1=90,2=90.000000
L 1.1933368 4.0635637 1.1983352 4.0585654 15 P 0 ;0,1=54,2=90.000000
L 1.1983352 4.0135799 1.1683449 4.0135799 15 P 0 ;0,1=54,2=90.000000
L 1.1983352 4.0485686 1.1933368 4.0435702 15 P 0 ;0,1=54,2=90.000000
L 1.1983352 4.0585654 1.1983352 4.0485686 15 P 0 ;0,1=54,2=90.000000
L 1.1983352 4.0735605 1.1983352 4.0835573 15 P 0 ;0,1=54,2=90.000000
L 1.1983352 4.0785589 1.1683449 4.0785589 15 P 0 ;0,1=54,2=90.000000
L 1.1983352 4.0835573 1.1983352 4.0785589 15 P 0 ;0,1=54,2=90.000000
L 1.2242833 4.066063 1.2636533 4.066063 8 P 0
L 1.312559 0.313945 1.312559 0.5029213 0 P 0
L 1.312559 0.313945 1.6275197 0.313945 0 P 0
L 1.3307858 4.2962599 1.3257874 4.3012583 15 P 0 ;0,1=7,2=0.000000
L 1.3326771 4.1043307 1.3326771 4.1200788 5 P 0
L 1.3326772 4 1.3326772 4.0157481 5 P 0
L 1.3357842 4.2962599 1.3307858 4.2962599 15 P 0 ;0,1=7,2=0.000000
L 1.3357842 4.3262502 1.3407826 4.3262502 15 P 0 ;0,1=7,2=0.000000
L 1.3407826 4.3012583 1.3357842 4.2962599 15 P 0 ;0,1=7,2=0.000000
L 1.3407826 4.3262502 1.3407826 4.3012583 15 P 0 ;0,1=7,2=0.000000
L 1.3457809 4.3262502 1.3357842 4.3262502 15 P 0 ;0,1=7,2=0.000000
L 1.3557777 4.2962599 1.3557777 4.3262502 15 P 0 ;0,1=7,2=0.000000
L 1.3557777 4.3262502 1.3707729 4.3262502 15 P 0 ;0,1=7,2=0.000000
L 1.3602362 4.1043307 1.3602362 4.1200788 5 P 0
L 1.3602363 4 1.3602363 4.0157481 5 P 0
L 1.3707729 4.3062567 1.3557777 4.3062567 15 P 0 ;0,1=7,2=0.000000
L 1.3707729 4.3262502 1.3757712 4.3212518 15 P 0 ;0,1=7,2=0.000000
L 1.3757712 4.3112551 1.3707729 4.3062567 15 P 0 ;0,1=7,2=0.000000
L 1.3757712 4.3212518 1.3757712 4.3112551 15 P 0 ;0,1=7,2=0.000000
L 1.385768 4.2962599 1.3957648 4.2962599 15 P 0 ;0,1=7,2=0.000000
L 1.3907664 4.2962599 1.3907664 4.3262502 15 P 0 ;0,1=7,2=0.000000
L 1.3907664 4.3262502 1.385768 4.3212518 15 P 0 ;0,1=7,2=0.000000
L 1.3957648 4.2962599 1.3907664 4.2962599 15 P 0 ;0,1=7,2=0.000000
L 1.4076771 4.003937 1.4076771 4.303937 8 P 0
L 1.4076771 4.003937 1.5076771 4.003937 8 P 0
L 1.4076771 4.303937 1.5076771 4.303937 8 P 0
L 1.5058619 4.2595687 1.5108603 4.2545703 15 P 0 ;0,1=31,2=0.000000
L 1.5058619 4.2795622 1.5058619 4.2595687 15 P 0 ;0,1=31,2=0.000000
L 1.5076771 4.003937 1.5076771 4.303937 8 P 0
L 1.5108603 4.2545703 1.5208571 4.2545703 15 P 0 ;0,1=31,2=0.000000
L 1.5108603 4.2845606 1.5058619 4.2795622 15 P 0 ;0,1=31,2=0.000000
L 1.5208571 4.2545703 1.5258554 4.2595687 15 P 0 ;0,1=31,2=0.000000
L 1.5208571 4.2845606 1.5108603 4.2845606 15 P 0 ;0,1=31,2=0.000000
L 1.5258554 4.2795622 1.5208571 4.2845606 15 P 0 ;0,1=31,2=0.000000
L 1.5358522 4.2595687 1.5408506 4.2545703 15 P 0 ;0,1=31,2=0.000000
L 1.5358522 4.2745638 1.5408506 4.2695655 15 P 0 ;0,1=31,2=0.000000
L 1.5358522 4.2795622 1.5358522 4.2745638 15 P 0 ;0,1=31,2=0.000000
L 1.5408506 4.2545703 1.5508474 4.2545703 15 P 0 ;0,1=31,2=0.000000
L 1.5408506 4.2695655 1.5558457 4.2695655 15 P 0 ;0,1=31,2=0.000000
L 1.5408506 4.2845606 1.5358522 4.2795622 15 P 0 ;0,1=31,2=0.000000
L 1.5413449 4.0258312 1.5663368 4.0258312 15 P 0 ;0,1=34,2=90.000000
L 1.5413449 4.0608199 1.5463433 4.0558215 15 P 0 ;0,1=34,2=90.000000
L 1.5413449 4.1008069 1.5463433 4.0908102 15 P 0 ;0,1=34,2=90.000000
L 1.5463433 4.0908102 1.55634 4.0808134 15 P 0 ;0,1=34,2=90.000000
L 1.5508325 0.815533 1.5508325 2.587193 12 P 0
L 1.5508325 0.815533 3.7161925 0.815533 12 P 0
L 1.5508325 2.587193 3.7161925 2.587193 12 P 0
L 1.5508474 4.2545703 1.5558457 4.2595687 15 P 0 ;0,1=31,2=0.000000
L 1.5508474 4.2845606 1.5408506 4.2845606 15 P 0 ;0,1=31,2=0.000000
L 1.5558457 4.2595687 1.5558457 4.2795622 15 P 0 ;0,1=31,2=0.000000
L 1.5558457 4.2795622 1.5508474 4.2845606 15 P 0 ;0,1=31,2=0.000000
L 1.55634 4.0808134 1.5663368 4.0808134 15 P 0 ;0,1=34,2=90.000000
L 1.55634 4.0958086 1.55634 4.0808134 15 P 0 ;0,1=34,2=90.000000
L 1.5568425 2.619063 1.5568425 2.6490533 15 P 0 ;0,1=77,2=0.000000
L 1.5568425 2.6490533 1.5718377 2.6490533 15 P 0 ;0,1=77,2=0.000000
L 1.5613384 4.1008069 1.55634 4.0958086 15 P 0 ;0,1=34,2=90.000000
L 1.5658425 4.2545703 1.585836 4.2745638 15 P 0 ;0,1=31,2=0.000000
L 1.5663368 4.0258312 1.5713352 4.0308296 15 P 0 ;0,1=34,2=90.000000
L 1.5663368 4.0458247 1.5413449 4.0458247 15 P 0 ;0,1=34,2=90.000000
L 1.5663368 4.0808134 1.5713352 4.0858118 15 P 0 ;0,1=34,2=90.000000
L 1.5663368 4.1008069 1.5613384 4.1008069 15 P 0 ;0,1=34,2=90.000000
L 1.5708409 4.2845606 1.5658425 4.2795622 15 P 0 ;0,1=31,2=0.000000
L 1.5713352 4.0308296 1.5713352 4.0408264 15 P 0 ;0,1=34,2=90.000000
L 1.5713352 4.0408264 1.5663368 4.0458247 15 P 0 ;0,1=34,2=90.000000
L 1.5713352 4.0558215 1.5713352 4.0658183 15 P 0 ;0,1=34,2=90.000000
L 1.5713352 4.0608199 1.5413449 4.0608199 15 P 0 ;0,1=34,2=90.000000
L 1.5713352 4.0658183 1.5713352 4.0608199 15 P 0 ;0,1=34,2=90.000000
L 1.5713352 4.0858118 1.5713352 4.0958086 15 P 0 ;0,1=34,2=90.000000
L 1.5713352 4.0958086 1.5663368 4.1008069 15 P 0 ;0,1=34,2=90.000000
L 1.5718377 2.6290598 1.5568425 2.6290598 15 P 0 ;0,1=77,2=0.000000
L 1.5718377 2.6490533 1.576836 2.6440549 15 P 0 ;0,1=77,2=0.000000
L 1.576836 2.6340582 1.5718377 2.6290598 15 P 0 ;0,1=77,2=0.000000
L 1.576836 2.6440549 1.576836 2.6340582 15 P 0 ;0,1=77,2=0.000000
L 1.5808377 4.2845606 1.5708409 4.2845606 15 P 0 ;0,1=31,2=0.000000
L 1.585836 4.2545703 1.5658425 4.2545703 15 P 0 ;0,1=31,2=0.000000
L 1.585836 4.2745638 1.585836 4.2795622 15 P 0 ;0,1=31,2=0.000000
L 1.585836 4.2795622 1.5808377 4.2845606 15 P 0 ;0,1=31,2=0.000000
L 1.5868328 2.619063 1.5968296 2.619063 15 P 0 ;0,1=77,2=0.000000
L 1.5918312 2.619063 1.5918312 2.6490533 15 P 0 ;0,1=77,2=0.000000
L 1.5918312 2.6490533 1.5868328 2.6440549 15 P 0 ;0,1=77,2=0.000000
L 1.5968296 2.619063 1.5918312 2.619063 15 P 0 ;0,1=77,2=0.000000
L 1.6180925 1.282273 1.6180925 1.308533 13 P 0
L 1.6180925 1.282273 1.6417125 1.282273 13 P 0
L 1.6180925 2.098533 1.6180925 2.124793 13 P 0
L 1.6180925 2.124793 1.6417125 2.124793 13 P 0
L 1.6275197 0.313945 1.6275197 0.4310709 0 P 0
L 1.6417125 1.260623 1.6417125 1.282273 13 P 0
L 1.6417125 1.260623 1.7519525 1.260623 13 P 0
L 1.6417125 2.124793 1.6417125 2.146443 13 P 0
L 1.6417125 2.146443 1.7519525 2.146443 13 P 0
L 1.6684325 2.2345268 1.6784293 2.2445236 4 P 0 ;0,1=2,2=0.000000
L 1.6708425 4.245063 1.7208425 4.245063 8 P 0
L 1.6708425 4.301063 1.7208425 4.301063 8 P 0
L 1.6758503 4.0136378 1.6758503 4.2104882 5 P 0
L 1.6758503 4.0136378 1.8018346 4.0136378 5 P 0
L 1.6758503 4.2104882 1.8018346 4.2104882 5 P 0
L 1.6784293 2.184543 1.6684325 2.1945398 4 P 0 ;0,1=2,2=0.000000
L 1.6784293 2.2445236 1.6984228 2.2445236 4 P 0 ;0,1=2,2=0.000000
L 1.688426 2.2145333 1.6984228 2.2145333 4 P 0 ;0,1=2,2=0.000000
L 1.6984228 2.184543 1.6784293 2.184543 4 P 0 ;0,1=2,2=0.000000
L 1.6984228 2.2145333 1.688426 2.2145333 4 P 0 ;0,1=2,2=0.000000
L 1.6984228 2.2145333 1.7084196 2.2045365 4 P 0 ;0,1=2,2=0.000000
L 1.6984228 2.2445236 1.7084196 2.2345268 4 P 0 ;0,1=2,2=0.000000
L 1.7084196 2.1945398 1.6984228 2.184543 4 P 0 ;0,1=2,2=0.000000
L 1.7084196 2.2045365 1.7084196 2.1945398 4 P 0 ;0,1=2,2=0.000000
L 1.7084196 2.2245301 1.6984228 2.2145333 4 P 0 ;0,1=2,2=0.000000
L 1.7084196 2.2345268 1.7084196 2.2245301 4 P 0 ;0,1=2,2=0.000000
L 1.7519525 1.260623 1.7519525 1.282273 13 P 0
L 1.7519525 1.282273 1.7755725 1.282273 13 P 0
L 1.7519525 2.124793 1.7519525 2.146443 13 P 0
L 1.7519525 2.124793 1.7755725 2.124793 13 P 0
L 1.7755725 1.282273 1.7755725 1.308533 13 P 0
L 1.7755725 2.098533 1.7755725 2.124793 13 P 0
L 1.7878425 0.253063 1.7878425 0.2830533 15 P 0 ;0,1=76,2=0.000000
L 1.7878425 0.2830533 1.8028377 0.2830533 15 P 0 ;0,1=76,2=0.000000
L 1.8018346 4.0136378 1.8018346 4.2104882 5 P 0
L 1.8028377 0.2630598 1.7878425 0.2630598 15 P 0 ;0,1=76,2=0.000000
L 1.8028377 0.2830533 1.807836 0.2780549 15 P 0 ;0,1=76,2=0.000000
L 1.807836 0.2680582 1.8028377 0.2630598 15 P 0 ;0,1=76,2=0.000000
L 1.807836 0.2780549 1.807836 0.2680582 15 P 0 ;0,1=76,2=0.000000
L 1.8078425 4.238063 1.8678425 4.238063 8 P 0
L 1.8078425 4.314063 1.8678425 4.314063 8 P 0
L 1.8178328 0.253063 1.8378263 0.2730565 15 P 0 ;0,1=76,2=0.000000
L 1.8228312 0.2830533 1.8178328 0.2780549 15 P 0 ;0,1=76,2=0.000000
L 1.832828 0.2830533 1.8228312 0.2830533 15 P 0 ;0,1=76,2=0.000000
L 1.8378263 0.253063 1.8178328 0.253063 15 P 0 ;0,1=76,2=0.000000
L 1.8378263 0.2730565 1.8378263 0.2780549 15 P 0 ;0,1=76,2=0.000000
L 1.8378263 0.2780549 1.832828 0.2830533 15 P 0 ;0,1=76,2=0.000000
L 1.8958555 4.1670679 1.8958555 4.1970582 15 P 0 ;0,1=33,2=0.000000
L 1.8958555 4.1970582 1.9108507 4.1970582 15 P 0 ;0,1=33,2=0.000000
L 1.9058523 4.1770647 1.915849 4.1670679 15 P 0 ;0,1=33,2=0.000000
L 1.9108507 4.1770647 1.8958555 4.1770647 15 P 0 ;0,1=33,2=0.000000
L 1.9108507 4.1970582 1.915849 4.1920598 15 P 0 ;0,1=33,2=0.000000
L 1.9141575 4.102063 1.9535275 4.102063 8 P 0
L 1.915849 4.1820631 1.9108507 4.1770647 15 P 0 ;0,1=33,2=0.000000
L 1.915849 4.1920598 1.915849 4.1820631 15 P 0 ;0,1=33,2=0.000000
L 1.9258458 4.1820631 1.9458393 4.1820631 15 P 0 ;0,1=33,2=0.000000
L 1.9353448 4.2285784 1.9403432 4.22358 15 P 0 ;0,1=30,2=90.000000
L 1.9353448 4.2385752 1.9353448 4.2285784 15 P 0 ;0,1=30,2=90.000000
L 1.9353448 4.2585687 1.9403432 4.2535703 15 P 0 ;0,1=30,2=90.000000
L 1.9353448 4.2685655 1.9353448 4.2585687 15 P 0 ;0,1=30,2=90.000000
L 1.9353448 4.288559 1.9403432 4.2835606 15 P 0 ;0,1=30,2=90.000000
L 1.9403432 4.22358 1.9603367 4.22358 15 P 0 ;0,1=30,2=90.000000
L 1.9403432 4.2435735 1.9353448 4.2385752 15 P 0 ;0,1=30,2=90.000000
L 1.9403432 4.2535703 1.9453416 4.2535703 15 P 0 ;0,1=30,2=90.000000
L 1.9403432 4.2735638 1.9353448 4.2685655 15 P 0 ;0,1=30,2=90.000000
L 1.940841 4.1670679 1.940841 4.1970582 15 P 0 ;0,1=33,2=0.000000
L 1.940841 4.1970582 1.9258458 4.1820631 15 P 0 ;0,1=33,2=0.000000
L 1.9453416 4.2535703 1.9503399 4.2585687 15 P 0 ;0,1=30,2=90.000000
L 1.9503399 4.2585687 1.9503399 4.2735638 15 P 0 ;0,1=30,2=90.000000
L 1.9532774 3.995233 1.9532774 4.0002314 15 P 0 ;0,1=6,2=90.000000
L 1.9532774 4.0002314 1.9782693 4.0002314 15 P 0 ;0,1=6,2=90.000000
L 1.9532774 4.0052297 1.9532774 3.995233 15 P 0 ;0,1=6,2=90.000000
L 1.9532774 4.0152265 1.9532774 4.0302217 15 P 0 ;0,1=6,2=90.000000
L 1.9532774 4.0302217 1.9582758 4.03522 15 P 0 ;0,1=6,2=90.000000
L 1.9532774 4.0502152 1.9582758 4.0452168 15 P 0 ;0,1=6,2=90.000000
L 1.9532774 4.060212 1.9532774 4.0502152 15 P 0 ;0,1=6,2=90.000000
L 1.9558361 4.1920598 1.9608345 4.1970582 15 P 0 ;0,1=33,2=0.000000
L 1.9582758 4.03522 1.9682725 4.03522 15 P 0 ;0,1=6,2=90.000000
L 1.9582758 4.0652103 1.9532774 4.060212 15 P 0 ;0,1=6,2=90.000000
L 1.9603367 4.22358 1.9653351 4.2285784 15 P 0 ;0,1=30,2=90.000000
L 1.9603367 4.2535703 1.9653351 4.2585687 15 P 0 ;0,1=30,2=90.000000
L 1.9603367 4.2735638 1.9403432 4.2735638 15 P 0 ;0,1=30,2=90.000000
L 1.9608345 4.1670679 1.9558361 4.1720663 15 P 0 ;0,1=33,2=0.000000
L 1.9608345 4.1970582 1.9708313 4.1970582 15 P 0 ;0,1=33,2=0.000000
L 1.9632742 4.0652103 1.9582758 4.0652103 15 P 0 ;0,1=6,2=90.000000
L 1.9653351 4.2285784 1.9653351 4.2385752 15 P 0 ;0,1=30,2=90.000000
L 1.9653351 4.2385752 1.9603367 4.2435735 15 P 0 ;0,1=30,2=90.000000
L 1.9653351 4.2585687 1.9653351 4.2685655 15 P 0 ;0,1=30,2=90.000000
L 1.9653351 4.2685655 1.9603367 4.2735638 15 P 0 ;0,1=30,2=90.000000
L 1.9653351 4.2835606 1.9653351 4.2935574 15 P 0 ;0,1=30,2=90.000000
L 1.9653351 4.288559 1.9353448 4.288559 15 P 0 ;0,1=30,2=90.000000
L 1.9653351 4.2935574 1.9653351 4.288559 15 P 0 ;0,1=30,2=90.000000
L 1.9658329 4.1820631 1.9708313 4.1820631 15 P 0 ;0,1=33,2=0.000000
L 1.9682725 4.03522 1.9732709 4.0302217 15 P 0 ;0,1=6,2=90.000000
L 1.9708313 4.1670679 1.9608345 4.1670679 15 P 0 ;0,1=33,2=0.000000
L 1.9708313 4.1820631 1.9658329 4.1820631 15 P 0 ;0,1=33,2=0.000000
L 1.9708313 4.1820631 1.9758296 4.1770647 15 P 0 ;0,1=33,2=0.000000
L 1.9708313 4.1970582 1.9758296 4.1920598 15 P 0 ;0,1=33,2=0.000000
L 1.9732709 4.0302217 1.9732709 4.0152265 15 P 0 ;0,1=6,2=90.000000
L 1.9758296 4.1720663 1.9708313 4.1670679 15 P 0 ;0,1=33,2=0.000000
L 1.9758296 4.1770647 1.9758296 4.1720663 15 P 0 ;0,1=33,2=0.000000
L 1.9758296 4.1870614 1.9708313 4.1820631 15 P 0 ;0,1=33,2=0.000000
L 1.9758296 4.1920598 1.9758296 4.1870614 15 P 0 ;0,1=33,2=0.000000
L 1.9782693 4.0002314 1.9832677 3.995233 15 P 0 ;0,1=6,2=90.000000
L 1.9828619 2.6325703 1.9828619 2.6625606 15 P 0 ;0,1=63,2=0.000000
L 1.9828619 2.6625606 1.9978571 2.6625606 15 P 0 ;0,1=63,2=0.000000
L 1.9832677 3.9902346 1.9782693 3.9852362 15 P 0 ;0,1=6,2=90.000000
L 1.9832677 3.995233 1.9832677 3.9902346 15 P 0 ;0,1=6,2=90.000000
L 1.9832677 4.0152265 1.9532774 4.0152265 15 P 0 ;0,1=6,2=90.000000
L 1.9832677 4.0452168 1.9632742 4.0652103 15 P 0 ;0,1=6,2=90.000000
L 1.9832677 4.0652103 1.9832677 4.0452168 15 P 0 ;0,1=6,2=90.000000
L 1.9928587 2.6425671 2.0028554 2.6325703 15 P 0 ;0,1=63,2=0.000000
L 1.9933071 4.007874 1.9933071 4.307874 8 P 0
L 1.9933071 4.007874 2.0933071 4.007874 8 P 0
L 1.9933071 4.307874 2.0933071 4.307874 8 P 0
L 1.9978571 2.6425671 1.9828619 2.6425671 15 P 0 ;0,1=63,2=0.000000
L 1.9978571 2.6625606 2.0028554 2.6575622 15 P 0 ;0,1=63,2=0.000000
L 2.0028554 2.6475655 1.9978571 2.6425671 15 P 0 ;0,1=63,2=0.000000
L 2.0028554 2.6575622 2.0028554 2.6475655 15 P 0 ;0,1=63,2=0.000000
L 2.0128522 2.6325703 2.0328457 2.6525638 15 P 0 ;0,1=63,2=0.000000
L 2.0178506 2.6625606 2.0128522 2.6575622 15 P 0 ;0,1=63,2=0.000000
L 2.0278474 2.6625606 2.0178506 2.6625606 15 P 0 ;0,1=63,2=0.000000
L 2.0328457 2.6325703 2.0128522 2.6325703 15 P 0 ;0,1=63,2=0.000000
L 2.0328457 2.6525638 2.0328457 2.6575622 15 P 0 ;0,1=63,2=0.000000
L 2.0328457 2.6575622 2.0278474 2.6625606 15 P 0 ;0,1=63,2=0.000000
L 2.0428425 2.6325703 2.062836 2.6525638 15 P 0 ;0,1=63,2=0.000000
L 2.0478409 2.6625606 2.0428425 2.6575622 15 P 0 ;0,1=63,2=0.000000
L 2.0578377 2.6625606 2.0478409 2.6625606 15 P 0 ;0,1=63,2=0.000000
L 2.062836 2.6325703 2.0428425 2.6325703 15 P 0 ;0,1=63,2=0.000000
L 2.062836 2.6525638 2.062836 2.6575622 15 P 0 ;0,1=63,2=0.000000
L 2.062836 2.6575622 2.0578377 2.6625606 15 P 0 ;0,1=63,2=0.000000
L 2.0663449 3.6210808 2.0713433 3.6160824 15 P 0 ;0,1=111,2=90.000000
L 2.0663449 3.6310776 2.0663449 3.6210808 15 P 0 ;0,1=111,2=90.000000
L 2.0663449 3.6460727 2.08134 3.6460727 15 P 0 ;0,1=111,2=90.000000
L 2.0663449 3.6660662 2.0663449 3.6460727 15 P 0 ;0,1=111,2=90.000000
L 2.0663449 3.6810614 2.0713433 3.676063 15 P 0 ;0,1=111,2=90.000000
L 2.0663449 3.6910582 2.0663449 3.6810614 15 P 0 ;0,1=111,2=90.000000
L 2.0684325 0.9645333 2.1084196 0.9645333 4 P 0 ;0,1=3,2=0.000000
L 2.0684325 2.409543 2.1084196 2.4495301 4 P 0 ;0,1=1,2=0.000000
L 2.0713433 3.6160824 2.0913368 3.6160824 15 P 0 ;0,1=111,2=90.000000
L 2.0713433 3.6360759 2.0663449 3.6310776 15 P 0 ;0,1=111,2=90.000000
L 2.0713433 3.676063 2.0763417 3.676063 15 P 0 ;0,1=111,2=90.000000
L 2.0713433 3.6960565 2.0663449 3.6910582 15 P 0 ;0,1=111,2=90.000000
L 2.0763417 3.6560695 2.0763417 3.6610679 15 P 0 ;0,1=111,2=90.000000
L 2.0763417 3.6610679 2.08134 3.6660662 15 P 0 ;0,1=111,2=90.000000
L 2.0763417 3.676063 2.08134 3.6810614 15 P 0 ;0,1=111,2=90.000000
L 2.0784293 2.4695236 2.0684325 2.4595268 4 P 0 ;0,1=1,2=0.000000
L 2.08134 3.6460727 2.0763417 3.6560695 15 P 0 ;0,1=111,2=90.000000
L 2.08134 3.6660662 2.0913368 3.6660662 15 P 0 ;0,1=111,2=90.000000
L 2.08134 3.6810614 2.08134 3.6960565 15 P 0 ;0,1=111,2=90.000000
L 2.0913368 3.6160824 2.0963352 3.6210808 15 P 0 ;0,1=111,2=90.000000
L 2.0913368 3.6660662 2.0963352 3.6610679 15 P 0 ;0,1=111,2=90.000000
L 2.0913368 3.676063 2.0963352 3.6810614 15 P 0 ;0,1=111,2=90.000000
L 2.0913368 3.6960565 2.0713433 3.6960565 15 P 0 ;0,1=111,2=90.000000
L 2.0933071 4.007874 2.0933071 4.307874 8 P 0
L 2.0963352 3.6210808 2.0963352 3.6310776 15 P 0 ;0,1=111,2=90.000000
L 2.0963352 3.6310776 2.0913368 3.6360759 15 P 0 ;0,1=111,2=90.000000
L 2.0963352 3.6510711 2.0913368 3.6460727 15 P 0 ;0,1=111,2=90.000000
L 2.0963352 3.6610679 2.0963352 3.6510711 15 P 0 ;0,1=111,2=90.000000
L 2.0963352 3.6810614 2.0963352 3.6910582 15 P 0 ;0,1=111,2=90.000000
L 2.0963352 3.6910582 2.0913368 3.6960565 15 P 0 ;0,1=111,2=90.000000
L 2.0984228 0.934543 2.0984228 0.9945236 4 P 0 ;0,1=3,2=0.000000
L 2.0984228 0.9945236 2.0684325 0.9645333 4 P 0 ;0,1=3,2=0.000000
L 2.0984228 2.4695236 2.0784293 2.4695236 4 P 0 ;0,1=1,2=0.000000
L 2.1084196 2.409543 2.0684325 2.409543 4 P 0 ;0,1=1,2=0.000000
L 2.1084196 2.4495301 2.1084196 2.4595268 4 P 0 ;0,1=1,2=0.000000
L 2.1084196 2.4595268 2.0984228 2.4695236 4 P 0 ;0,1=1,2=0.000000
L 2.1271575 2.652063 2.1665275 2.652063 8 P 0
L 2.1377952 4.0374016 2.1377952 4.0531497 5 P 0
L 2.1539225 2.383413 2.1539225 2.493653 13 P 0
L 2.1539225 2.383413 2.1755725 2.383413 13 P 0
L 2.1539225 2.493653 2.1755725 2.493653 13 P 0
L 2.1539325 0.903473 2.1539325 1.013713 13 P 0
L 2.1539325 0.903473 2.1755825 0.903473 13 P 0
L 2.1539325 1.013713 2.1755825 1.013713 13 P 0
L 2.1653543 4.0374016 2.1653543 4.0531497 5 P 0
L 2.1718425 3.651063 2.1718425 3.711063 8 P 0
L 2.1725669 4.1603386 2.1725669 4.2353386 8 P 0
L 2.1755725 2.359793 2.1755725 2.383413 13 P 0
L 2.1755725 2.359793 2.2018325 2.359793 13 P 0
L 2.1755725 2.493653 2.1755725 2.517273 13 P 0
L 2.1755725 2.517273 2.2018325 2.517273 13 P 0
L 2.1755825 0.879853 2.1755825 0.903473 13 P 0
L 2.1755825 0.879853 2.2018425 0.879853 13 P 0
L 2.1755825 1.013713 2.1755825 1.037333 13 P 0
L 2.1755825 1.037333 2.2018425 1.037333 13 P 0
L 2.1988188 4.0374016 2.1988188 4.0531497 5 P 0
L 2.2023449 3.7680808 2.2073433 3.7630824 15 P 0 ;0,1=112,2=90.000000
L 2.2023449 3.7780776 2.2023449 3.7680808 15 P 0 ;0,1=112,2=90.000000
L 2.2023449 3.7930727 2.21734 3.7930727 15 P 0 ;0,1=112,2=90.000000
L 2.2023449 3.8130662 2.2023449 3.7930727 15 P 0 ;0,1=112,2=90.000000
L 2.2023449 3.8280614 2.2023449 3.8380582 15 P 0 ;0,1=112,2=90.000000
L 2.2023449 3.8380582 2.2073433 3.8430565 15 P 0 ;0,1=112,2=90.000000
L 2.2073433 3.7630824 2.2273368 3.7630824 15 P 0 ;0,1=112,2=90.000000
L 2.2073433 3.7830759 2.2023449 3.7780776 15 P 0 ;0,1=112,2=90.000000
L 2.2073433 3.823063 2.2023449 3.8280614 15 P 0 ;0,1=112,2=90.000000
L 2.2073433 3.8430565 2.2123417 3.8430565 15 P 0 ;0,1=112,2=90.000000
L 2.2123417 3.8030695 2.2123417 3.8080679 15 P 0 ;0,1=112,2=90.000000
L 2.2123417 3.8080679 2.21734 3.8130662 15 P 0 ;0,1=112,2=90.000000
L 2.2123417 3.823063 2.2073433 3.823063 15 P 0 ;0,1=112,2=90.000000
L 2.2123417 3.8430565 2.21734 3.8380582 15 P 0 ;0,1=112,2=90.000000
L 2.21734 3.7930727 2.2123417 3.8030695 15 P 0 ;0,1=112,2=90.000000
L 2.21734 3.8130662 2.2273368 3.8130662 15 P 0 ;0,1=112,2=90.000000
L 2.21734 3.8280614 2.2123417 3.823063 15 P 0 ;0,1=112,2=90.000000
L 2.21734 3.8280614 2.21734 3.8380582 15 P 0 ;0,1=112,2=90.000000
L 2.21734 3.8380582 2.2223384 3.8430565 15 P 0 ;0,1=112,2=90.000000
L 2.2223384 3.823063 2.21734 3.8280614 15 P 0 ;0,1=112,2=90.000000
L 2.2223384 3.8430565 2.2273368 3.8430565 15 P 0 ;0,1=112,2=90.000000
L 2.2263779 4.0374016 2.2263779 4.0531497 5 P 0
L 2.2273368 3.7630824 2.2323352 3.7680808 15 P 0 ;0,1=112,2=90.000000
L 2.2273368 3.8130662 2.2323352 3.8080679 15 P 0 ;0,1=112,2=90.000000
L 2.2273368 3.823063 2.2223384 3.823063 15 P 0 ;0,1=112,2=90.000000
L 2.2273368 3.8430565 2.2323352 3.8380582 15 P 0 ;0,1=112,2=90.000000
L 2.2323352 3.7680808 2.2323352 3.7780776 15 P 0 ;0,1=112,2=90.000000
L 2.2323352 3.7780776 2.2273368 3.7830759 15 P 0 ;0,1=112,2=90.000000
L 2.2323352 3.7980711 2.2273368 3.7930727 15 P 0 ;0,1=112,2=90.000000
L 2.2323352 3.8080679 2.2323352 3.7980711 15 P 0 ;0,1=112,2=90.000000
L 2.2323352 3.8280614 2.2273368 3.823063 15 P 0 ;0,1=112,2=90.000000
L 2.2323352 3.8380582 2.2323352 3.8280614 15 P 0 ;0,1=112,2=90.000000
L 2.2478425 3.651063 2.2478425 3.711063 8 P 0
L 2.3738425 3.008063 2.3738425 3.0380533 4 P 0 ;0,1=11,2=0.000000
L 2.3738425 3.0380533 2.3888377 3.0380533 4 P 0 ;0,1=11,2=0.000000
L 2.3740158 2.9212598 2.3740158 2.9370079 5 P 0
L 2.3838393 3.0180598 2.393836 3.008063 4 P 0 ;0,1=11,2=0.000000
L 2.3888377 3.0180598 2.3738425 3.0180598 4 P 0 ;0,1=11,2=0.000000
L 2.3888377 3.0380533 2.393836 3.0330549 4 P 0 ;0,1=11,2=0.000000
L 2.3888582 3.7160614 2.3938566 3.711063 15 P 0 ;0,1=41,2=0.000000
L 2.3888582 3.7410533 2.3888582 3.7160614 15 P 0 ;0,1=41,2=0.000000
L 2.393836 3.0230582 2.3888377 3.0180598 4 P 0 ;0,1=11,2=0.000000
L 2.393836 3.0330549 2.393836 3.0230582 4 P 0 ;0,1=11,2=0.000000
L 2.3938566 3.711063 2.4038534 3.711063 15 P 0 ;0,1=41,2=0.000000
L 2.4015749 2.9212598 2.4015749 2.9370079 5 P 0
L 2.4025669 4.1066443 2.4025669 4.116641 4 P 0 ;0,1=0,2=270.000000
L 2.4025669 4.116641 2.4625475 4.116641 4 P 0 ;0,1=0,2=270.000000
L 2.4025669 4.1266378 2.4025669 4.1066443 4 P 0 ;0,1=0,2=270.000000
L 2.4038328 3.008063 2.4138296 3.008063 4 P 0 ;0,1=11,2=0.000000
L 2.4038534 3.711063 2.4088517 3.7160614 15 P 0 ;0,1=41,2=0.000000
L 2.4088312 3.008063 2.4088312 3.0380533 4 P 0 ;0,1=11,2=0.000000
L 2.4088312 3.0380533 2.4038328 3.0330549 4 P 0 ;0,1=11,2=0.000000
L 2.4088517 3.7160614 2.4088517 3.7410533 15 P 0 ;0,1=41,2=0.000000
L 2.4138296 3.008063 2.4088312 3.008063 4 P 0 ;0,1=11,2=0.000000
L 2.4188485 3.7160614 2.4238469 3.711063 15 P 0 ;0,1=41,2=0.000000
L 2.4188485 3.7310565 2.4238469 3.7260582 15 P 0 ;0,1=41,2=0.000000
L 2.4188485 3.7360549 2.4188485 3.7310565 15 P 0 ;0,1=41,2=0.000000
L 2.4238469 3.711063 2.4338437 3.711063 15 P 0 ;0,1=41,2=0.000000
L 2.4238469 3.7260582 2.438842 3.7260582 15 P 0 ;0,1=41,2=0.000000
L 2.4238469 3.7410533 2.4188485 3.7360549 15 P 0 ;0,1=41,2=0.000000
L 2.4288247 3.0130614 2.4288247 3.008063 4 P 0 ;0,1=11,2=0.000000
L 2.4288247 3.0380533 2.4488182 3.0380533 4 P 0 ;0,1=11,2=0.000000
L 2.4338437 3.711063 2.438842 3.7160614 15 P 0 ;0,1=41,2=0.000000
L 2.4338437 3.7410533 2.4238469 3.7410533 15 P 0 ;0,1=41,2=0.000000
L 2.4384394 0.5403579 2.4384394 0.5553531 15 P 0 ;0,1=62,2=90.000000
L 2.4384394 0.5553531 2.4434378 0.5603514 15 P 0 ;0,1=62,2=90.000000
L 2.4384394 0.5753466 2.4434378 0.5703482 15 P 0 ;0,1=62,2=90.000000
L 2.4384394 0.5853434 2.4384394 0.5753466 15 P 0 ;0,1=62,2=90.000000
L 2.4384394 0.6053369 2.4384394 0.6153337 15 P 0 ;0,1=62,2=90.000000
L 2.4384394 0.6153337 2.4434378 0.620332 15 P 0 ;0,1=62,2=90.000000
L 2.438842 3.7160614 2.438842 3.7360549 15 P 0 ;0,1=41,2=0.000000
L 2.438842 3.7360549 2.4338437 3.7410533 15 P 0 ;0,1=41,2=0.000000
L 2.4434378 0.5603514 2.4534345 0.5603514 15 P 0 ;0,1=62,2=90.000000
L 2.4434378 0.5903417 2.4384394 0.5853434 15 P 0 ;0,1=62,2=90.000000
L 2.4434378 0.6003385 2.4384394 0.6053369 15 P 0 ;0,1=62,2=90.000000
L 2.4434378 0.620332 2.4484362 0.620332 15 P 0 ;0,1=62,2=90.000000
L 2.4484362 0.5903417 2.4434378 0.5903417 15 P 0 ;0,1=62,2=90.000000
L 2.4484362 0.620332 2.4534345 0.6153337 15 P 0 ;0,1=62,2=90.000000
L 2.4488182 3.0330549 2.4288247 3.0130614 4 P 0 ;0,1=11,2=0.000000
L 2.4488182 3.0380533 2.4488182 3.0330549 4 P 0 ;0,1=11,2=0.000000
L 2.4534345 0.5603514 2.4584329 0.5553531 15 P 0 ;0,1=62,2=90.000000
L 2.4534345 0.6103353 2.4534345 0.6153337 15 P 0 ;0,1=62,2=90.000000
L 2.4534345 0.6153337 2.4534345 0.6103353 15 P 0 ;0,1=62,2=90.000000
L 2.4534345 0.6153337 2.4584329 0.620332 15 P 0 ;0,1=62,2=90.000000
L 2.4584329 0.5503547 2.4684297 0.5603514 15 P 0 ;0,1=62,2=90.000000
L 2.4584329 0.5553531 2.4584329 0.5403579 15 P 0 ;0,1=62,2=90.000000
L 2.4584329 0.620332 2.4634313 0.620332 15 P 0 ;0,1=62,2=90.000000
L 2.4625475 4.116641 2.4525507 4.1266378 4 P 0 ;0,1=0,2=270.000000
L 2.4634313 0.620332 2.4684297 0.6153337 15 P 0 ;0,1=62,2=90.000000
L 2.4684297 0.5403579 2.4384394 0.5403579 15 P 0 ;0,1=62,2=90.000000
L 2.4684297 0.5703482 2.4484362 0.5903417 15 P 0 ;0,1=62,2=90.000000
L 2.4684297 0.5903417 2.4684297 0.5703482 15 P 0 ;0,1=62,2=90.000000
L 2.4684297 0.6053369 2.4634313 0.6003385 15 P 0 ;0,1=62,2=90.000000
L 2.4684297 0.6153337 2.4684297 0.6053369 15 P 0 ;0,1=62,2=90.000000
L 2.4925669 4.1603386 2.4925669 4.2353386 8 P 0
L 2.520353 4.1585703 2.5153546 4.1635687 15 P 0 ;0,1=35,2=0.000000
L 2.5253514 4.1585703 2.520353 4.1585703 15 P 0 ;0,1=35,2=0.000000
L 2.5253514 4.1885606 2.5303498 4.1885606 15 P 0 ;0,1=35,2=0.000000
L 2.5303498 4.1635687 2.5253514 4.1585703 15 P 0 ;0,1=35,2=0.000000
L 2.5303498 4.1885606 2.5303498 4.1635687 15 P 0 ;0,1=35,2=0.000000
L 2.5353481 4.1885606 2.5253514 4.1885606 15 P 0 ;0,1=35,2=0.000000
L 2.5453449 4.1735655 2.5653384 4.1735655 15 P 0 ;0,1=35,2=0.000000
L 2.5603401 4.1585703 2.5603401 4.1885606 15 P 0 ;0,1=35,2=0.000000
L 2.5603401 4.1885606 2.5453449 4.1735655 15 P 0 ;0,1=35,2=0.000000
L 2.6018425 3.541063 2.6018425 3.601063 8 P 0
L 2.6293546 4.2265687 2.634353 4.2215703 15 P 0 ;0,1=44,2=0.000000
L 2.6293546 4.2515606 2.6293546 4.2265687 15 P 0 ;0,1=44,2=0.000000
L 2.634353 4.2215703 2.6443498 4.2215703 15 P 0 ;0,1=44,2=0.000000
L 2.6443498 4.2215703 2.6493481 4.2265687 15 P 0 ;0,1=44,2=0.000000
L 2.6493481 4.2265687 2.6493481 4.2515606 15 P 0 ;0,1=44,2=0.000000
L 2.6593449 4.2365655 2.6693417 4.2415638 15 P 0 ;0,1=44,2=0.000000
L 2.6593449 4.2515606 2.6593449 4.2365655 15 P 0 ;0,1=44,2=0.000000
L 2.6628937 2.7167323 2.6628937 3.9667323 4 P 0
L 2.6643433 4.2215703 2.6593449 4.2265687 15 P 0 ;0,1=44,2=0.000000
L 2.6693417 4.2415638 2.6743401 4.2415638 15 P 0 ;0,1=44,2=0.000000
L 2.6743401 4.2215703 2.6643433 4.2215703 15 P 0 ;0,1=44,2=0.000000
L 2.6743401 4.2415638 2.6793384 4.2365655 15 P 0 ;0,1=44,2=0.000000
L 2.6765355 3.6794882 2.6765355 3.7188582 5 P 0
L 2.6765355 3.6794882 2.694252 3.6794882 5 P 0
L 2.6778425 3.541063 2.6778425 3.601063 8 P 0
L 2.6793384 4.2265687 2.6743401 4.2215703 15 P 0 ;0,1=44,2=0.000000
L 2.6793384 4.2365655 2.6793384 4.2265687 15 P 0 ;0,1=44,2=0.000000
L 2.6793384 4.2515606 2.6593449 4.2515606 15 P 0 ;0,1=44,2=0.000000
L 2.6923449 3.3590808 2.6973433 3.3540824 15 P 0 ;0,1=110,2=90.000000
L 2.6923449 3.3690776 2.6923449 3.3590808 15 P 0 ;0,1=110,2=90.000000
L 2.6923449 3.4040662 2.6973433 3.3940695 15 P 0 ;0,1=110,2=90.000000
L 2.6923449 3.4190614 2.6923449 3.4290582 15 P 0 ;0,1=110,2=90.000000
L 2.6923449 3.4290582 2.6973433 3.4340565 15 P 0 ;0,1=110,2=90.000000
L 2.6973433 3.3540824 2.7173368 3.3540824 15 P 0 ;0,1=110,2=90.000000
L 2.6973433 3.3740759 2.6923449 3.3690776 15 P 0 ;0,1=110,2=90.000000
L 2.6973433 3.3940695 2.70734 3.3840727 15 P 0 ;0,1=110,2=90.000000
L 2.6973433 3.414063 2.6923449 3.4190614 15 P 0 ;0,1=110,2=90.000000
L 2.6973433 3.4340565 2.7173368 3.4340565 15 P 0 ;0,1=110,2=90.000000
L 2.7053546 3.8225703 2.7203498 3.8225703 15 P 0 ;0,1=98,2=0.000000
L 2.7053546 3.8525606 2.7053546 3.8225703 15 P 0 ;0,1=98,2=0.000000
L 2.70734 3.3840727 2.7173368 3.3840727 15 P 0 ;0,1=110,2=90.000000
L 2.70734 3.3990679 2.70734 3.3840727 15 P 0 ;0,1=110,2=90.000000
L 2.7123384 3.4040662 2.70734 3.3990679 15 P 0 ;0,1=110,2=90.000000
L 2.7173368 3.3540824 2.7223352 3.3590808 15 P 0 ;0,1=110,2=90.000000
L 2.7173368 3.3840727 2.7223352 3.3890711 15 P 0 ;0,1=110,2=90.000000
L 2.7173368 3.4040662 2.7123384 3.4040662 15 P 0 ;0,1=110,2=90.000000
L 2.7173368 3.414063 2.6973433 3.414063 15 P 0 ;0,1=110,2=90.000000
L 2.7173368 3.4340565 2.7223352 3.4290582 15 P 0 ;0,1=110,2=90.000000
L 2.7203498 3.8225703 2.7253481 3.8275687 15 P 0 ;0,1=98,2=0.000000
L 2.7203498 3.8525606 2.7053546 3.8525606 15 P 0 ;0,1=98,2=0.000000
L 2.7223352 3.3590808 2.7223352 3.3690776 15 P 0 ;0,1=110,2=90.000000
L 2.7223352 3.3690776 2.7173368 3.3740759 15 P 0 ;0,1=110,2=90.000000
L 2.7223352 3.3890711 2.7223352 3.3990679 15 P 0 ;0,1=110,2=90.000000
L 2.7223352 3.3990679 2.7173368 3.4040662 15 P 0 ;0,1=110,2=90.000000
L 2.7223352 3.4190614 2.7173368 3.414063 15 P 0 ;0,1=110,2=90.000000
L 2.7223352 3.4290582 2.7223352 3.4190614 15 P 0 ;0,1=110,2=90.000000
L 2.7253481 3.8275687 2.7253481 3.8475622 15 P 0 ;0,1=98,2=0.000000
L 2.7253481 3.8475622 2.7203498 3.8525606 15 P 0 ;0,1=98,2=0.000000
L 2.7353449 3.8275687 2.7403433 3.8225703 15 P 0 ;0,1=98,2=0.000000
L 2.7353449 3.8375655 2.7353449 3.8275687 15 P 0 ;0,1=98,2=0.000000
L 2.7403433 3.8225703 2.7503401 3.8225703 15 P 0 ;0,1=98,2=0.000000
L 2.7448425 3.9036221 2.7448425 4.2685827 5 P 0
L 2.7448425 3.9036221 2.906063 3.9036221 5 P 0
L 2.7448425 4.2685827 2.906063 4.2685827 5 P 0
L 2.7453417 3.8475622 2.7353449 3.8375655 15 P 0 ;0,1=98,2=0.000000
L 2.7454331 3.6794882 2.7631496 3.6794882 5 P 0
L 2.7503401 3.8225703 2.7553384 3.8275687 15 P 0 ;0,1=98,2=0.000000
L 2.7503401 3.8375655 2.7353449 3.8375655 15 P 0 ;0,1=98,2=0.000000
L 2.7553384 3.8275687 2.7553384 3.8325671 15 P 0 ;0,1=98,2=0.000000
L 2.7553384 3.8325671 2.7503401 3.8375655 15 P 0 ;0,1=98,2=0.000000
L 2.7553384 3.8525606 2.7453417 3.8475622 15 P 0 ;0,1=98,2=0.000000
L 2.7631496 3.6794882 2.7631496 3.7188582 5 P 0
L 2.7673449 3.4475783 2.7723433 3.4425799 15 P 0 ;0,1=109,2=90.000000
L 2.7673449 3.4575751 2.7673449 3.4475783 15 P 0 ;0,1=109,2=90.000000
L 2.7673449 3.4925637 2.7723433 3.482567 15 P 0 ;0,1=109,2=90.000000
L 2.7673449 3.5075589 2.7723433 3.5025605 15 P 0 ;0,1=109,2=90.000000
L 2.7723433 3.4425799 2.7923368 3.4425799 15 P 0 ;0,1=109,2=90.000000
L 2.7723433 3.4625734 2.7673449 3.4575751 15 P 0 ;0,1=109,2=90.000000
L 2.7723433 3.482567 2.78234 3.4725702 15 P 0 ;0,1=109,2=90.000000
L 2.78234 3.4725702 2.7923368 3.4725702 15 P 0 ;0,1=109,2=90.000000
L 2.78234 3.4875654 2.78234 3.4725702 15 P 0 ;0,1=109,2=90.000000
L 2.7873384 3.4925637 2.78234 3.4875654 15 P 0 ;0,1=109,2=90.000000
L 2.7915355 3.6794882 2.7915355 3.7188582 5 P 0
L 2.7915355 3.6794882 2.809252 3.6794882 5 P 0
L 2.7923368 3.4425799 2.7973352 3.4475783 15 P 0 ;0,1=109,2=90.000000
L 2.7923368 3.4725702 2.7973352 3.4775686 15 P 0 ;0,1=109,2=90.000000
L 2.7923368 3.4925637 2.7873384 3.4925637 15 P 0 ;0,1=109,2=90.000000
L 2.7973352 3.4475783 2.7973352 3.4575751 15 P 0 ;0,1=109,2=90.000000
L 2.7973352 3.4575751 2.7923368 3.4625734 15 P 0 ;0,1=109,2=90.000000
L 2.7973352 3.4775686 2.7973352 3.4875654 15 P 0 ;0,1=109,2=90.000000
L 2.7973352 3.4875654 2.7923368 3.4925637 15 P 0 ;0,1=109,2=90.000000
L 2.7973352 3.5025605 2.7973352 3.5125573 15 P 0 ;0,1=109,2=90.000000
L 2.7973352 3.5075589 2.7673449 3.5075589 15 P 0 ;0,1=109,2=90.000000
L 2.7973352 3.5125573 2.7973352 3.5075589 15 P 0 ;0,1=109,2=90.000000
L 2.8120079 2.9055118 2.8120079 3.3188976 5 P 0
L 2.8120079 2.9055118 3.0561024 2.9055118 5 P 0
L 2.8120079 3.3188976 3.0561024 3.3188976 5 P 0
L 2.8411498 3.356145 2.8461482 3.3511466 4 P 0 ;0,1=12,2=0.000000
L 2.8411498 3.3811369 2.8411498 3.356145 4 P 0 ;0,1=12,2=0.000000
L 2.8461482 3.3511466 2.856145 3.3511466 4 P 0 ;0,1=12,2=0.000000
L 2.856145 3.3511466 2.8611433 3.356145 4 P 0 ;0,1=12,2=0.000000
L 2.8604331 3.6794882 2.8781496 3.6794882 5 P 0
L 2.8611433 3.356145 2.8611433 3.3811369 4 P 0 ;0,1=12,2=0.000000
L 2.8653449 3.5485751 2.8953352 3.5485751 15 P 0 ;0,1=99,2=90.000000
L 2.8653449 3.5635703 2.8653449 3.5485751 15 P 0 ;0,1=99,2=90.000000
L 2.8653449 3.5785654 2.88034 3.5785654 15 P 0 ;0,1=99,2=90.000000
L 2.8653449 3.5985589 2.8653449 3.5785654 15 P 0 ;0,1=99,2=90.000000
L 2.8703433 3.5685686 2.8653449 3.5635703 15 P 0 ;0,1=99,2=90.000000
L 2.8711401 3.3761385 2.8761385 3.3811369 4 P 0 ;0,1=12,2=0.000000
L 2.8753417 3.5885622 2.8753417 3.5935606 15 P 0 ;0,1=99,2=90.000000
L 2.8753417 3.5935606 2.88034 3.5985589 15 P 0 ;0,1=99,2=90.000000
L 2.8761385 3.3511466 2.8711401 3.356145 4 P 0 ;0,1=12,2=0.000000
L 2.8761385 3.3811369 2.8861353 3.3811369 4 P 0 ;0,1=12,2=0.000000
L 2.8781496 3.6794882 2.8781496 3.7188582 5 P 0
L 2.88034 3.5785654 2.8753417 3.5885622 15 P 0 ;0,1=99,2=90.000000
L 2.88034 3.5985589 2.8903368 3.5985589 15 P 0 ;0,1=99,2=90.000000
L 2.8811369 3.3661418 2.8861353 3.3661418 4 P 0 ;0,1=12,2=0.000000
L 2.8861353 3.3511466 2.8761385 3.3511466 4 P 0 ;0,1=12,2=0.000000
L 2.8861353 3.3661418 2.8811369 3.3661418 4 P 0 ;0,1=12,2=0.000000
L 2.8861353 3.3661418 2.8911336 3.3611434 4 P 0 ;0,1=12,2=0.000000
L 2.8861353 3.3811369 2.8911336 3.3761385 4 P 0 ;0,1=12,2=0.000000
L 2.8903368 3.5685686 2.8703433 3.5685686 15 P 0 ;0,1=99,2=90.000000
L 2.8903368 3.5985589 2.8953352 3.5935606 15 P 0 ;0,1=99,2=90.000000
L 2.8911336 3.356145 2.8861353 3.3511466 4 P 0 ;0,1=12,2=0.000000
L 2.8911336 3.3611434 2.8911336 3.356145 4 P 0 ;0,1=12,2=0.000000
L 2.8911336 3.3711401 2.8861353 3.3661418 4 P 0 ;0,1=12,2=0.000000
L 2.8911336 3.3761385 2.8911336 3.3711401 4 P 0 ;0,1=12,2=0.000000
L 2.8953352 3.5485751 2.8953352 3.5635703 15 P 0 ;0,1=99,2=90.000000
L 2.8953352 3.5635703 2.8903368 3.5685686 15 P 0 ;0,1=99,2=90.000000
L 2.8953352 3.5835638 2.8903368 3.5785654 15 P 0 ;0,1=99,2=90.000000
L 2.8953352 3.5935606 2.8953352 3.5835638 15 P 0 ;0,1=99,2=90.000000
L 2.9148425 3.706063 2.9748425 3.706063 8 P 0
L 2.9423449 3.5138312 2.9423449 3.5288264 15 P 0 ;0,1=67,2=90.000000
L 2.9423449 3.5288264 2.9473433 3.5338247 15 P 0 ;0,1=67,2=90.000000
L 2.9423449 3.5488199 2.9473433 3.5438215 15 P 0 ;0,1=67,2=90.000000
L 2.9423449 3.5738118 2.9423449 3.5838086 15 P 0 ;0,1=67,2=90.000000
L 2.9423449 3.5838086 2.9473433 3.5888069 15 P 0 ;0,1=67,2=90.000000
L 2.9473433 3.5338247 2.95734 3.5338247 15 P 0 ;0,1=67,2=90.000000
L 2.9473433 3.5688134 2.9423449 3.5738118 15 P 0 ;0,1=67,2=90.000000
L 2.9473433 3.5888069 2.9523417 3.5888069 15 P 0 ;0,1=67,2=90.000000
L 2.9523417 3.5688134 2.9473433 3.5688134 15 P 0 ;0,1=67,2=90.000000
L 2.9523417 3.5888069 2.95734 3.5838086 15 P 0 ;0,1=67,2=90.000000
L 2.95734 3.5338247 2.9623384 3.5288264 15 P 0 ;0,1=67,2=90.000000
L 2.95734 3.5738118 2.9523417 3.5688134 15 P 0 ;0,1=67,2=90.000000
L 2.95734 3.5738118 2.95734 3.5838086 15 P 0 ;0,1=67,2=90.000000
L 2.95734 3.5838086 2.9623384 3.5888069 15 P 0 ;0,1=67,2=90.000000
L 2.9623384 3.523828 2.9723352 3.5338247 15 P 0 ;0,1=67,2=90.000000
L 2.9623384 3.5288264 2.9623384 3.5138312 15 P 0 ;0,1=67,2=90.000000
L 2.9623384 3.5688134 2.95734 3.5738118 15 P 0 ;0,1=67,2=90.000000
L 2.9623384 3.5888069 2.9673368 3.5888069 15 P 0 ;0,1=67,2=90.000000
L 2.9673368 3.5688134 2.9623384 3.5688134 15 P 0 ;0,1=67,2=90.000000
L 2.9673368 3.5888069 2.9723352 3.5838086 15 P 0 ;0,1=67,2=90.000000
L 2.9723352 3.5138312 2.9423449 3.5138312 15 P 0 ;0,1=67,2=90.000000
L 2.9723352 3.5438215 2.9723352 3.5538183 15 P 0 ;0,1=67,2=90.000000
L 2.9723352 3.5488199 2.9423449 3.5488199 15 P 0 ;0,1=67,2=90.000000
L 2.9723352 3.5538183 2.9723352 3.5488199 15 P 0 ;0,1=67,2=90.000000
L 2.9723352 3.5738118 2.9673368 3.5688134 15 P 0 ;0,1=67,2=90.000000
L 2.9723352 3.5838086 2.9723352 3.5738118 15 P 0 ;0,1=67,2=90.000000
L 2.9866205 0.5373579 2.9866205 0.5523531 15 P 0 ;0,1=61,2=90.000000
L 2.9866205 0.5523531 2.9916189 0.5573514 15 P 0 ;0,1=61,2=90.000000
L 2.9866205 0.5723466 2.9916189 0.5673482 15 P 0 ;0,1=61,2=90.000000
L 2.9866205 0.5823434 2.9866205 0.5723466 15 P 0 ;0,1=61,2=90.000000
L 2.9866205 0.6123337 3.0016156 0.5973385 15 P 0 ;0,1=61,2=90.000000
L 2.9916189 0.5573514 3.0016156 0.5573514 15 P 0 ;0,1=61,2=90.000000
L 2.9916189 0.5873417 2.9866205 0.5823434 15 P 0 ;0,1=61,2=90.000000
L 2.9918325 2.359793 3.0180925 2.359793 13 P 0
L 2.9918325 2.517273 3.0180925 2.517273 13 P 0
L 2.9918425 0.879853 3.0181025 0.879853 13 P 0
L 2.9918425 1.037333 3.0181025 1.037333 13 P 0
L 2.9966173 0.5873417 2.9916189 0.5873417 15 P 0 ;0,1=61,2=90.000000
L 3.0016156 0.5573514 3.006614 0.5523531 15 P 0 ;0,1=61,2=90.000000
L 3.0016156 0.5973385 3.0016156 0.617332 15 P 0 ;0,1=61,2=90.000000
L 3.006614 0.5473547 3.0166108 0.5573514 15 P 0 ;0,1=61,2=90.000000
L 3.006614 0.5523531 3.006614 0.5373579 15 P 0 ;0,1=61,2=90.000000
L 3.0148425 3.706063 3.0748425 3.706063 8 P 0
L 3.0166108 0.5373579 2.9866205 0.5373579 15 P 0 ;0,1=61,2=90.000000
L 3.0166108 0.5673482 2.9966173 0.5873417 15 P 0 ;0,1=61,2=90.000000
L 3.0166108 0.5873417 3.0166108 0.5673482 15 P 0 ;0,1=61,2=90.000000
L 3.0166108 0.6123337 2.9866205 0.6123337 15 P 0 ;0,1=61,2=90.000000
L 3.0180925 2.359793 3.0180925 2.383413 13 P 0
L 3.0180925 2.383413 3.0397425 2.383413 13 P 0
L 3.0180925 2.493653 3.0180925 2.517273 13 P 0
L 3.0180925 2.493653 3.0397425 2.493653 13 P 0
L 3.0181025 0.879853 3.0181025 0.903473 13 P 0
L 3.0181025 0.903473 3.0397525 0.903473 13 P 0
L 3.0181025 1.013713 3.0181025 1.037333 13 P 0
L 3.0181025 1.013713 3.0397525 1.013713 13 P 0
L 3.0363449 3.5138312 3.0363449 3.5288264 15 P 0 ;0,1=66,2=90.000000
L 3.0363449 3.5288264 3.0413433 3.5338247 15 P 0 ;0,1=66,2=90.000000
L 3.0363449 3.5488199 3.0413433 3.5438215 15 P 0 ;0,1=66,2=90.000000
L 3.0363449 3.5738118 3.0413433 3.5688134 15 P 0 ;0,1=66,2=90.000000
L 3.0363449 3.5838086 3.0363449 3.5738118 15 P 0 ;0,1=66,2=90.000000
L 3.0397425 2.383413 3.0397425 2.493653 13 P 0
L 3.0397525 0.903473 3.0397525 1.013713 13 P 0
L 3.0413433 3.5338247 3.05134 3.5338247 15 P 0 ;0,1=66,2=90.000000
L 3.0413433 3.5688134 3.0463417 3.5688134 15 P 0 ;0,1=66,2=90.000000
L 3.0413433 3.5888069 3.0363449 3.5838086 15 P 0 ;0,1=66,2=90.000000
L 3.0463417 3.5688134 3.05134 3.5738118 15 P 0 ;0,1=66,2=90.000000
L 3.05134 3.5338247 3.0563384 3.5288264 15 P 0 ;0,1=66,2=90.000000
L 3.05134 3.5738118 3.05134 3.5888069 15 P 0 ;0,1=66,2=90.000000
L 3.0561024 2.9055118 3.0561024 3.3188976 5 P 0
L 3.0563384 3.523828 3.0663352 3.5338247 15 P 0 ;0,1=66,2=90.000000
L 3.0563384 3.5288264 3.0563384 3.5138312 15 P 0 ;0,1=66,2=90.000000
L 3.0613368 3.5688134 3.0663352 3.5738118 15 P 0 ;0,1=66,2=90.000000
L 3.0613368 3.5888069 3.0413433 3.5888069 15 P 0 ;0,1=66,2=90.000000
L 3.0663352 3.5138312 3.0363449 3.5138312 15 P 0 ;0,1=66,2=90.000000
L 3.0663352 3.5438215 3.0663352 3.5538183 15 P 0 ;0,1=66,2=90.000000
L 3.0663352 3.5488199 3.0363449 3.5488199 15 P 0 ;0,1=66,2=90.000000
L 3.0663352 3.5538183 3.0663352 3.5488199 15 P 0 ;0,1=66,2=90.000000
L 3.0663352 3.5738118 3.0663352 3.5838086 15 P 0 ;0,1=66,2=90.000000
L 3.0663352 3.5838086 3.0613368 3.5888069 15 P 0 ;0,1=66,2=90.000000
L 3.1148425 3.706063 3.1748425 3.706063 8 P 0
L 3.1383449 3.5100824 3.1383449 3.5250776 15 P 0 ;0,1=65,2=90.000000
L 3.1383449 3.5250776 3.1433433 3.5300759 15 P 0 ;0,1=65,2=90.000000
L 3.1383449 3.5450711 3.1433433 3.5400727 15 P 0 ;0,1=65,2=90.000000
L 3.1383449 3.5550679 3.1383449 3.5450711 15 P 0 ;0,1=65,2=90.000000
L 3.1383449 3.5750614 3.1383449 3.5850582 15 P 0 ;0,1=65,2=90.000000
L 3.1383449 3.5850582 3.1433433 3.5900565 15 P 0 ;0,1=65,2=90.000000
L 3.1433433 3.5300759 3.15334 3.5300759 15 P 0 ;0,1=65,2=90.000000
L 3.1433433 3.5600662 3.1383449 3.5550679 15 P 0 ;0,1=65,2=90.000000
L 3.1433433 3.570063 3.1383449 3.5750614 15 P 0 ;0,1=65,2=90.000000
L 3.1433433 3.5900565 3.1633368 3.5900565 15 P 0 ;0,1=65,2=90.000000
L 3.1483417 3.5600662 3.1433433 3.5600662 15 P 0 ;0,1=65,2=90.000000
L 3.15334 3.5300759 3.1583384 3.5250776 15 P 0 ;0,1=65,2=90.000000
L 3.1583384 3.5200792 3.1683352 3.5300759 15 P 0 ;0,1=65,2=90.000000
L 3.1583384 3.5250776 3.1583384 3.5100824 15 P 0 ;0,1=65,2=90.000000
L 3.1591082 3.3955687 3.1641066 3.3905703 15 P 0 ;0,1=39,2=0.000000
L 3.1591082 3.4205606 3.1591082 3.3955687 15 P 0 ;0,1=39,2=0.000000
L 3.1633368 3.570063 3.1433433 3.570063 15 P 0 ;0,1=65,2=90.000000
L 3.1633368 3.5900565 3.1683352 3.5850582 15 P 0 ;0,1=65,2=90.000000
L 3.1641066 3.3905703 3.1741034 3.3905703 15 P 0 ;0,1=39,2=0.000000
L 3.1683352 3.5100824 3.1383449 3.5100824 15 P 0 ;0,1=65,2=90.000000
L 3.1683352 3.5400727 3.1483417 3.5600662 15 P 0 ;0,1=65,2=90.000000
L 3.1683352 3.5600662 3.1683352 3.5400727 15 P 0 ;0,1=65,2=90.000000
L 3.1683352 3.5750614 3.1633368 3.570063 15 P 0 ;0,1=65,2=90.000000
L 3.1683352 3.5850582 3.1683352 3.5750614 15 P 0 ;0,1=65,2=90.000000
L 3.1741034 3.3905703 3.1791017 3.3955687 15 P 0 ;0,1=39,2=0.000000
L 3.1791017 3.3955687 3.1791017 3.4205606 15 P 0 ;0,1=39,2=0.000000
L 3.1890985 3.3905703 3.1990953 3.3905703 15 P 0 ;0,1=39,2=0.000000
L 3.1918425 2.916063 3.2018393 2.916063 4 P 0 ;0,1=4,2=0.000000
L 3.1918425 2.9460533 3.2018393 2.9460533 4 P 0 ;0,1=4,2=0.000000
L 3.1940969 3.3905703 3.1940969 3.4205606 15 P 0 ;0,1=39,2=0.000000
L 3.1940969 3.4205606 3.1890985 3.4155622 15 P 0 ;0,1=39,2=0.000000
L 3.1968409 2.916063 3.1918425 2.916063 4 P 0 ;0,1=4,2=0.000000
L 3.1968409 2.9460533 3.1968409 2.916063 4 P 0 ;0,1=4,2=0.000000
L 3.1990953 3.3905703 3.1940969 3.3905703 15 P 0 ;0,1=39,2=0.000000
L 3.1998031 2.7755905 3.1998031 2.7834645 0 P 0
L 3.1998031 2.7755905 3.2194882 2.7755905 0 P 0
L 3.1998031 2.8464567 3.1998031 2.8543307 0 P 0
L 3.1998031 2.8543307 3.2194882 2.8543307 0 P 0
L 3.2015355 3.6794882 3.2015355 3.7188582 5 P 0
L 3.2015355 3.6794882 3.219252 3.6794882 5 P 0
L 3.2018393 2.9460533 3.1968409 2.9460533 4 P 0 ;0,1=4,2=0.000000
L 3.2140904 3.3905703 3.2240872 3.3905703 15 P 0 ;0,1=39,2=0.000000
L 3.2168344 2.9210614 3.2218328 2.916063 4 P 0 ;0,1=4,2=0.000000
L 3.2168344 2.9410549 3.2168344 2.9210614 4 P 0 ;0,1=4,2=0.000000
L 3.2190888 3.3905703 3.2190888 3.4205606 15 P 0 ;0,1=39,2=0.000000
L 3.2190888 3.4205606 3.2140904 3.4155622 15 P 0 ;0,1=39,2=0.000000
L 3.2218328 2.916063 3.2318296 2.916063 4 P 0 ;0,1=4,2=0.000000
L 3.2218328 2.9460533 3.2168344 2.9410549 4 P 0 ;0,1=4,2=0.000000
L 3.2240872 3.3905703 3.2190888 3.3905703 15 P 0 ;0,1=39,2=0.000000
L 3.2318296 2.916063 3.2368279 2.9210614 4 P 0 ;0,1=4,2=0.000000
L 3.2318296 2.9460533 3.2218328 2.9460533 4 P 0 ;0,1=4,2=0.000000
L 3.2353449 3.5005751 3.2653352 3.5005751 15 P 0 ;0,1=97,2=90.000000
L 3.2353449 3.5155703 3.2353449 3.5005751 15 P 0 ;0,1=97,2=90.000000
L 3.2353449 3.5305654 3.2353449 3.5505589 15 P 0 ;0,1=97,2=90.000000
L 3.2353449 3.5505589 3.2403433 3.5505589 15 P 0 ;0,1=97,2=90.000000
L 3.2368279 2.9410549 3.2318296 2.9460533 4 P 0 ;0,1=4,2=0.000000
L 3.2403433 3.5205686 3.2353449 3.5155703 15 P 0 ;0,1=97,2=90.000000
L 3.2403433 3.5505589 3.2603368 3.5305654 15 P 0 ;0,1=97,2=90.000000
L 3.2468247 2.9410549 3.2518231 2.9460533 4 P 0 ;0,1=4,2=0.000000
L 3.2518231 2.9460533 3.2618199 2.9460533 4 P 0 ;0,1=4,2=0.000000
L 3.2568215 2.9210614 3.2568215 2.916063 4 P 0 ;0,1=4,2=0.000000
L 3.2588582 2.7755905 3.2785433 2.7755905 0 P 0
L 3.2588582 2.8543307 3.2785433 2.8543307 0 P 0
L 3.2603368 3.5205686 3.2403433 3.5205686 15 P 0 ;0,1=97,2=90.000000
L 3.2603368 3.5305654 3.2653352 3.5305654 15 P 0 ;0,1=97,2=90.000000
L 3.2618199 2.9460533 3.2668182 2.9410549 4 P 0 ;0,1=4,2=0.000000
L 3.2653352 3.5005751 3.2653352 3.5155703 15 P 0 ;0,1=97,2=90.000000
L 3.2653352 3.5155703 3.2603368 3.5205686 15 P 0 ;0,1=97,2=90.000000
L 3.2668182 2.9360565 3.2568215 2.9260598 4 P 0 ;0,1=4,2=0.000000
L 3.2668182 2.9410549 3.2668182 2.9360565 4 P 0 ;0,1=4,2=0.000000
L 3.2704331 3.6794882 3.2881496 3.6794882 5 P 0
L 3.2740551 3.1629134 3.2740551 3.2022835 10 P 0
L 3.2740551 3.1629134 3.3134252 3.1629134 10 P 0
L 3.2740551 3.3991339 3.2740551 3.438504 10 P 0
L 3.2740551 3.438504 3.3134252 3.438504 10 P 0
L 3.2785433 2.7755905 3.2785433 2.7834645 0 P 0
L 3.2785433 2.8464567 3.2785433 2.8543307 0 P 0
L 3.2881496 3.6794882 3.2881496 3.7188582 5 P 0
L 3.3198425 3.706063 3.3798425 3.706063 8 P 0
L 3.3413449 3.5195799 3.3413449 3.5345751 15 P 0 ;0,1=64,2=90.000000
L 3.3413449 3.5345751 3.3463433 3.5395734 15 P 0 ;0,1=64,2=90.000000
L 3.3413449 3.5545686 3.3463433 3.5495702 15 P 0 ;0,1=64,2=90.000000
L 3.3413449 3.5645654 3.3413449 3.5545686 15 P 0 ;0,1=64,2=90.000000
L 3.3413449 3.5845589 3.3463433 3.5795605 15 P 0 ;0,1=64,2=90.000000
L 3.3463433 3.5395734 3.35634 3.5395734 15 P 0 ;0,1=64,2=90.000000
L 3.3463433 3.5695637 3.3413449 3.5645654 15 P 0 ;0,1=64,2=90.000000
L 3.3513417 3.5695637 3.3463433 3.5695637 15 P 0 ;0,1=64,2=90.000000
L 3.35634 3.5395734 3.3613384 3.5345751 15 P 0 ;0,1=64,2=90.000000
L 3.3613384 3.5295767 3.3713352 3.5395734 15 P 0 ;0,1=64,2=90.000000
L 3.3613384 3.5345751 3.3613384 3.5195799 15 P 0 ;0,1=64,2=90.000000
L 3.3713352 3.5195799 3.3413449 3.5195799 15 P 0 ;0,1=64,2=90.000000
L 3.3713352 3.5495702 3.3513417 3.5695637 15 P 0 ;0,1=64,2=90.000000
L 3.3713352 3.5695637 3.3713352 3.5495702 15 P 0 ;0,1=64,2=90.000000
L 3.3713352 3.5795605 3.3713352 3.5895573 15 P 0 ;0,1=64,2=90.000000
L 3.3713352 3.5845589 3.3413449 3.5845589 15 P 0 ;0,1=64,2=90.000000
L 3.3713352 3.5895573 3.3713352 3.5845589 15 P 0 ;0,1=64,2=90.000000
L 3.383622 3.9036221 3.5448425 3.9036221 5 P 0
L 3.383622 4.2685827 3.5448425 4.2685827 5 P 0
L 3.4048425 2.852063 3.4048425 2.872063 10 P 0
L 3.4048425 2.852063 3.4248425 2.852063 10 P 0
L 3.4048425 3.0293174 3.4048425 3.092063 10 P 0
L 3.4048425 3.092063 3.4587977 3.092063 10 P 0
L 3.4265355 3.6794882 3.4265355 3.7188582 5 P 0
L 3.4265355 3.6794882 3.444252 3.6794882 5 P 0
L 3.4468619 2.6945703 3.4468619 2.7245606 15 P 0 ;0,1=32,2=0.000000
L 3.4468619 2.7245606 3.4618571 2.7245606 15 P 0 ;0,1=32,2=0.000000
L 3.4568587 2.7045671 3.4668554 2.6945703 15 P 0 ;0,1=32,2=0.000000
L 3.4618571 2.7045671 3.4468619 2.7045671 15 P 0 ;0,1=32,2=0.000000
L 3.4618571 2.7245606 3.4668554 2.7195622 15 P 0 ;0,1=32,2=0.000000
L 3.4633449 3.7975751 3.4933352 3.7975751 15 P 0 ;0,1=96,2=90.000000
L 3.4633449 3.8125703 3.4633449 3.7975751 15 P 0 ;0,1=96,2=90.000000
L 3.4633449 3.8325638 3.4633449 3.8425606 15 P 0 ;0,1=96,2=90.000000
L 3.4633449 3.8425606 3.4683433 3.8475589 15 P 0 ;0,1=96,2=90.000000
L 3.4668554 2.7095655 3.4618571 2.7045671 15 P 0 ;0,1=32,2=0.000000
L 3.4668554 2.7195622 3.4668554 2.7095655 15 P 0 ;0,1=32,2=0.000000
L 3.4683433 3.8175686 3.4633449 3.8125703 15 P 0 ;0,1=96,2=90.000000
L 3.4683433 3.8275654 3.4633449 3.8325638 15 P 0 ;0,1=96,2=90.000000
L 3.4683433 3.8475589 3.4733417 3.8475589 15 P 0 ;0,1=96,2=90.000000
L 3.4733417 3.8275654 3.4683433 3.8275654 15 P 0 ;0,1=96,2=90.000000
L 3.4733417 3.8475589 3.47834 3.8425606 15 P 0 ;0,1=96,2=90.000000
L 3.4768522 2.7095655 3.4968457 2.7095655 15 P 0 ;0,1=32,2=0.000000
L 3.47834 3.8325638 3.4733417 3.8275654 15 P 0 ;0,1=96,2=90.000000
L 3.47834 3.8325638 3.47834 3.8425606 15 P 0 ;0,1=96,2=90.000000
L 3.47834 3.8425606 3.4833384 3.8475589 15 P 0 ;0,1=96,2=90.000000
L 3.4833384 3.8275654 3.47834 3.8325638 15 P 0 ;0,1=96,2=90.000000
L 3.4833384 3.8475589 3.4883368 3.8475589 15 P 0 ;0,1=96,2=90.000000
L 3.4883368 3.8175686 3.4683433 3.8175686 15 P 0 ;0,1=96,2=90.000000
L 3.4883368 3.8275654 3.4833384 3.8275654 15 P 0 ;0,1=96,2=90.000000
L 3.4883368 3.8475589 3.4933352 3.8425606 15 P 0 ;0,1=96,2=90.000000
L 3.4918474 2.6945703 3.4918474 2.7245606 15 P 0 ;0,1=32,2=0.000000
L 3.4918474 2.7245606 3.4768522 2.7095655 15 P 0 ;0,1=32,2=0.000000
L 3.4930025 1.282233 3.4930025 1.308493 13 P 0
L 3.4930025 1.282233 3.5166225 1.282233 13 P 0
L 3.4930025 2.098493 3.4930025 2.124753 13 P 0
L 3.4930025 2.124753 3.5166225 2.124753 13 P 0
L 3.4933352 3.7975751 3.4933352 3.8125703 15 P 0 ;0,1=96,2=90.000000
L 3.4933352 3.8125703 3.4883368 3.8175686 15 P 0 ;0,1=96,2=90.000000
L 3.4933352 3.8325638 3.4883368 3.8275654 15 P 0 ;0,1=96,2=90.000000
L 3.4933352 3.8425606 3.4933352 3.8325638 15 P 0 ;0,1=96,2=90.000000
L 3.4948619 0.7135687 3.4998603 0.7085703 15 P 0 ;0,1=108,2=0.000000
L 3.4948619 0.7335622 3.4948619 0.7135687 15 P 0 ;0,1=108,2=0.000000
L 3.4954331 3.6794882 3.5131496 3.6794882 5 P 0
L 3.4998603 0.7085703 3.5098571 0.7085703 15 P 0 ;0,1=108,2=0.000000
L 3.4998603 0.7385606 3.4948619 0.7335622 15 P 0 ;0,1=108,2=0.000000
L 3.5048425 2.777378 3.5048425 2.816748 8 P 0
L 3.5068425 2.6945703 3.526836 2.7145638 15 P 0 ;0,1=32,2=0.000000
L 3.5084749 3.438504 3.6283859 3.438504 10 P 0
L 3.5098571 0.7085703 3.5148554 0.7135687 15 P 0 ;0,1=108,2=0.000000
L 3.5098571 0.7385606 3.4998603 0.7385606 15 P 0 ;0,1=108,2=0.000000
L 3.5118409 2.7245606 3.5068425 2.7195622 15 P 0 ;0,1=32,2=0.000000
L 3.5131496 3.6794882 3.5131496 3.7188582 5 P 0
L 3.5148554 0.7335622 3.5098571 0.7385606 15 P 0 ;0,1=108,2=0.000000
L 3.5166225 1.260583 3.5166225 1.282233 13 P 0
L 3.5166225 1.260583 3.6268625 1.260583 13 P 0
L 3.5166225 2.124753 3.5166225 2.146403 13 P 0
L 3.5166225 2.146403 3.6268625 2.146403 13 P 0
L 3.5218377 2.7245606 3.5118409 2.7245606 15 P 0 ;0,1=32,2=0.000000
L 3.5248522 0.7135687 3.5298506 0.7085703 15 P 0 ;0,1=108,2=0.000000
L 3.5248522 0.7235655 3.5248522 0.7135687 15 P 0 ;0,1=108,2=0.000000
L 3.526836 2.6945703 3.5068425 2.6945703 15 P 0 ;0,1=32,2=0.000000
L 3.526836 2.7145638 3.526836 2.7195622 15 P 0 ;0,1=32,2=0.000000
L 3.526836 2.7195622 3.5218377 2.7245606 15 P 0 ;0,1=32,2=0.000000
L 3.5298506 0.7085703 3.5398474 0.7085703 15 P 0 ;0,1=108,2=0.000000
L 3.534849 0.7335622 3.5248522 0.7235655 15 P 0 ;0,1=108,2=0.000000
L 3.5398474 0.7085703 3.5448457 0.7135687 15 P 0 ;0,1=108,2=0.000000
L 3.5398474 0.7235655 3.5248522 0.7235655 15 P 0 ;0,1=108,2=0.000000
L 3.5434325 2.184543 3.563426 2.184543 4 P 0 ;0,1=0,2=0.000000
L 3.5448425 2.852063 3.5648425 2.852063 10 P 0
L 3.5448425 3.092063 3.5648425 3.092063 10 P 0
L 3.5448425 3.9036221 3.5448425 4.2685827 5 P 0
L 3.5448457 0.7135687 3.5448457 0.7185671 15 P 0 ;0,1=108,2=0.000000
L 3.5448457 0.7185671 3.5398474 0.7235655 15 P 0 ;0,1=108,2=0.000000
L 3.5448457 0.7385606 3.534849 0.7335622 15 P 0 ;0,1=108,2=0.000000
L 3.5534293 2.184543 3.5534293 2.2445236 4 P 0 ;0,1=0,2=0.000000
L 3.5534293 2.2445236 3.5434325 2.2345268 4 P 0 ;0,1=0,2=0.000000
L 3.5548425 0.7085703 3.574836 0.7285638 15 P 0 ;0,1=108,2=0.000000
L 3.5598409 0.7385606 3.5548425 0.7335622 15 P 0 ;0,1=108,2=0.000000
L 3.563426 2.184543 3.5534293 2.184543 4 P 0 ;0,1=0,2=0.000000
L 3.5648425 2.852063 3.5648425 2.872063 10 P 0
L 3.5648425 3.072063 3.5648425 3.092063 10 P 0
L 3.5698377 0.7385606 3.5598409 0.7385606 15 P 0 ;0,1=108,2=0.000000
L 3.574836 0.7085703 3.5548425 0.7085703 15 P 0 ;0,1=108,2=0.000000
L 3.574836 0.7285638 3.574836 0.7335622 15 P 0 ;0,1=108,2=0.000000
L 3.574836 0.7335622 3.5698377 0.7385606 15 P 0 ;0,1=108,2=0.000000
L 3.5783449 3.5718312 3.6083352 3.5718312 15 P 0 ;0,1=94,2=90.000000
L 3.5783449 3.5868264 3.5783449 3.5718312 15 P 0 ;0,1=94,2=90.000000
L 3.5783449 3.6068199 3.5833433 3.6018215 15 P 0 ;0,1=94,2=90.000000
L 3.5783449 3.6318118 3.5783449 3.6418086 15 P 0 ;0,1=94,2=90.000000
L 3.5783449 3.6418086 3.5833433 3.6468069 15 P 0 ;0,1=94,2=90.000000
L 3.5833433 3.5918247 3.5783449 3.5868264 15 P 0 ;0,1=94,2=90.000000
L 3.5833433 3.6268134 3.5783449 3.6318118 15 P 0 ;0,1=94,2=90.000000
L 3.5833433 3.6468069 3.6033368 3.6468069 15 P 0 ;0,1=94,2=90.000000
L 3.5886107 2.8645687 3.5936091 2.8595703 15 P 0 ;0,1=38,2=0.000000
L 3.5886107 2.8895606 3.5886107 2.8645687 15 P 0 ;0,1=38,2=0.000000
L 3.5890158 3.1629134 3.6283859 3.1629134 10 P 0
L 3.5903449 3.9615751 3.6203352 3.9615751 15 P 0 ;0,1=95,2=90.000000
L 3.5903449 3.9765703 3.5903449 3.9615751 15 P 0 ;0,1=95,2=90.000000
L 3.5903449 3.9965638 3.5953433 3.9915654 15 P 0 ;0,1=95,2=90.000000
L 3.5903449 4.0065606 3.5903449 3.9965638 15 P 0 ;0,1=95,2=90.000000
L 3.5936091 2.8595703 3.6036059 2.8595703 15 P 0 ;0,1=38,2=0.000000
L 3.5953433 3.9815686 3.5903449 3.9765703 15 P 0 ;0,1=95,2=90.000000
L 3.5953433 3.9915654 3.6003417 3.9915654 15 P 0 ;0,1=95,2=90.000000
L 3.5953433 4.0115589 3.5903449 4.0065606 15 P 0 ;0,1=95,2=90.000000
L 3.6003417 3.9915654 3.60534 3.9965638 15 P 0 ;0,1=95,2=90.000000
L 3.6033368 3.5918247 3.5833433 3.5918247 15 P 0 ;0,1=94,2=90.000000
L 3.6033368 3.6268134 3.5833433 3.6268134 15 P 0 ;0,1=94,2=90.000000
L 3.6033368 3.6468069 3.6083352 3.6418086 15 P 0 ;0,1=94,2=90.000000
L 3.6036059 2.8595703 3.6086042 2.8645687 15 P 0 ;0,1=38,2=0.000000
L 3.60534 3.9965638 3.60534 4.0115589 15 P 0 ;0,1=95,2=90.000000
L 3.6083352 3.5718312 3.6083352 3.5868264 15 P 0 ;0,1=94,2=90.000000
L 3.6083352 3.5868264 3.6033368 3.5918247 15 P 0 ;0,1=94,2=90.000000
L 3.6083352 3.6018215 3.6083352 3.6118183 15 P 0 ;0,1=94,2=90.000000
L 3.6083352 3.6068199 3.5783449 3.6068199 15 P 0 ;0,1=94,2=90.000000
L 3.6083352 3.6118183 3.6083352 3.6068199 15 P 0 ;0,1=94,2=90.000000
L 3.6083352 3.6318118 3.6033368 3.6268134 15 P 0 ;0,1=94,2=90.000000
L 3.6083352 3.6418086 3.6083352 3.6318118 15 P 0 ;0,1=94,2=90.000000
L 3.6086042 2.8645687 3.6086042 2.8895606 15 P 0 ;0,1=38,2=0.000000
L 3.6153368 3.9815686 3.5953433 3.9815686 15 P 0 ;0,1=95,2=90.000000
L 3.6153368 3.9915654 3.6203352 3.9965638 15 P 0 ;0,1=95,2=90.000000
L 3.6153368 4.0115589 3.5953433 4.0115589 15 P 0 ;0,1=95,2=90.000000
L 3.618601 2.8595703 3.6285978 2.8595703 15 P 0 ;0,1=38,2=0.000000
L 3.6203352 3.9615751 3.6203352 3.9765703 15 P 0 ;0,1=95,2=90.000000
L 3.6203352 3.9765703 3.6153368 3.9815686 15 P 0 ;0,1=95,2=90.000000
L 3.6203352 3.9965638 3.6203352 4.0065606 15 P 0 ;0,1=95,2=90.000000
L 3.6203352 4.0065606 3.6153368 4.0115589 15 P 0 ;0,1=95,2=90.000000
L 3.6235994 2.8595703 3.6235994 2.8895606 15 P 0 ;0,1=38,2=0.000000
L 3.6235994 2.8895606 3.618601 2.8845622 15 P 0 ;0,1=38,2=0.000000
L 3.6268625 1.260583 3.6268625 1.282233 13 P 0
L 3.6268625 1.282233 3.6504825 1.282233 13 P 0
L 3.6268625 2.124753 3.6268625 2.146403 13 P 0
L 3.6268625 2.124753 3.6504825 2.124753 13 P 0
L 3.6283859 3.1629134 3.6283859 3.2022835 10 P 0
L 3.6283859 3.3267535 3.6283859 3.438504 10 P 0
L 3.6285978 2.8595703 3.6235994 2.8595703 15 P 0 ;0,1=38,2=0.000000
L 3.6318619 3.8905703 3.6318619 3.9205606 15 P 0 ;0,1=60,2=0.000000
L 3.6318619 3.9205606 3.6468571 3.9205606 15 P 0 ;0,1=60,2=0.000000
L 3.6418587 3.9005671 3.6518554 3.8905703 15 P 0 ;0,1=60,2=0.000000
L 3.6435929 2.8845622 3.6485913 2.8895606 15 P 0 ;0,1=38,2=0.000000
L 3.6468571 3.9005671 3.6318619 3.9005671 15 P 0 ;0,1=60,2=0.000000
L 3.6468571 3.9205606 3.6518554 3.9155622 15 P 0 ;0,1=60,2=0.000000
L 3.6485913 2.8595703 3.6435929 2.8645687 15 P 0 ;0,1=38,2=0.000000
L 3.6485913 2.8895606 3.6585881 2.8895606 15 P 0 ;0,1=38,2=0.000000
L 3.6504825 1.282233 3.6504825 1.308493 13 P 0
L 3.6504825 2.098493 3.6504825 2.124753 13 P 0
L 3.6518554 3.9055655 3.6468571 3.9005671 15 P 0 ;0,1=60,2=0.000000
L 3.6518554 3.9155622 3.6518554 3.9055655 15 P 0 ;0,1=60,2=0.000000
L 3.6535897 2.8745655 3.6585881 2.8745655 15 P 0 ;0,1=38,2=0.000000
L 3.6558425 3.123063 3.6558425 3.183063 8 P 0
L 3.6585881 2.8595703 3.6485913 2.8595703 15 P 0 ;0,1=38,2=0.000000
L 3.6585881 2.8745655 3.6535897 2.8745655 15 P 0 ;0,1=38,2=0.000000
L 3.6585881 2.8745655 3.6635864 2.8695671 15 P 0 ;0,1=38,2=0.000000
L 3.6585881 2.8895606 3.6635864 2.8845622 15 P 0 ;0,1=38,2=0.000000
L 3.6608425 3.273063 3.6608425 3.323063 8 P 0
L 3.6618522 3.8905703 3.6818457 3.9105638 15 P 0 ;0,1=60,2=0.000000
L 3.6635864 2.8645687 3.6585881 2.8595703 15 P 0 ;0,1=38,2=0.000000
L 3.6635864 2.8695671 3.6635864 2.8645687 15 P 0 ;0,1=38,2=0.000000
L 3.6635864 2.8795638 3.6585881 2.8745655 15 P 0 ;0,1=38,2=0.000000
L 3.6635864 2.8845622 3.6635864 2.8795638 15 P 0 ;0,1=38,2=0.000000
L 3.6648425 0.688063 3.7248425 0.688063 8 P 0
L 3.6648425 0.764063 3.7248425 0.764063 8 P 0
L 3.6658425 3.3950614 3.6708409 3.390063 15 P 0 ;0,1=104,2=0.000000
L 3.6658425 3.4150549 3.6658425 3.3950614 15 P 0 ;0,1=104,2=0.000000
L 3.6668506 3.9205606 3.6618522 3.9155622 15 P 0 ;0,1=60,2=0.000000
L 3.6708409 3.390063 3.6808377 3.390063 15 P 0 ;0,1=104,2=0.000000
L 3.6708409 3.4200533 3.6658425 3.4150549 15 P 0 ;0,1=104,2=0.000000
L 3.6753449 3.6040824 3.6753449 3.6190776 15 P 0 ;0,1=59,2=90.000000
L 3.6753449 3.6190776 3.6803433 3.6240759 15 P 0 ;0,1=59,2=90.000000
L 3.6753449 3.6390711 3.6803433 3.6340727 15 P 0 ;0,1=59,2=90.000000
L 3.6753449 3.6490679 3.6753449 3.6390711 15 P 0 ;0,1=59,2=90.000000
L 3.6753449 3.6840565 3.6803433 3.6740598 15 P 0 ;0,1=59,2=90.000000
L 3.6768474 3.9205606 3.6668506 3.9205606 15 P 0 ;0,1=60,2=0.000000
L 3.6803433 3.6240759 3.69034 3.6240759 15 P 0 ;0,1=59,2=90.000000
L 3.6803433 3.6540662 3.6753449 3.6490679 15 P 0 ;0,1=59,2=90.000000
L 3.6803433 3.6740598 3.69034 3.664063 15 P 0 ;0,1=59,2=90.000000
L 3.6808377 3.390063 3.685836 3.3950614 15 P 0 ;0,1=104,2=0.000000
L 3.6808377 3.4200533 3.6708409 3.4200533 15 P 0 ;0,1=104,2=0.000000
L 3.6818457 3.8905703 3.6618522 3.8905703 15 P 0 ;0,1=60,2=0.000000
L 3.6818457 3.9105638 3.6818457 3.9155622 15 P 0 ;0,1=60,2=0.000000
L 3.6818457 3.9155622 3.6768474 3.9205606 15 P 0 ;0,1=60,2=0.000000
L 3.6844488 4.0987008 3.6844488 4.1737008 8 P 0
L 3.6853417 3.6540662 3.6803433 3.6540662 15 P 0 ;0,1=59,2=90.000000
L 3.685836 3.4150549 3.6808377 3.4200533 15 P 0 ;0,1=104,2=0.000000
L 3.69034 3.6240759 3.6953384 3.6190776 15 P 0 ;0,1=59,2=90.000000
L 3.69034 3.664063 3.7003368 3.664063 15 P 0 ;0,1=59,2=90.000000
L 3.69034 3.6790582 3.69034 3.664063 15 P 0 ;0,1=59,2=90.000000
L 3.6918425 3.9055655 3.7018393 3.9105638 15 P 0 ;0,1=60,2=0.000000
L 3.6918425 3.9205606 3.6918425 3.9055655 15 P 0 ;0,1=60,2=0.000000
L 3.6953384 3.6140792 3.7053352 3.6240759 15 P 0 ;0,1=59,2=90.000000
L 3.6953384 3.6190776 3.6953384 3.6040824 15 P 0 ;0,1=59,2=90.000000
L 3.6953384 3.6840565 3.69034 3.6790582 15 P 0 ;0,1=59,2=90.000000
L 3.6958328 3.3950614 3.7008312 3.390063 15 P 0 ;0,1=104,2=0.000000
L 3.6958328 3.4050582 3.6958328 3.3950614 15 P 0 ;0,1=104,2=0.000000
L 3.6968409 3.8905703 3.6918425 3.8955687 15 P 0 ;0,1=60,2=0.000000
L 3.7003368 3.664063 3.7053352 3.6690614 15 P 0 ;0,1=59,2=90.000000
L 3.7003368 3.6840565 3.6953384 3.6840565 15 P 0 ;0,1=59,2=90.000000
L 3.7008312 3.390063 3.710828 3.390063 15 P 0 ;0,1=104,2=0.000000
L 3.7018393 3.9105638 3.7068377 3.9105638 15 P 0 ;0,1=60,2=0.000000
L 3.7053352 3.6040824 3.6753449 3.6040824 15 P 0 ;0,1=59,2=90.000000
L 3.7053352 3.6340727 3.6853417 3.6540662 15 P 0 ;0,1=59,2=90.000000
L 3.7053352 3.6540662 3.7053352 3.6340727 15 P 0 ;0,1=59,2=90.000000
L 3.7053352 3.6690614 3.7053352 3.6790582 15 P 0 ;0,1=59,2=90.000000
L 3.7053352 3.6790582 3.7003368 3.6840565 15 P 0 ;0,1=59,2=90.000000
L 3.7058296 3.4150549 3.6958328 3.4050582 15 P 0 ;0,1=104,2=0.000000
L 3.7068377 3.8905703 3.6968409 3.8905703 15 P 0 ;0,1=60,2=0.000000
L 3.7068377 3.9105638 3.711836 3.9055655 15 P 0 ;0,1=60,2=0.000000
L 3.710828 3.390063 3.7158263 3.3950614 15 P 0 ;0,1=104,2=0.000000
L 3.710828 3.4050582 3.6958328 3.4050582 15 P 0 ;0,1=104,2=0.000000
L 3.711836 3.8955687 3.7068377 3.8905703 15 P 0 ;0,1=60,2=0.000000
L 3.711836 3.9055655 3.711836 3.8955687 15 P 0 ;0,1=60,2=0.000000
L 3.711836 3.9205606 3.6918425 3.9205606 15 P 0 ;0,1=60,2=0.000000
L 3.7158263 3.3950614 3.7158263 3.4000598 15 P 0 ;0,1=104,2=0.000000
L 3.7158263 3.4000598 3.710828 3.4050582 15 P 0 ;0,1=104,2=0.000000
L 3.7158263 3.4200533 3.7058296 3.4150549 15 P 0 ;0,1=104,2=0.000000
L 3.7161925 0.815533 3.7161925 2.587193 12 P 0
L 3.7168425 3.273063 3.7168425 3.323063 8 P 0
L 3.7258231 3.3950614 3.7258231 3.390063 15 P 0 ;0,1=104,2=0.000000
L 3.7258231 3.4200533 3.7458166 3.4200533 15 P 0 ;0,1=104,2=0.000000
L 3.7318425 3.123063 3.7318425 3.183063 8 P 0
L 3.7458166 3.4150549 3.7258231 3.3950614 15 P 0 ;0,1=104,2=0.000000
L 3.7458166 3.4200533 3.7458166 3.4150549 15 P 0 ;0,1=104,2=0.000000
L 3.7528619 3.1095687 3.7578603 3.1045703 15 P 0 ;0,1=106,2=0.000000
L 3.7528619 3.1295622 3.7528619 3.1095687 15 P 0 ;0,1=106,2=0.000000
L 3.7578603 3.1045703 3.7678571 3.1045703 15 P 0 ;0,1=106,2=0.000000
L 3.7578603 3.1345606 3.7528619 3.1295622 15 P 0 ;0,1=106,2=0.000000
L 3.7608619 0.6185687 3.7658603 0.6135703 15 P 0 ;0,1=107,2=0.000000
L 3.7608619 0.6385622 3.7608619 0.6185687 15 P 0 ;0,1=107,2=0.000000
L 3.7658603 0.6135703 3.7758571 0.6135703 15 P 0 ;0,1=107,2=0.000000
L 3.7658603 0.6435606 3.7608619 0.6385622 15 P 0 ;0,1=107,2=0.000000
L 3.7678571 3.1045703 3.7728554 3.1095687 15 P 0 ;0,1=106,2=0.000000
L 3.7678571 3.1345606 3.7578603 3.1345606 15 P 0 ;0,1=106,2=0.000000
L 3.7678619 2.7985687 3.7728603 2.7935703 15 P 0 ;0,1=17,2=0.000000
L 3.7678619 2.8185622 3.7678619 2.7985687 15 P 0 ;0,1=17,2=0.000000
L 3.7728554 3.1295622 3.7678571 3.1345606 15 P 0 ;0,1=106,2=0.000000
L 3.7728603 2.7935703 3.7828571 2.7935703 15 P 0 ;0,1=17,2=0.000000
L 3.7728603 2.8235606 3.7678619 2.8185622 15 P 0 ;0,1=17,2=0.000000
L 3.7758571 0.6135703 3.7808554 0.6185687 15 P 0 ;0,1=107,2=0.000000
L 3.7758571 0.6435606 3.7658603 0.6435606 15 P 0 ;0,1=107,2=0.000000
L 3.7789398 0.6898312 3.7789398 2.6898312 4 P 0
L 3.7789398 0.6898312 5.7789398 0.6898312 4 P 0
L 3.7789398 2.6898312 5.7789398 2.6898312 4 P 0
L 3.7808554 0.6385622 3.7758571 0.6435606 15 P 0 ;0,1=107,2=0.000000
L 3.7828522 3.1095687 3.7878506 3.1045703 15 P 0 ;0,1=106,2=0.000000
L 3.7828522 3.1195655 3.7828522 3.1095687 15 P 0 ;0,1=106,2=0.000000
L 3.7828571 2.7935703 3.7878554 2.7985687 15 P 0 ;0,1=17,2=0.000000
L 3.7828571 2.8235606 3.7728603 2.8235606 15 P 0 ;0,1=17,2=0.000000
L 3.7868619 3.2905687 3.7918603 3.2855703 15 P 0 ;0,1=105,2=0.000000
L 3.7868619 3.3105622 3.7868619 3.2905687 15 P 0 ;0,1=105,2=0.000000
L 3.7878506 3.1045703 3.7978474 3.1045703 15 P 0 ;0,1=106,2=0.000000
L 3.7878554 2.8185622 3.7828571 2.8235606 15 P 0 ;0,1=17,2=0.000000
L 3.7908522 0.6185687 3.7958506 0.6135703 15 P 0 ;0,1=107,2=0.000000
L 3.7908522 0.6285655 3.7908522 0.6185687 15 P 0 ;0,1=107,2=0.000000
L 3.7918603 3.2855703 3.8018571 3.2855703 15 P 0 ;0,1=105,2=0.000000
L 3.7918603 3.3155606 3.7868619 3.3105622 15 P 0 ;0,1=105,2=0.000000
L 3.792849 3.1295622 3.7828522 3.1195655 15 P 0 ;0,1=106,2=0.000000
L 3.7958506 0.6135703 3.8058474 0.6135703 15 P 0 ;0,1=107,2=0.000000
L 3.7978474 3.1045703 3.8028457 3.1095687 15 P 0 ;0,1=106,2=0.000000
L 3.7978474 3.1195655 3.7828522 3.1195655 15 P 0 ;0,1=106,2=0.000000
L 3.7978522 2.7985687 3.7978522 2.7935703 15 P 0 ;0,1=17,2=0.000000
L 3.7978522 2.8235606 3.8178457 2.8235606 15 P 0 ;0,1=17,2=0.000000
L 3.800849 0.6385622 3.7908522 0.6285655 15 P 0 ;0,1=107,2=0.000000
L 3.8018571 3.2855703 3.8068554 3.2905687 15 P 0 ;0,1=105,2=0.000000
L 3.8018571 3.3155606 3.7918603 3.3155606 15 P 0 ;0,1=105,2=0.000000
L 3.8028457 3.1095687 3.8028457 3.1145671 15 P 0 ;0,1=106,2=0.000000
L 3.8028457 3.1145671 3.7978474 3.1195655 15 P 0 ;0,1=106,2=0.000000
L 3.8028457 3.1345606 3.792849 3.1295622 15 P 0 ;0,1=106,2=0.000000
L 3.8058474 0.6135703 3.8108457 0.6185687 15 P 0 ;0,1=107,2=0.000000
L 3.8058474 0.6285655 3.7908522 0.6285655 15 P 0 ;0,1=107,2=0.000000
L 3.8068554 3.3105622 3.8018571 3.3155606 15 P 0 ;0,1=105,2=0.000000
L 3.8108457 0.6185687 3.8108457 0.6235671 15 P 0 ;0,1=107,2=0.000000
L 3.8108457 0.6235671 3.8058474 0.6285655 15 P 0 ;0,1=107,2=0.000000
L 3.8108457 0.6435606 3.800849 0.6385622 15 P 0 ;0,1=107,2=0.000000
L 3.8128425 3.1195655 3.8228393 3.1245638 15 P 0 ;0,1=106,2=0.000000
L 3.8128425 3.1345606 3.8128425 3.1195655 15 P 0 ;0,1=106,2=0.000000
L 3.8168503 3.6726378 3.8168503 3.8694882 5 P 0
L 3.8168503 3.6726378 3.9428346 3.6726378 5 P 0
L 3.8168503 3.8694882 3.9428346 3.8694882 5 P 0
L 3.8168522 3.2905687 3.8218506 3.2855703 15 P 0 ;0,1=105,2=0.000000
L 3.8168522 3.3005655 3.8168522 3.2905687 15 P 0 ;0,1=105,2=0.000000
L 3.8178409 3.1045703 3.8128425 3.1095687 15 P 0 ;0,1=106,2=0.000000
L 3.8178457 2.8185622 3.7978522 2.7985687 15 P 0 ;0,1=17,2=0.000000
L 3.8178457 2.8235606 3.8178457 2.8185622 15 P 0 ;0,1=17,2=0.000000
L 3.8208425 0.6385622 3.8258409 0.6435606 15 P 0 ;0,1=107,2=0.000000
L 3.8218506 3.2855703 3.8318474 3.2855703 15 P 0 ;0,1=105,2=0.000000
L 3.8228393 3.1245638 3.8278377 3.1245638 15 P 0 ;0,1=106,2=0.000000
L 3.8258409 0.6135703 3.8208425 0.6185687 15 P 0 ;0,1=107,2=0.000000
L 3.8258409 0.6435606 3.8358377 0.6435606 15 P 0 ;0,1=107,2=0.000000
L 3.826849 3.3105622 3.8168522 3.3005655 15 P 0 ;0,1=105,2=0.000000
L 3.8278377 3.1045703 3.8178409 3.1045703 15 P 0 ;0,1=106,2=0.000000
L 3.8278377 3.1245638 3.832836 3.1195655 15 P 0 ;0,1=106,2=0.000000
L 3.8278425 2.8085655 3.847836 2.8085655 15 P 0 ;0,1=17,2=0.000000
L 3.8308393 0.6285655 3.8358377 0.6285655 15 P 0 ;0,1=107,2=0.000000
L 3.8318474 3.2855703 3.8368457 3.2905687 15 P 0 ;0,1=105,2=0.000000
L 3.8318474 3.3005655 3.8168522 3.3005655 15 P 0 ;0,1=105,2=0.000000
L 3.832836 3.1095687 3.8278377 3.1045703 15 P 0 ;0,1=106,2=0.000000
L 3.832836 3.1195655 3.832836 3.1095687 15 P 0 ;0,1=106,2=0.000000
L 3.832836 3.1345606 3.8128425 3.1345606 15 P 0 ;0,1=106,2=0.000000
L 3.8358377 0.6135703 3.8258409 0.6135703 15 P 0 ;0,1=107,2=0.000000
L 3.8358377 0.6285655 3.8308393 0.6285655 15 P 0 ;0,1=107,2=0.000000
L 3.8358377 0.6285655 3.840836 0.6235671 15 P 0 ;0,1=107,2=0.000000
L 3.8358377 0.6435606 3.840836 0.6385622 15 P 0 ;0,1=107,2=0.000000
L 3.8368457 3.2905687 3.8368457 3.2955671 15 P 0 ;0,1=105,2=0.000000
L 3.8368457 3.2955671 3.8318474 3.3005655 15 P 0 ;0,1=105,2=0.000000
L 3.8368457 3.3155606 3.826849 3.3105622 15 P 0 ;0,1=105,2=0.000000
L 3.840836 0.6185687 3.8358377 0.6135703 15 P 0 ;0,1=107,2=0.000000
L 3.840836 0.6235671 3.840836 0.6185687 15 P 0 ;0,1=107,2=0.000000
L 3.840836 0.6335638 3.8358377 0.6285655 15 P 0 ;0,1=107,2=0.000000
L 3.840836 0.6385622 3.840836 0.6335638 15 P 0 ;0,1=107,2=0.000000
L 3.8413546 3.6085687 3.846353 3.6035703 15 P 0 ;0,1=43,2=0.000000
L 3.8413546 3.6335606 3.8413546 3.6085687 15 P 0 ;0,1=43,2=0.000000
L 3.8428377 2.7935703 3.8428377 2.8235606 15 P 0 ;0,1=17,2=0.000000
L 3.8428377 2.8235606 3.8278425 2.8085655 15 P 0 ;0,1=17,2=0.000000
L 3.846353 3.6035703 3.8563498 3.6035703 15 P 0 ;0,1=43,2=0.000000
L 3.8468425 3.2905687 3.8518409 3.2855703 15 P 0 ;0,1=105,2=0.000000
L 3.8468425 3.3005655 3.8468425 3.2905687 15 P 0 ;0,1=105,2=0.000000
L 3.8518409 3.2855703 3.8618377 3.2855703 15 P 0 ;0,1=105,2=0.000000
L 3.8563498 3.6035703 3.8613481 3.6085687 15 P 0 ;0,1=43,2=0.000000
L 3.8568393 3.3105622 3.8468425 3.3005655 15 P 0 ;0,1=105,2=0.000000
L 3.8613481 3.6085687 3.8613481 3.6335606 15 P 0 ;0,1=43,2=0.000000
L 3.8618377 3.2855703 3.866836 3.2905687 15 P 0 ;0,1=105,2=0.000000
L 3.8618377 3.3005655 3.8468425 3.3005655 15 P 0 ;0,1=105,2=0.000000
L 3.866836 3.2905687 3.866836 3.2955671 15 P 0 ;0,1=105,2=0.000000
L 3.866836 3.2955671 3.8618377 3.3005655 15 P 0 ;0,1=105,2=0.000000
L 3.866836 3.3155606 3.8568393 3.3105622 15 P 0 ;0,1=105,2=0.000000
L 3.8713449 3.6085687 3.8763433 3.6035703 15 P 0 ;0,1=43,2=0.000000
L 3.8713449 3.6185655 3.8713449 3.6085687 15 P 0 ;0,1=43,2=0.000000
L 3.8763433 3.6035703 3.8863401 3.6035703 15 P 0 ;0,1=43,2=0.000000
L 3.8813417 3.6285622 3.8713449 3.6185655 15 P 0 ;0,1=43,2=0.000000
L 3.8863401 3.6035703 3.8913384 3.6085687 15 P 0 ;0,1=43,2=0.000000
L 3.8863401 3.6185655 3.8713449 3.6185655 15 P 0 ;0,1=43,2=0.000000
L 3.8913384 3.6085687 3.8913384 3.6135671 15 P 0 ;0,1=43,2=0.000000
L 3.8913384 3.6135671 3.8863401 3.6185655 15 P 0 ;0,1=43,2=0.000000
L 3.8913384 3.6335606 3.8813417 3.6285622 15 P 0 ;0,1=43,2=0.000000
L 3.9218425 2.786063 3.9218425 2.846063 8 P 0
L 3.9428346 3.6726378 3.9428346 3.8694882 5 P 0
L 3.9522931 3.1939748 3.9572915 3.1889764 15 P 0 ;0,1=19,2=90.000000
L 3.9522931 3.2039716 3.9522931 3.1939748 15 P 0 ;0,1=19,2=90.000000
L 3.9522931 3.2189667 3.9522931 3.2389602 15 P 0 ;0,1=19,2=90.000000
L 3.9522931 3.2389602 3.9572915 3.2389602 15 P 0 ;0,1=19,2=90.000000
L 3.9522931 3.2689505 3.9572915 3.2589538 15 P 0 ;0,1=19,2=90.000000
L 3.9572915 3.1889764 3.977285 3.1889764 15 P 0 ;0,1=19,2=90.000000
L 3.9572915 3.2089699 3.9522931 3.2039716 15 P 0 ;0,1=19,2=90.000000
L 3.9572915 3.2389602 3.977285 3.2189667 15 P 0 ;0,1=19,2=90.000000
L 3.9572915 3.2589538 3.9672882 3.248957 15 P 0 ;0,1=19,2=90.000000
L 3.9644553 3.9737008 3.974452 3.9737008 4 P 0 ;0,1=0,2=180.000000
L 3.9672882 3.248957 3.977285 3.248957 15 P 0 ;0,1=19,2=90.000000
L 3.9672882 3.2639522 3.9672882 3.248957 15 P 0 ;0,1=19,2=90.000000
L 3.9722866 3.2689505 3.9672882 3.2639522 15 P 0 ;0,1=19,2=90.000000
L 3.974452 3.9137202 3.9844488 3.923717 4 P 0 ;0,1=0,2=180.000000
L 3.974452 3.9737008 3.974452 3.9137202 4 P 0 ;0,1=0,2=180.000000
L 3.977285 3.1889764 3.9822834 3.1939748 15 P 0 ;0,1=19,2=90.000000
L 3.977285 3.2189667 3.9822834 3.2189667 15 P 0 ;0,1=19,2=90.000000
L 3.977285 3.248957 3.9822834 3.2539554 15 P 0 ;0,1=19,2=90.000000
L 3.977285 3.2689505 3.9722866 3.2689505 15 P 0 ;0,1=19,2=90.000000
L 3.9818619 2.9165687 3.9868603 2.9115703 15 P 0 ;0,1=18,2=0.000000
L 3.9818619 2.9365622 3.9818619 2.9165687 15 P 0 ;0,1=18,2=0.000000
L 3.9822834 3.1939748 3.9822834 3.2039716 15 P 0 ;0,1=19,2=90.000000
L 3.9822834 3.2039716 3.977285 3.2089699 15 P 0 ;0,1=19,2=90.000000
L 3.9822834 3.2539554 3.9822834 3.2639522 15 P 0 ;0,1=19,2=90.000000
L 3.9822834 3.2639522 3.977285 3.2689505 15 P 0 ;0,1=19,2=90.000000
L 3.9844488 3.9737008 3.9644553 3.9737008 4 P 0 ;0,1=0,2=180.000000
L 3.9868603 2.9115703 3.9968571 2.9115703 15 P 0 ;0,1=18,2=0.000000
L 3.9868603 2.9415606 3.9818619 2.9365622 15 P 0 ;0,1=18,2=0.000000
L 3.9968571 2.9115703 4.0018554 2.9165687 15 P 0 ;0,1=18,2=0.000000
L 3.9968571 2.9415606 3.9868603 2.9415606 15 P 0 ;0,1=18,2=0.000000
L 3.9978425 2.786063 3.9978425 2.846063 8 P 0
L 4.0018554 2.9365622 3.9968571 2.9415606 15 P 0 ;0,1=18,2=0.000000
L 4.006427 3.1939748 4.0114254 3.1889764 15 P 0 ;0,1=20,2=90.000000
L 4.006427 3.2039716 4.006427 3.1939748 15 P 0 ;0,1=20,2=90.000000
L 4.006427 3.2189667 4.006427 3.2389602 15 P 0 ;0,1=20,2=90.000000
L 4.006427 3.2389602 4.0114254 3.2389602 15 P 0 ;0,1=20,2=90.000000
L 4.006427 3.248957 4.006427 3.2689505 15 P 0 ;0,1=20,2=90.000000
L 4.006427 3.2689505 4.0114254 3.2689505 15 P 0 ;0,1=20,2=90.000000
L 4.0114254 3.1889764 4.0314189 3.1889764 15 P 0 ;0,1=20,2=90.000000
L 4.0114254 3.2089699 4.006427 3.2039716 15 P 0 ;0,1=20,2=90.000000
L 4.0114254 3.2389602 4.0314189 3.2189667 15 P 0 ;0,1=20,2=90.000000
L 4.0114254 3.2689505 4.0314189 3.248957 15 P 0 ;0,1=20,2=90.000000
L 4.0118425 3.036063 4.0118425 3.086063 8 P 0
L 4.0118522 2.9165687 4.0118522 2.9115703 15 P 0 ;0,1=18,2=0.000000
L 4.0118522 2.9415606 4.0318457 2.9415606 15 P 0 ;0,1=18,2=0.000000
L 4.0268425 2.786063 4.0268425 2.846063 8 P 0
L 4.0314189 3.1889764 4.0364173 3.1939748 15 P 0 ;0,1=20,2=90.000000
L 4.0314189 3.2189667 4.0364173 3.2189667 15 P 0 ;0,1=20,2=90.000000
L 4.0314189 3.248957 4.0364173 3.248957 15 P 0 ;0,1=20,2=90.000000
L 4.0318457 2.9365622 4.0118522 2.9165687 15 P 0 ;0,1=18,2=0.000000
L 4.0318457 2.9415606 4.0318457 2.9365622 15 P 0 ;0,1=18,2=0.000000
L 4.0364173 3.1939748 4.0364173 3.2039716 15 P 0 ;0,1=20,2=90.000000
L 4.0364173 3.2039716 4.0314189 3.2089699 15 P 0 ;0,1=20,2=90.000000
L 4.0418425 2.9265655 4.0518393 2.9315638 15 P 0 ;0,1=18,2=0.000000
L 4.0418425 2.9415606 4.0418425 2.9265655 15 P 0 ;0,1=18,2=0.000000
L 4.0468409 2.9115703 4.0418425 2.9165687 15 P 0 ;0,1=18,2=0.000000
L 4.0518393 2.9315638 4.0568377 2.9315638 15 P 0 ;0,1=18,2=0.000000
L 4.0568377 2.9115703 4.0468409 2.9115703 15 P 0 ;0,1=18,2=0.000000
L 4.0568377 2.9315638 4.061836 2.9265655 15 P 0 ;0,1=18,2=0.000000
L 4.0594488 4.0987008 4.0594488 4.1737008 8 P 0
L 4.061836 2.9165687 4.0568377 2.9115703 15 P 0 ;0,1=18,2=0.000000
L 4.061836 2.9265655 4.061836 2.9165687 15 P 0 ;0,1=18,2=0.000000
L 4.061836 2.9415606 4.0418425 2.9415606 15 P 0 ;0,1=18,2=0.000000
L 4.0644979 3.1929905 4.0694963 3.1879921 15 P 0 ;0,1=21,2=90.000000
L 4.0644979 3.2029873 4.0644979 3.1929905 15 P 0 ;0,1=21,2=90.000000
L 4.0644979 3.2179824 4.0644979 3.2379759 15 P 0 ;0,1=21,2=90.000000
L 4.0644979 3.2379759 4.0694963 3.2379759 15 P 0 ;0,1=21,2=90.000000
L 4.0644979 3.2529711 4.0644979 3.2629679 15 P 0 ;0,1=21,2=90.000000
L 4.0644979 3.2629679 4.0694963 3.2679662 15 P 0 ;0,1=21,2=90.000000
L 4.0668425 3.776063 4.0668425 3.836063 8 P 0
L 4.0678425 3.036063 4.0678425 3.086063 8 P 0
L 4.0694963 3.1879921 4.0894898 3.1879921 15 P 0 ;0,1=21,2=90.000000
L 4.0694963 3.2079856 4.0644979 3.2029873 15 P 0 ;0,1=21,2=90.000000
L 4.0694963 3.2379759 4.0894898 3.2179824 15 P 0 ;0,1=21,2=90.000000
L 4.0694963 3.2479727 4.0644979 3.2529711 15 P 0 ;0,1=21,2=90.000000
L 4.0694963 3.2679662 4.0744947 3.2679662 15 P 0 ;0,1=21,2=90.000000
L 4.0744947 3.2479727 4.0694963 3.2479727 15 P 0 ;0,1=21,2=90.000000
L 4.0744947 3.2679662 4.079493 3.2629679 15 P 0 ;0,1=21,2=90.000000
L 4.079493 3.2529711 4.0744947 3.2479727 15 P 0 ;0,1=21,2=90.000000
L 4.079493 3.2529711 4.079493 3.2629679 15 P 0 ;0,1=21,2=90.000000
L 4.079493 3.2629679 4.0844914 3.2679662 15 P 0 ;0,1=21,2=90.000000
L 4.0844914 3.2479727 4.079493 3.2529711 15 P 0 ;0,1=21,2=90.000000
L 4.0844914 3.2679662 4.0894898 3.2679662 15 P 0 ;0,1=21,2=90.000000
L 4.0894898 3.1879921 4.0944882 3.1929905 15 P 0 ;0,1=21,2=90.000000
L 4.0894898 3.2179824 4.0944882 3.2179824 15 P 0 ;0,1=21,2=90.000000
L 4.0894898 3.2479727 4.0844914 3.2479727 15 P 0 ;0,1=21,2=90.000000
L 4.0894898 3.2679662 4.0944882 3.2629679 15 P 0 ;0,1=21,2=90.000000
L 4.0944882 3.1929905 4.0944882 3.2029873 15 P 0 ;0,1=21,2=90.000000
L 4.0944882 3.2029873 4.0894898 3.2079856 15 P 0 ;0,1=21,2=90.000000
L 4.0944882 3.2529711 4.0894898 3.2479727 15 P 0 ;0,1=21,2=90.000000
L 4.0944882 3.2629679 4.0944882 3.2529711 15 P 0 ;0,1=21,2=90.000000
L 4.1028425 2.786063 4.1028425 2.846063 8 P 0
L 4.1206002 3.1929905 4.1255986 3.1879921 15 P 0 ;0,1=22,2=90.000000
L 4.1206002 3.2029873 4.1206002 3.1929905 15 P 0 ;0,1=22,2=90.000000
L 4.1206002 3.2179824 4.1206002 3.2379759 15 P 0 ;0,1=22,2=90.000000
L 4.1206002 3.2379759 4.1255986 3.2379759 15 P 0 ;0,1=22,2=90.000000
L 4.1206002 3.2529711 4.1255986 3.2479727 15 P 0 ;0,1=22,2=90.000000
L 4.1206002 3.2629679 4.1206002 3.2529711 15 P 0 ;0,1=22,2=90.000000
L 4.121353 4.2365703 4.1163546 4.2415687 15 P 0 ;0,1=80,2=0.000000
L 4.1255986 3.1879921 4.1455921 3.1879921 15 P 0 ;0,1=22,2=90.000000
L 4.1255986 3.2079856 4.1206002 3.2029873 15 P 0 ;0,1=22,2=90.000000
L 4.1255986 3.2379759 4.1455921 3.2179824 15 P 0 ;0,1=22,2=90.000000
L 4.1255986 3.2479727 4.130597 3.2479727 15 P 0 ;0,1=22,2=90.000000
L 4.1255986 3.2679662 4.1206002 3.2629679 15 P 0 ;0,1=22,2=90.000000
L 4.1263514 4.2365703 4.121353 4.2365703 15 P 0 ;0,1=80,2=0.000000
L 4.1263514 4.2665606 4.1313498 4.2665606 15 P 0 ;0,1=80,2=0.000000
L 4.1273449 3.8930808 4.1323433 3.8880824 15 P 0 ;0,1=116,2=90.000000
L 4.1273449 3.9030776 4.1273449 3.8930808 15 P 0 ;0,1=116,2=90.000000
L 4.1273449 3.9180727 4.14234 3.9180727 15 P 0 ;0,1=116,2=90.000000
L 4.1273449 3.9380662 4.1273449 3.9180727 15 P 0 ;0,1=116,2=90.000000
L 4.1273449 3.9630582 4.14234 3.948063 15 P 0 ;0,1=116,2=90.000000
L 4.130597 3.2479727 4.1355953 3.2529711 15 P 0 ;0,1=22,2=90.000000
L 4.1313498 4.2415687 4.1263514 4.2365703 15 P 0 ;0,1=80,2=0.000000
L 4.1313498 4.2665606 4.1313498 4.2415687 15 P 0 ;0,1=80,2=0.000000
L 4.1323433 3.8880824 4.1523368 3.8880824 15 P 0 ;0,1=116,2=90.000000
L 4.1323433 3.9080759 4.1273449 3.9030776 15 P 0 ;0,1=116,2=90.000000
L 4.1327559 0.8574803 4.1327559 2.4574803 5 P 0
L 4.1327559 0.8574803 5.5227559 0.8574803 5 P 0
L 4.1327559 2.4574803 5.5227559 2.4574803 5 P 0
L 4.1355953 3.2529711 4.1355953 3.2679662 15 P 0 ;0,1=22,2=90.000000
L 4.1363481 4.2665606 4.1263514 4.2665606 15 P 0 ;0,1=80,2=0.000000
L 4.1373417 3.9280695 4.1373417 3.9330679 15 P 0 ;0,1=116,2=90.000000
L 4.1373417 3.9330679 4.14234 3.9380662 15 P 0 ;0,1=116,2=90.000000
L 4.1378425 2.4970614 4.1428409 2.492063 4 P 0 ;0,1=13,2=0.000000
L 4.1378425 2.5220533 4.1378425 2.4970614 4 P 0 ;0,1=13,2=0.000000
L 4.1378425 3.660063 4.1378425 3.6900533 15 P 0 ;0,1=75,2=0.000000
L 4.1378425 3.6900533 4.1528377 3.6900533 15 P 0 ;0,1=75,2=0.000000
L 4.1398425 3.681378 4.1398425 3.720748 8 P 0
L 4.14234 3.9180727 4.1373417 3.9280695 15 P 0 ;0,1=116,2=90.000000
L 4.14234 3.9380662 4.1523368 3.9380662 15 P 0 ;0,1=116,2=90.000000
L 4.14234 3.948063 4.14234 3.9680565 15 P 0 ;0,1=116,2=90.000000
L 4.1428409 2.492063 4.1528377 2.492063 4 P 0 ;0,1=13,2=0.000000
L 4.1428425 3.776063 4.1428425 3.836063 8 P 0
L 4.1443449 2.8870824 4.15934 2.8870824 15 P 0 ;0,1=83,2=90.000000
L 4.1443449 2.9070759 4.1443449 2.8870824 15 P 0 ;0,1=83,2=90.000000
L 4.1443449 2.9170727 4.1743352 2.9170727 15 P 0 ;0,1=83,2=90.000000
L 4.1443449 2.9320679 4.1443449 2.9170727 15 P 0 ;0,1=83,2=90.000000
L 4.1443449 2.9520614 4.1443449 2.9620582 15 P 0 ;0,1=83,2=90.000000
L 4.1443449 2.9620582 4.1493433 2.9670565 15 P 0 ;0,1=83,2=90.000000
L 4.1455921 3.1879921 4.1505905 3.1929905 15 P 0 ;0,1=22,2=90.000000
L 4.1455921 3.2179824 4.1505905 3.2179824 15 P 0 ;0,1=22,2=90.000000
L 4.1455921 3.2479727 4.1505905 3.2529711 15 P 0 ;0,1=22,2=90.000000
L 4.1455921 3.2679662 4.1255986 3.2679662 15 P 0 ;0,1=22,2=90.000000
L 4.1463449 4.2615622 4.1513433 4.2665606 15 P 0 ;0,1=80,2=0.000000
L 4.1478393 3.6700598 4.157836 3.660063 15 P 0 ;0,1=75,2=0.000000
L 4.1493433 2.9370662 4.1443449 2.9320679 15 P 0 ;0,1=83,2=90.000000
L 4.1493433 2.947063 4.1443449 2.9520614 15 P 0 ;0,1=83,2=90.000000
L 4.1493433 2.9670565 4.1543417 2.9670565 15 P 0 ;0,1=83,2=90.000000
L 4.1505905 3.1929905 4.1505905 3.2029873 15 P 0 ;0,1=22,2=90.000000
L 4.1505905 3.2029873 4.1455921 3.2079856 15 P 0 ;0,1=22,2=90.000000
L 4.1505905 3.2529711 4.1505905 3.2629679 15 P 0 ;0,1=22,2=90.000000
L 4.1505905 3.2629679 4.1455921 3.2679662 15 P 0 ;0,1=22,2=90.000000
L 4.1513433 4.2365703 4.1463449 4.2415687 15 P 0 ;0,1=80,2=0.000000
L 4.1513433 4.2665606 4.1613401 4.2665606 15 P 0 ;0,1=80,2=0.000000
L 4.1523368 3.8880824 4.1573352 3.8930808 15 P 0 ;0,1=116,2=90.000000
L 4.1523368 3.9380662 4.1573352 3.9330679 15 P 0 ;0,1=116,2=90.000000
L 4.1528377 2.492063 4.157836 2.4970614 4 P 0 ;0,1=13,2=0.000000
L 4.1528377 3.6700598 4.1378425 3.6700598 15 P 0 ;0,1=75,2=0.000000
L 4.1528377 3.6900533 4.157836 3.6850549 15 P 0 ;0,1=75,2=0.000000
L 4.1543417 2.9370662 4.1493433 2.9370662 15 P 0 ;0,1=83,2=90.000000
L 4.1543417 2.9670565 4.15934 2.9620582 15 P 0 ;0,1=83,2=90.000000
L 4.1563417 4.2515655 4.1613401 4.2515655 15 P 0 ;0,1=80,2=0.000000
L 4.1573352 3.8930808 4.1573352 3.9030776 15 P 0 ;0,1=116,2=90.000000
L 4.1573352 3.9030776 4.1523368 3.9080759 15 P 0 ;0,1=116,2=90.000000
L 4.1573352 3.9230711 4.1523368 3.9180727 15 P 0 ;0,1=116,2=90.000000
L 4.1573352 3.9330679 4.1573352 3.9230711 15 P 0 ;0,1=116,2=90.000000
L 4.1573352 3.9630582 4.1273449 3.9630582 15 P 0 ;0,1=116,2=90.000000
L 4.157836 2.4970614 4.157836 2.5220533 4 P 0 ;0,1=13,2=0.000000
L 4.157836 3.6750582 4.1528377 3.6700598 15 P 0 ;0,1=75,2=0.000000
L 4.157836 3.6850549 4.157836 3.6750582 15 P 0 ;0,1=75,2=0.000000
L 4.15934 2.8870824 4.15934 2.8970792 15 P 0 ;0,1=83,2=90.000000
L 4.15934 2.8870824 4.1743352 2.8870824 15 P 0 ;0,1=83,2=90.000000
L 4.15934 2.8970792 4.15934 2.8870824 15 P 0 ;0,1=83,2=90.000000
L 4.15934 2.9170727 4.15934 2.9320679 15 P 0 ;0,1=83,2=90.000000
L 4.15934 2.9320679 4.1543417 2.9370662 15 P 0 ;0,1=83,2=90.000000
L 4.15934 2.9320679 4.15934 2.9170727 15 P 0 ;0,1=83,2=90.000000
L 4.15934 2.9570598 4.15934 2.9620582 15 P 0 ;0,1=83,2=90.000000
L 4.15934 2.9620582 4.15934 2.9570598 15 P 0 ;0,1=83,2=90.000000
L 4.15934 2.9620582 4.1643384 2.9670565 15 P 0 ;0,1=83,2=90.000000
L 4.1613401 4.2365703 4.1513433 4.2365703 15 P 0 ;0,1=80,2=0.000000
L 4.1613401 4.2515655 4.1563417 4.2515655 15 P 0 ;0,1=80,2=0.000000
L 4.1613401 4.2515655 4.1663384 4.2465671 15 P 0 ;0,1=80,2=0.000000
L 4.1613401 4.2665606 4.1663384 4.2615622 15 P 0 ;0,1=80,2=0.000000
L 4.1643384 2.9370662 4.15934 2.9320679 15 P 0 ;0,1=83,2=90.000000
L 4.1643384 2.9670565 4.1693368 2.9670565 15 P 0 ;0,1=83,2=90.000000
L 4.1663384 4.2415687 4.1613401 4.2365703 15 P 0 ;0,1=80,2=0.000000
L 4.1663384 4.2465671 4.1663384 4.2415687 15 P 0 ;0,1=80,2=0.000000
L 4.1663384 4.2565638 4.1613401 4.2515655 15 P 0 ;0,1=80,2=0.000000
L 4.1663384 4.2615622 4.1663384 4.2565638 15 P 0 ;0,1=80,2=0.000000
L 4.1668425 3.781063 4.1668425 3.831063 8 P 0
L 4.1678328 2.492063 4.1778296 2.492063 4 P 0 ;0,1=13,2=0.000000
L 4.1678328 3.660063 4.1778296 3.660063 15 P 0 ;0,1=75,2=0.000000
L 4.1693368 2.9370662 4.1643384 2.9370662 15 P 0 ;0,1=83,2=90.000000
L 4.1693368 2.9670565 4.1743352 2.9620582 15 P 0 ;0,1=83,2=90.000000
L 4.1728312 2.492063 4.1728312 2.5220533 4 P 0 ;0,1=13,2=0.000000
L 4.1728312 2.5220533 4.1678328 2.5170549 4 P 0 ;0,1=13,2=0.000000
L 4.1728312 3.660063 4.1728312 3.6900533 15 P 0 ;0,1=75,2=0.000000
L 4.1728312 3.6900533 4.1678328 3.6850549 15 P 0 ;0,1=75,2=0.000000
L 4.1743352 2.9170727 4.1743352 2.9320679 15 P 0 ;0,1=83,2=90.000000
L 4.1743352 2.9320679 4.1693368 2.9370662 15 P 0 ;0,1=83,2=90.000000
L 4.1743352 2.9520614 4.1693368 2.947063 15 P 0 ;0,1=83,2=90.000000
L 4.1743352 2.9620582 4.1743352 2.9520614 15 P 0 ;0,1=83,2=90.000000
L 4.1777559 3.5836615 4.1777559 3.6230315 8 P 0
L 4.1778296 2.492063 4.1728312 2.492063 4 P 0 ;0,1=13,2=0.000000
L 4.1778296 3.660063 4.1728312 3.660063 15 P 0 ;0,1=75,2=0.000000
L 4.1808425 3.3210614 4.1858409 3.316063 15 P 0 ;0,1=27,2=0.000000
L 4.1808425 3.3410549 4.1808425 3.3210614 15 P 0 ;0,1=27,2=0.000000
L 4.1858409 3.316063 4.1958377 3.316063 15 P 0 ;0,1=27,2=0.000000
L 4.1858409 3.3460533 4.1808425 3.3410549 15 P 0 ;0,1=27,2=0.000000
L 4.1928247 2.4970614 4.1928247 2.5170549 4 P 0 ;0,1=13,2=0.000000
L 4.1928247 2.5170549 4.1978231 2.5220533 4 P 0 ;0,1=13,2=0.000000
L 4.1958377 3.316063 4.200836 3.3210614 15 P 0 ;0,1=27,2=0.000000
L 4.1958377 3.3460533 4.1858409 3.3460533 15 P 0 ;0,1=27,2=0.000000
L 4.1968425 2.786063 4.1968425 2.846063 8 P 0
L 4.1978231 2.492063 4.1928247 2.4970614 4 P 0 ;0,1=13,2=0.000000
L 4.1978231 2.5220533 4.2078199 2.5220533 4 P 0 ;0,1=13,2=0.000000
L 4.200836 3.3410549 4.1958377 3.3460533 15 P 0 ;0,1=27,2=0.000000
L 4.2068619 3.6785703 4.2068619 3.7085606 15 P 0 ;0,1=58,2=0.000000
L 4.2068619 3.7085606 4.2218571 3.7085606 15 P 0 ;0,1=58,2=0.000000
L 4.2078199 2.492063 4.1978231 2.492063 4 P 0 ;0,1=13,2=0.000000
L 4.2078199 2.5220533 4.2128182 2.5170549 4 P 0 ;0,1=13,2=0.000000
L 4.2108328 3.3210614 4.2108328 3.3260598 15 P 0 ;0,1=27,2=0.000000
L 4.2108328 3.3260598 4.2158312 3.3310582 15 P 0 ;0,1=27,2=0.000000
L 4.2108328 3.3360565 4.2108328 3.3410549 15 P 0 ;0,1=27,2=0.000000
L 4.2108328 3.3410549 4.2158312 3.3460533 15 P 0 ;0,1=27,2=0.000000
L 4.2128182 2.4970614 4.2078199 2.492063 4 P 0 ;0,1=13,2=0.000000
L 4.2128182 2.5170549 4.2128182 2.4970614 4 P 0 ;0,1=13,2=0.000000
L 4.2148425 3.208063 4.2748425 3.208063 8 P 0
L 4.2148425 3.284063 4.2748425 3.284063 8 P 0
L 4.2158312 3.316063 4.2108328 3.3210614 15 P 0 ;0,1=27,2=0.000000
L 4.2158312 3.3310582 4.2108328 3.3360565 15 P 0 ;0,1=27,2=0.000000
L 4.2158312 3.3310582 4.225828 3.3310582 15 P 0 ;0,1=27,2=0.000000
L 4.2158312 3.3460533 4.225828 3.3460533 15 P 0 ;0,1=27,2=0.000000
L 4.2168587 3.6885671 4.2268554 3.6785703 15 P 0 ;0,1=58,2=0.000000
L 4.2218571 3.6885671 4.2068619 3.6885671 15 P 0 ;0,1=58,2=0.000000
L 4.2218571 3.7085606 4.2268554 3.7035622 15 P 0 ;0,1=58,2=0.000000
L 4.222815 2.492063 4.222815 2.5120565 4 P 0 ;0,1=13,2=0.000000
L 4.222815 2.5120565 4.2328118 2.5220533 4 P 0 ;0,1=13,2=0.000000
L 4.2228425 3.781063 4.2228425 3.831063 8 P 0
L 4.225828 3.316063 4.2158312 3.316063 15 P 0 ;0,1=27,2=0.000000
L 4.225828 3.3310582 4.2308263 3.3260598 15 P 0 ;0,1=27,2=0.000000
L 4.225828 3.3460533 4.2308263 3.3410549 15 P 0 ;0,1=27,2=0.000000
L 4.2268554 3.6935655 4.2218571 3.6885671 15 P 0 ;0,1=58,2=0.000000
L 4.2268554 3.7035622 4.2268554 3.6935655 15 P 0 ;0,1=58,2=0.000000
L 4.2303449 2.9000808 4.2353433 2.8950824 15 P 0 ;0,1=16,2=90.000000
L 4.2303449 2.9100776 4.2303449 2.9000808 15 P 0 ;0,1=16,2=90.000000
L 4.2303449 2.9250727 4.2303449 2.9450662 15 P 0 ;0,1=16,2=90.000000
L 4.2303449 2.9450662 4.2353433 2.9450662 15 P 0 ;0,1=16,2=90.000000
L 4.2303449 2.9600614 4.2303449 2.9700582 15 P 0 ;0,1=16,2=90.000000
L 4.2303449 2.9700582 4.2353433 2.9750565 15 P 0 ;0,1=16,2=90.000000
L 4.2308263 3.3210614 4.225828 3.316063 15 P 0 ;0,1=27,2=0.000000
L 4.2308263 3.3260598 4.2308263 3.3210614 15 P 0 ;0,1=27,2=0.000000
L 4.2308263 3.3360565 4.225828 3.3310582 15 P 0 ;0,1=27,2=0.000000
L 4.2308263 3.3410549 4.2308263 3.3360565 15 P 0 ;0,1=27,2=0.000000
L 4.2328118 2.5220533 4.2428085 2.5120565 4 P 0 ;0,1=13,2=0.000000
L 4.2353433 2.8950824 4.2553368 2.8950824 15 P 0 ;0,1=16,2=90.000000
L 4.2353433 2.9150759 4.2303449 2.9100776 15 P 0 ;0,1=16,2=90.000000
L 4.2353433 2.9450662 4.2553368 2.9250727 15 P 0 ;0,1=16,2=90.000000
L 4.2353433 2.955063 4.2303449 2.9600614 15 P 0 ;0,1=16,2=90.000000
L 4.2353433 2.9750565 4.2403417 2.9750565 15 P 0 ;0,1=16,2=90.000000
L 4.2368522 3.6785703 4.2568457 3.6985638 15 P 0 ;0,1=58,2=0.000000
L 4.2403417 2.9750565 4.24534 2.9700582 15 P 0 ;0,1=16,2=90.000000
L 4.2408231 3.3310582 4.2608166 3.3310582 15 P 0 ;0,1=27,2=0.000000
L 4.2418506 3.7085606 4.2368522 3.7035622 15 P 0 ;0,1=58,2=0.000000
L 4.2428085 2.492063 4.2428085 2.5070582 4 P 0 ;0,1=13,2=0.000000
L 4.2428085 2.5070582 4.222815 2.5070582 4 P 0 ;0,1=13,2=0.000000
L 4.2428085 2.5120565 4.2428085 2.492063 4 P 0 ;0,1=13,2=0.000000
L 4.24534 2.9650598 4.24534 2.9700582 15 P 0 ;0,1=16,2=90.000000
L 4.24534 2.9700582 4.24534 2.9650598 15 P 0 ;0,1=16,2=90.000000
L 4.24534 2.9700582 4.2503384 2.9750565 15 P 0 ;0,1=16,2=90.000000
L 4.2503384 2.9750565 4.2553368 2.9750565 15 P 0 ;0,1=16,2=90.000000
L 4.2518474 3.7085606 4.2418506 3.7085606 15 P 0 ;0,1=58,2=0.000000
L 4.2528053 2.492063 4.2727988 2.492063 4 P 0 ;0,1=13,2=0.000000
L 4.2528053 2.5220533 4.2528053 2.492063 4 P 0 ;0,1=13,2=0.000000
L 4.2553368 2.8950824 4.2603352 2.9000808 15 P 0 ;0,1=16,2=90.000000
L 4.2553368 2.9250727 4.2603352 2.9250727 15 P 0 ;0,1=16,2=90.000000
L 4.2553368 2.9750565 4.2603352 2.9700582 15 P 0 ;0,1=16,2=90.000000
L 4.2558183 3.316063 4.2558183 3.3460533 15 P 0 ;0,1=27,2=0.000000
L 4.2558183 3.3460533 4.2408231 3.3310582 15 P 0 ;0,1=27,2=0.000000
L 4.2568457 3.6785703 4.2368522 3.6785703 15 P 0 ;0,1=58,2=0.000000
L 4.2568457 3.6985638 4.2568457 3.7035622 15 P 0 ;0,1=58,2=0.000000
L 4.2568457 3.7035622 4.2518474 3.7085606 15 P 0 ;0,1=58,2=0.000000
L 4.2603352 2.9000808 4.2603352 2.9100776 15 P 0 ;0,1=16,2=90.000000
L 4.2603352 2.9100776 4.2553368 2.9150759 15 P 0 ;0,1=16,2=90.000000
L 4.2603352 2.9600614 4.2553368 2.955063 15 P 0 ;0,1=16,2=90.000000
L 4.2603352 2.9700582 4.2603352 2.9600614 15 P 0 ;0,1=16,2=90.000000
L 4.2668425 3.6835687 4.2668425 3.6785703 15 P 0 ;0,1=58,2=0.000000
L 4.2668425 3.7085606 4.286836 3.7085606 15 P 0 ;0,1=58,2=0.000000
L 4.2683449 3.8100808 4.2733433 3.8050824 15 P 0 ;0,1=115,2=90.000000
L 4.2683449 3.8200776 4.2683449 3.8100808 15 P 0 ;0,1=115,2=90.000000
L 4.2683449 3.8350727 4.28334 3.8350727 15 P 0 ;0,1=115,2=90.000000
L 4.2683449 3.8550662 4.2683449 3.8350727 15 P 0 ;0,1=115,2=90.000000
L 4.2683449 3.865063 4.28334 3.865063 15 P 0 ;0,1=115,2=90.000000
L 4.2683449 3.8850565 4.2683449 3.865063 15 P 0 ;0,1=115,2=90.000000
L 4.2728425 2.786063 4.2728425 2.846063 8 P 0
L 4.2733433 3.8050824 4.2933368 3.8050824 15 P 0 ;0,1=115,2=90.000000
L 4.2733433 3.8250759 4.2683449 3.8200776 15 P 0 ;0,1=115,2=90.000000
L 4.2783417 3.8450695 4.2783417 3.8500679 15 P 0 ;0,1=115,2=90.000000
L 4.2783417 3.8500679 4.28334 3.8550662 15 P 0 ;0,1=115,2=90.000000
L 4.2783417 3.8750598 4.2783417 3.8800582 15 P 0 ;0,1=115,2=90.000000
L 4.2783417 3.8800582 4.28334 3.8850565 15 P 0 ;0,1=115,2=90.000000
L 4.28334 3.8350727 4.2783417 3.8450695 15 P 0 ;0,1=115,2=90.000000
L 4.28334 3.8550662 4.2933368 3.8550662 15 P 0 ;0,1=115,2=90.000000
L 4.28334 3.865063 4.2783417 3.8750598 15 P 0 ;0,1=115,2=90.000000
L 4.28334 3.8850565 4.2933368 3.8850565 15 P 0 ;0,1=115,2=90.000000
L 4.286836 3.7035622 4.2668425 3.6835687 15 P 0 ;0,1=58,2=0.000000
L 4.286836 3.7085606 4.286836 3.7035622 15 P 0 ;0,1=58,2=0.000000
L 4.2933368 3.8050824 4.2983352 3.8100808 15 P 0 ;0,1=115,2=90.000000
L 4.2933368 3.8550662 4.2983352 3.8500679 15 P 0 ;0,1=115,2=90.000000
L 4.2933368 3.8850565 4.2983352 3.8800582 15 P 0 ;0,1=115,2=90.000000
L 4.2983352 3.8100808 4.2983352 3.8200776 15 P 0 ;0,1=115,2=90.000000
L 4.2983352 3.8200776 4.2933368 3.8250759 15 P 0 ;0,1=115,2=90.000000
L 4.2983352 3.8400711 4.2933368 3.8350727 15 P 0 ;0,1=115,2=90.000000
L 4.2983352 3.8500679 4.2983352 3.8400711 15 P 0 ;0,1=115,2=90.000000
L 4.2983352 3.8700614 4.2933368 3.865063 15 P 0 ;0,1=115,2=90.000000
L 4.2983352 3.8800582 4.2983352 3.8700614 15 P 0 ;0,1=115,2=90.000000
L 4.3018425 2.786063 4.3018425 2.846063 8 P 0
L 4.3248031 3.6338583 4.3397983 3.6338583 15 P 0 ;0,1=100,2=0.000000
L 4.3248031 3.6638486 4.3248031 3.6338583 15 P 0 ;0,1=100,2=0.000000
L 4.3333449 2.8990808 4.3383433 2.8940824 15 P 0 ;0,1=15,2=90.000000
L 4.3333449 2.9090776 4.3333449 2.8990808 15 P 0 ;0,1=15,2=90.000000
L 4.3333449 2.9240727 4.3333449 2.9440662 15 P 0 ;0,1=15,2=90.000000
L 4.3333449 2.9440662 4.3383433 2.9440662 15 P 0 ;0,1=15,2=90.000000
L 4.3333449 2.9590614 4.3383433 2.954063 15 P 0 ;0,1=15,2=90.000000
L 4.3333449 2.9690582 4.3333449 2.9590614 15 P 0 ;0,1=15,2=90.000000
L 4.3341829 3.2156283 4.3391813 3.2106299 15 P 0 ;0,1=23,2=90.000000
L 4.3341829 3.2256251 4.3341829 3.2156283 15 P 0 ;0,1=23,2=90.000000
L 4.3341829 3.2456186 4.3341829 3.2556154 15 P 0 ;0,1=23,2=90.000000
L 4.3341829 3.2556154 4.3391813 3.2606137 15 P 0 ;0,1=23,2=90.000000
L 4.3341829 3.2756089 4.3341829 3.2856057 15 P 0 ;0,1=23,2=90.000000
L 4.3341829 3.2856057 4.3391813 3.290604 15 P 0 ;0,1=23,2=90.000000
L 4.3383433 2.8940824 4.3583368 2.8940824 15 P 0 ;0,1=15,2=90.000000
L 4.3383433 2.9140759 4.3333449 2.9090776 15 P 0 ;0,1=15,2=90.000000
L 4.3383433 2.9440662 4.3583368 2.9240727 15 P 0 ;0,1=15,2=90.000000
L 4.3383433 2.9740565 4.3333449 2.9690582 15 P 0 ;0,1=15,2=90.000000
L 4.3391813 3.2106299 4.3591748 3.2106299 15 P 0 ;0,1=23,2=90.000000
L 4.3391813 3.2306234 4.3341829 3.2256251 15 P 0 ;0,1=23,2=90.000000
L 4.3391813 3.2406202 4.3341829 3.2456186 15 P 0 ;0,1=23,2=90.000000
L 4.3391813 3.2606137 4.3441797 3.2606137 15 P 0 ;0,1=23,2=90.000000
L 4.3391813 3.2706105 4.3341829 3.2756089 15 P 0 ;0,1=23,2=90.000000
L 4.3391813 3.290604 4.3591748 3.290604 15 P 0 ;0,1=23,2=90.000000
L 4.3397983 3.6338583 4.3447966 3.6388567 15 P 0 ;0,1=100,2=0.000000
L 4.3397983 3.6638486 4.3248031 3.6638486 15 P 0 ;0,1=100,2=0.000000
L 4.3433417 2.9740565 4.3383433 2.9740565 15 P 0 ;0,1=15,2=90.000000
L 4.3441797 3.2406202 4.3391813 3.2406202 15 P 0 ;0,1=23,2=90.000000
L 4.3441797 3.2606137 4.349178 3.2556154 15 P 0 ;0,1=23,2=90.000000
L 4.3447966 3.6388567 4.3447966 3.6588502 15 P 0 ;0,1=100,2=0.000000
L 4.3447966 3.6588502 4.3397983 3.6638486 15 P 0 ;0,1=100,2=0.000000
L 4.349178 3.2456186 4.3441797 3.2406202 15 P 0 ;0,1=23,2=90.000000
L 4.349178 3.2456186 4.349178 3.2556154 15 P 0 ;0,1=23,2=90.000000
L 4.349178 3.2556154 4.3541764 3.2606137 15 P 0 ;0,1=23,2=90.000000
L 4.3541764 3.2406202 4.349178 3.2456186 15 P 0 ;0,1=23,2=90.000000
L 4.3541764 3.2606137 4.3591748 3.2606137 15 P 0 ;0,1=23,2=90.000000
L 4.3547934 3.6488535 4.3747869 3.6488535 15 P 0 ;0,1=100,2=0.000000
L 4.3583368 2.8940824 4.3633352 2.8990808 15 P 0 ;0,1=15,2=90.000000
L 4.3583368 2.9240727 4.3633352 2.9240727 15 P 0 ;0,1=15,2=90.000000
L 4.3591748 3.2106299 4.3641732 3.2156283 15 P 0 ;0,1=23,2=90.000000
L 4.3591748 3.2406202 4.3541764 3.2406202 15 P 0 ;0,1=23,2=90.000000
L 4.3591748 3.2606137 4.3641732 3.2556154 15 P 0 ;0,1=23,2=90.000000
L 4.3591748 3.2706105 4.3391813 3.2706105 15 P 0 ;0,1=23,2=90.000000
L 4.3591748 3.290604 4.3641732 3.2856057 15 P 0 ;0,1=23,2=90.000000
L 4.3633352 2.8990808 4.3633352 2.9090776 15 P 0 ;0,1=15,2=90.000000
L 4.3633352 2.9090776 4.3583368 2.9140759 15 P 0 ;0,1=15,2=90.000000
L 4.3633352 2.954063 4.3433417 2.9740565 15 P 0 ;0,1=15,2=90.000000
L 4.3633352 2.9740565 4.3633352 2.954063 15 P 0 ;0,1=15,2=90.000000
L 4.3641732 3.2156283 4.3641732 3.2256251 15 P 0 ;0,1=23,2=90.000000
L 4.3641732 3.2256251 4.3591748 3.2306234 15 P 0 ;0,1=23,2=90.000000
L 4.3641732 3.2456186 4.3591748 3.2406202 15 P 0 ;0,1=23,2=90.000000
L 4.3641732 3.2556154 4.3641732 3.2456186 15 P 0 ;0,1=23,2=90.000000
L 4.3641732 3.2756089 4.3591748 3.2706105 15 P 0 ;0,1=23,2=90.000000
L 4.3641732 3.2856057 4.3641732 3.2756089 15 P 0 ;0,1=23,2=90.000000
L 4.3697886 3.6338583 4.3697886 3.6638486 15 P 0 ;0,1=100,2=0.000000
L 4.3697886 3.6638486 4.3547934 3.6488535 15 P 0 ;0,1=100,2=0.000000
L 4.3778425 2.786063 4.3778425 2.846063 8 P 0
L 4.3843798 3.2156283 4.3893782 3.2106299 15 P 0 ;0,1=24,2=90.000000
L 4.3843798 3.2256251 4.3843798 3.2156283 15 P 0 ;0,1=24,2=90.000000
L 4.3843798 3.2456186 4.3843798 3.2556154 15 P 0 ;0,1=24,2=90.000000
L 4.3843798 3.2556154 4.3893782 3.2606137 15 P 0 ;0,1=24,2=90.000000
L 4.3843798 3.2756089 4.3893782 3.2706105 15 P 0 ;0,1=24,2=90.000000
L 4.3893782 3.2106299 4.4093717 3.2106299 15 P 0 ;0,1=24,2=90.000000
L 4.3893782 3.2306234 4.3843798 3.2256251 15 P 0 ;0,1=24,2=90.000000
L 4.3893782 3.2406202 4.3843798 3.2456186 15 P 0 ;0,1=24,2=90.000000
L 4.3893782 3.2606137 4.3943766 3.2606137 15 P 0 ;0,1=24,2=90.000000
L 4.3943766 3.2406202 4.3893782 3.2406202 15 P 0 ;0,1=24,2=90.000000
L 4.3943766 3.2606137 4.3993749 3.2556154 15 P 0 ;0,1=24,2=90.000000
L 4.3993749 3.2456186 4.3943766 3.2406202 15 P 0 ;0,1=24,2=90.000000
L 4.3993749 3.2456186 4.3993749 3.2556154 15 P 0 ;0,1=24,2=90.000000
L 4.3993749 3.2556154 4.4043733 3.2606137 15 P 0 ;0,1=24,2=90.000000
L 4.4043733 3.2406202 4.3993749 3.2456186 15 P 0 ;0,1=24,2=90.000000
L 4.4043733 3.2606137 4.4093717 3.2606137 15 P 0 ;0,1=24,2=90.000000
L 4.4068425 4.3170565 4.4118409 4.3120582 15 P 0 ;0,1=49,2=0.000000
L 4.4068425 4.3220549 4.4068425 4.3170565 15 P 0 ;0,1=49,2=0.000000
L 4.4093717 3.2106299 4.4143701 3.2156283 15 P 0 ;0,1=24,2=90.000000
L 4.4093717 3.2406202 4.4043733 3.2406202 15 P 0 ;0,1=24,2=90.000000
L 4.4093717 3.2606137 4.4143701 3.2556154 15 P 0 ;0,1=24,2=90.000000
L 4.4098425 4.151063 4.4098425 4.161063 10 P 0
L 4.4098425 4.151063 4.5898425 4.151063 10 P 0
L 4.4098425 4.251063 4.4098425 4.261063 10 P 0
L 4.4098425 4.261063 4.5898425 4.261063 10 P 0
L 4.4118409 4.297063 4.4068425 4.3020614 15 P 0 ;0,1=49,2=0.000000
L 4.4118409 4.3120582 4.4218377 4.3120582 15 P 0 ;0,1=49,2=0.000000
L 4.4118409 4.3270533 4.4068425 4.3220549 15 P 0 ;0,1=49,2=0.000000
L 4.4143701 3.2156283 4.4143701 3.2256251 15 P 0 ;0,1=24,2=90.000000
L 4.4143701 3.2256251 4.4093717 3.2306234 15 P 0 ;0,1=24,2=90.000000
L 4.4143701 3.2456186 4.4093717 3.2406202 15 P 0 ;0,1=24,2=90.000000
L 4.4143701 3.2556154 4.4143701 3.2456186 15 P 0 ;0,1=24,2=90.000000
L 4.4143701 3.2706105 4.4143701 3.2806073 15 P 0 ;0,1=24,2=90.000000
L 4.4143701 3.2756089 4.3843798 3.2756089 15 P 0 ;0,1=24,2=90.000000
L 4.4143701 3.2806073 4.4143701 3.2756089 15 P 0 ;0,1=24,2=90.000000
L 4.4218377 4.297063 4.4118409 4.297063 15 P 0 ;0,1=49,2=0.000000
L 4.4218377 4.3120582 4.426836 4.3070598 15 P 0 ;0,1=49,2=0.000000
L 4.4218377 4.3270533 4.4118409 4.3270533 15 P 0 ;0,1=49,2=0.000000
L 4.426836 4.3020614 4.4218377 4.297063 15 P 0 ;0,1=49,2=0.000000
L 4.426836 4.3070598 4.426836 4.3020614 15 P 0 ;0,1=49,2=0.000000
L 4.426836 4.3220549 4.4218377 4.3270533 15 P 0 ;0,1=49,2=0.000000
L 4.4335924 3.2107071 4.4385908 3.2057087 15 P 0 ;0,1=25,2=90.000000
L 4.4335924 3.2207039 4.4335924 3.2107071 15 P 0 ;0,1=25,2=90.000000
L 4.4335924 3.2406974 4.4335924 3.2506942 15 P 0 ;0,1=25,2=90.000000
L 4.4335924 3.2506942 4.4385908 3.2556925 15 P 0 ;0,1=25,2=90.000000
L 4.4335924 3.2706877 4.4385908 3.2656893 15 P 0 ;0,1=25,2=90.000000
L 4.4335924 3.2806845 4.4335924 3.2706877 15 P 0 ;0,1=25,2=90.000000
L 4.4368328 4.3120582 4.4468296 4.3170565 15 P 0 ;0,1=49,2=0.000000
L 4.4368328 4.3270533 4.4368328 4.3120582 15 P 0 ;0,1=49,2=0.000000
L 4.4385908 3.2057087 4.4585843 3.2057087 15 P 0 ;0,1=25,2=90.000000
L 4.4385908 3.2257022 4.4335924 3.2207039 15 P 0 ;0,1=25,2=90.000000
L 4.4385908 3.235699 4.4335924 3.2406974 15 P 0 ;0,1=25,2=90.000000
L 4.4385908 3.2556925 4.4435892 3.2556925 15 P 0 ;0,1=25,2=90.000000
L 4.4385908 3.2856828 4.4335924 3.2806845 15 P 0 ;0,1=25,2=90.000000
L 4.4418312 4.297063 4.4368328 4.3020614 15 P 0 ;0,1=49,2=0.000000
L 4.4435892 3.235699 4.4385908 3.235699 15 P 0 ;0,1=25,2=90.000000
L 4.4435892 3.2556925 4.4485875 3.2506942 15 P 0 ;0,1=25,2=90.000000
L 4.4435892 3.2856828 4.4385908 3.2856828 15 P 0 ;0,1=25,2=90.000000
L 4.4468296 4.3170565 4.451828 4.3170565 15 P 0 ;0,1=49,2=0.000000
L 4.4485875 3.2406974 4.4435892 3.235699 15 P 0 ;0,1=25,2=90.000000
L 4.4485875 3.2406974 4.4485875 3.2506942 15 P 0 ;0,1=25,2=90.000000
L 4.4485875 3.2506942 4.4535859 3.2556925 15 P 0 ;0,1=25,2=90.000000
L 4.451828 4.297063 4.4418312 4.297063 15 P 0 ;0,1=49,2=0.000000
L 4.451828 4.3170565 4.4568263 4.3120582 15 P 0 ;0,1=49,2=0.000000
L 4.4535859 3.235699 4.4485875 3.2406974 15 P 0 ;0,1=25,2=90.000000
L 4.4535859 3.2556925 4.4585843 3.2556925 15 P 0 ;0,1=25,2=90.000000
L 4.4568263 4.3020614 4.451828 4.297063 15 P 0 ;0,1=49,2=0.000000
L 4.4568263 4.3120582 4.4568263 4.3020614 15 P 0 ;0,1=49,2=0.000000
L 4.4568263 4.3270533 4.4368328 4.3270533 15 P 0 ;0,1=49,2=0.000000
L 4.4581215 3.8806742 4.4731167 3.8806742 4 P 0 ;0,1=14,2=0.000000
L 4.4581215 3.8956694 4.4731167 3.8956694 4 P 0 ;0,1=14,2=0.000000
L 4.4581215 3.9106645 4.4581215 3.8806742 4 P 0 ;0,1=14,2=0.000000
L 4.4585843 3.2057087 4.4635827 3.2107071 15 P 0 ;0,1=25,2=90.000000
L 4.4585843 3.235699 4.4535859 3.235699 15 P 0 ;0,1=25,2=90.000000
L 4.4585843 3.2556925 4.4635827 3.2506942 15 P 0 ;0,1=25,2=90.000000
L 4.4635827 3.2107071 4.4635827 3.2207039 15 P 0 ;0,1=25,2=90.000000
L 4.4635827 3.2207039 4.4585843 3.2257022 15 P 0 ;0,1=25,2=90.000000
L 4.4635827 3.2406974 4.4585843 3.235699 15 P 0 ;0,1=25,2=90.000000
L 4.4635827 3.2506942 4.4635827 3.2406974 15 P 0 ;0,1=25,2=90.000000
L 4.4635827 3.2656893 4.4435892 3.2856828 15 P 0 ;0,1=25,2=90.000000
L 4.4635827 3.2856828 4.4635827 3.2656893 15 P 0 ;0,1=25,2=90.000000
L 4.4731167 3.8806742 4.478115 3.8856726 4 P 0 ;0,1=14,2=0.000000
L 4.4731167 3.8956694 4.4581215 3.8956694 4 P 0 ;0,1=14,2=0.000000
L 4.4731167 3.8956694 4.478115 3.9006677 4 P 0 ;0,1=14,2=0.000000
L 4.4731167 3.9106645 4.4581215 3.9106645 4 P 0 ;0,1=14,2=0.000000
L 4.478115 3.8856726 4.478115 3.890671 4 P 0 ;0,1=14,2=0.000000
L 4.478115 3.890671 4.4731167 3.8956694 4 P 0 ;0,1=14,2=0.000000
L 4.478115 3.9006677 4.478115 3.9056661 4 P 0 ;0,1=14,2=0.000000
L 4.478115 3.9056661 4.4731167 3.9106645 4 P 0 ;0,1=14,2=0.000000
L 4.482805 3.1703527 4.4878034 3.1653543 15 P 0 ;0,1=26,2=90.000000
L 4.482805 3.1803495 4.482805 3.1703527 15 P 0 ;0,1=26,2=90.000000
L 4.482805 3.200343 4.482805 3.2103398 15 P 0 ;0,1=26,2=90.000000
L 4.482805 3.2103398 4.4878034 3.2153381 15 P 0 ;0,1=26,2=90.000000
L 4.482805 3.2303333 4.482805 3.2403301 15 P 0 ;0,1=26,2=90.000000
L 4.482805 3.2403301 4.4878034 3.2453284 15 P 0 ;0,1=26,2=90.000000
L 4.4878034 3.1653543 4.5077969 3.1653543 15 P 0 ;0,1=26,2=90.000000
L 4.4878034 3.1853478 4.482805 3.1803495 15 P 0 ;0,1=26,2=90.000000
L 4.4878034 3.1953446 4.482805 3.200343 15 P 0 ;0,1=26,2=90.000000
L 4.4878034 3.2153381 4.4928018 3.2153381 15 P 0 ;0,1=26,2=90.000000
L 4.4878034 3.2253349 4.482805 3.2303333 15 P 0 ;0,1=26,2=90.000000
L 4.4878034 3.2453284 4.4928018 3.2453284 15 P 0 ;0,1=26,2=90.000000
L 4.4881118 3.9106645 4.5081053 3.9106645 4 P 0 ;0,1=14,2=0.000000
L 4.4928018 3.1953446 4.4878034 3.1953446 15 P 0 ;0,1=26,2=90.000000
L 4.4928018 3.2153381 4.4978001 3.2103398 15 P 0 ;0,1=26,2=90.000000
L 4.4928018 3.2453284 4.4978001 3.2403301 15 P 0 ;0,1=26,2=90.000000
L 4.4963449 2.8340824 4.51134 2.8340824 15 P 0 ;0,1=84,2=90.000000
L 4.4963449 2.8540759 4.4963449 2.8340824 15 P 0 ;0,1=84,2=90.000000
L 4.4963449 2.8640727 4.5263352 2.8640727 15 P 0 ;0,1=84,2=90.000000
L 4.4963449 2.8790679 4.4963449 2.8640727 15 P 0 ;0,1=84,2=90.000000
L 4.4963449 2.8990614 4.5013433 2.894063 15 P 0 ;0,1=84,2=90.000000
L 4.4963449 2.9090582 4.4963449 2.8990614 15 P 0 ;0,1=84,2=90.000000
L 4.4978001 3.200343 4.4928018 3.1953446 15 P 0 ;0,1=26,2=90.000000
L 4.4978001 3.200343 4.4978001 3.2103398 15 P 0 ;0,1=26,2=90.000000
L 4.4978001 3.2103398 4.5027985 3.2153381 15 P 0 ;0,1=26,2=90.000000
L 4.4978001 3.2353317 4.4978001 3.2403301 15 P 0 ;0,1=26,2=90.000000
L 4.4978001 3.2403301 4.4978001 3.2353317 15 P 0 ;0,1=26,2=90.000000
L 4.4978001 3.2403301 4.5027985 3.2453284 15 P 0 ;0,1=26,2=90.000000
L 4.4981086 3.9106645 4.4981086 3.8806742 4 P 0 ;0,1=14,2=0.000000
L 4.5013433 2.8840662 4.4963449 2.8790679 15 P 0 ;0,1=84,2=90.000000
L 4.5013433 2.9140565 4.4963449 2.9090582 15 P 0 ;0,1=84,2=90.000000
L 4.5027985 3.1953446 4.4978001 3.200343 15 P 0 ;0,1=26,2=90.000000
L 4.5027985 3.2153381 4.5077969 3.2153381 15 P 0 ;0,1=26,2=90.000000
L 4.5027985 3.2453284 4.5077969 3.2453284 15 P 0 ;0,1=26,2=90.000000
L 4.5063417 2.8840662 4.5013433 2.8840662 15 P 0 ;0,1=84,2=90.000000
L 4.5063417 2.9140565 4.5013433 2.9140565 15 P 0 ;0,1=84,2=90.000000
L 4.5077969 3.1653543 4.5127953 3.1703527 15 P 0 ;0,1=26,2=90.000000
L 4.5077969 3.1953446 4.5027985 3.1953446 15 P 0 ;0,1=26,2=90.000000
L 4.5077969 3.2153381 4.5127953 3.2103398 15 P 0 ;0,1=26,2=90.000000
L 4.5077969 3.2453284 4.5127953 3.2403301 15 P 0 ;0,1=26,2=90.000000
L 4.5081053 3.9106645 4.4981086 3.9106645 4 P 0 ;0,1=14,2=0.000000
L 4.51134 2.8340824 4.51134 2.8440792 15 P 0 ;0,1=84,2=90.000000
L 4.51134 2.8340824 4.5263352 2.8340824 15 P 0 ;0,1=84,2=90.000000
L 4.51134 2.8440792 4.51134 2.8340824 15 P 0 ;0,1=84,2=90.000000
L 4.51134 2.8640727 4.51134 2.8790679 15 P 0 ;0,1=84,2=90.000000
L 4.51134 2.8790679 4.5063417 2.8840662 15 P 0 ;0,1=84,2=90.000000
L 4.51134 2.8790679 4.51134 2.8640727 15 P 0 ;0,1=84,2=90.000000
L 4.5127953 3.1703527 4.5127953 3.1803495 15 P 0 ;0,1=26,2=90.000000
L 4.5127953 3.1803495 4.5077969 3.1853478 15 P 0 ;0,1=26,2=90.000000
L 4.5127953 3.200343 4.5077969 3.1953446 15 P 0 ;0,1=26,2=90.000000
L 4.5127953 3.2103398 4.5127953 3.200343 15 P 0 ;0,1=26,2=90.000000
L 4.5127953 3.2303333 4.5077969 3.2253349 15 P 0 ;0,1=26,2=90.000000
L 4.5127953 3.2403301 4.5127953 3.2303333 15 P 0 ;0,1=26,2=90.000000
L 4.5163384 2.8840662 4.51134 2.8790679 15 P 0 ;0,1=84,2=90.000000
L 4.5181021 3.8806742 4.5280989 3.8806742 4 P 0 ;0,1=14,2=0.000000
L 4.5213368 2.8840662 4.5163384 2.8840662 15 P 0 ;0,1=84,2=90.000000
L 4.5231005 3.8806742 4.5231005 3.9106645 4 P 0 ;0,1=14,2=0.000000
L 4.5231005 3.9106645 4.5181021 3.9056661 4 P 0 ;0,1=14,2=0.000000
L 4.5263352 2.8640727 4.5263352 2.8790679 15 P 0 ;0,1=84,2=90.000000
L 4.5263352 2.8790679 4.5213368 2.8840662 15 P 0 ;0,1=84,2=90.000000
L 4.5263352 2.894063 4.5063417 2.9140565 15 P 0 ;0,1=84,2=90.000000
L 4.5263352 2.9140565 4.5263352 2.894063 15 P 0 ;0,1=84,2=90.000000
L 4.5280989 3.8806742 4.5231005 3.8806742 4 P 0 ;0,1=14,2=0.000000
L 4.5846457 2.8120079 4.5846457 3.9576771 5 P 0
L 4.5846457 2.8120079 4.8120079 2.8120079 5 P 0
L 4.5846457 3.9576771 4.8120079 3.9576771 5 P 0
L 4.5898425 4.151063 4.5898425 4.161063 10 P 0
L 4.5898425 4.251063 4.5898425 4.261063 10 P 0
L 4.6398425 4.263063 4.6398425 4.2930533 15 P 0 ;0,1=53,2=0.000000
L 4.6398425 4.2930533 4.6548377 4.2930533 15 P 0 ;0,1=53,2=0.000000
L 4.644685 4.0580709 4.644685 4.0880612 15 P 0 ;0,1=51,2=0.000000
L 4.644685 4.0880612 4.6596802 4.0880612 15 P 0 ;0,1=51,2=0.000000
L 4.6498393 4.2730598 4.659836 4.263063 15 P 0 ;0,1=53,2=0.000000
L 4.6546818 4.0680677 4.6646785 4.0580709 15 P 0 ;0,1=51,2=0.000000
L 4.6548377 4.2730598 4.6398425 4.2730598 15 P 0 ;0,1=53,2=0.000000
L 4.6548377 4.2930533 4.659836 4.2880549 15 P 0 ;0,1=53,2=0.000000
L 4.6596802 4.0680677 4.644685 4.0680677 15 P 0 ;0,1=51,2=0.000000
L 4.6596802 4.0880612 4.6646785 4.0830628 15 P 0 ;0,1=51,2=0.000000
L 4.659836 4.2780582 4.6548377 4.2730598 15 P 0 ;0,1=53,2=0.000000
L 4.659836 4.2880549 4.659836 4.2780582 15 P 0 ;0,1=53,2=0.000000
L 4.6646785 4.0730661 4.6596802 4.0680677 15 P 0 ;0,1=51,2=0.000000
L 4.6646785 4.0830628 4.6646785 4.0730661 15 P 0 ;0,1=51,2=0.000000
L 4.6698328 4.2880549 4.6748312 4.2930533 15 P 0 ;0,1=53,2=0.000000
L 4.6746753 4.0830628 4.6796737 4.0880612 15 P 0 ;0,1=51,2=0.000000
L 4.6748312 4.263063 4.6698328 4.2680614 15 P 0 ;0,1=53,2=0.000000
L 4.6748312 4.2930533 4.684828 4.2930533 15 P 0 ;0,1=53,2=0.000000
L 4.6796737 4.0580709 4.6746753 4.0630693 15 P 0 ;0,1=51,2=0.000000
L 4.6796737 4.0880612 4.6896705 4.0880612 15 P 0 ;0,1=51,2=0.000000
L 4.6798296 4.2780582 4.684828 4.2780582 15 P 0 ;0,1=53,2=0.000000
L 4.6798425 4.101378 4.6798425 4.140748 8 P 0
L 4.6798425 4.186378 4.6798425 4.225748 8 P 0
L 4.6846721 4.0730661 4.6896705 4.0730661 15 P 0 ;0,1=51,2=0.000000
L 4.684828 4.263063 4.6748312 4.263063 15 P 0 ;0,1=53,2=0.000000
L 4.684828 4.2780582 4.6798296 4.2780582 15 P 0 ;0,1=53,2=0.000000
L 4.684828 4.2780582 4.6898263 4.2730598 15 P 0 ;0,1=53,2=0.000000
L 4.684828 4.2930533 4.6898263 4.2880549 15 P 0 ;0,1=53,2=0.000000
L 4.6896705 4.0580709 4.6796737 4.0580709 15 P 0 ;0,1=51,2=0.000000
L 4.6896705 4.0730661 4.6846721 4.0730661 15 P 0 ;0,1=51,2=0.000000
L 4.6896705 4.0730661 4.6946688 4.0680677 15 P 0 ;0,1=51,2=0.000000
L 4.6896705 4.0880612 4.6946688 4.0830628 15 P 0 ;0,1=51,2=0.000000
L 4.6898263 4.2680614 4.684828 4.263063 15 P 0 ;0,1=53,2=0.000000
L 4.6898263 4.2730598 4.6898263 4.2680614 15 P 0 ;0,1=53,2=0.000000
L 4.6898263 4.2830565 4.684828 4.2780582 15 P 0 ;0,1=53,2=0.000000
L 4.6898263 4.2880549 4.6898263 4.2830565 15 P 0 ;0,1=53,2=0.000000
L 4.6946688 4.0630693 4.6896705 4.0580709 15 P 0 ;0,1=51,2=0.000000
L 4.6946688 4.0680677 4.6946688 4.0630693 15 P 0 ;0,1=51,2=0.000000
L 4.6946688 4.0780644 4.6896705 4.0730661 15 P 0 ;0,1=51,2=0.000000
L 4.6946688 4.0830628 4.6946688 4.0780644 15 P 0 ;0,1=51,2=0.000000
L 4.6998231 4.263063 4.7198166 4.2830565 15 P 0 ;0,1=53,2=0.000000
L 4.7046656 4.0730661 4.7246591 4.0730661 15 P 0 ;0,1=51,2=0.000000
L 4.7048215 4.2930533 4.6998231 4.2880549 15 P 0 ;0,1=53,2=0.000000
L 4.7148183 4.2930533 4.7048215 4.2930533 15 P 0 ;0,1=53,2=0.000000
L 4.7196608 4.0580709 4.7196608 4.0880612 15 P 0 ;0,1=51,2=0.000000
L 4.7196608 4.0880612 4.7046656 4.0730661 15 P 0 ;0,1=51,2=0.000000
L 4.7198166 4.263063 4.6998231 4.263063 15 P 0 ;0,1=53,2=0.000000
L 4.7198166 4.2830565 4.7198166 4.2880549 15 P 0 ;0,1=53,2=0.000000
L 4.7198166 4.2880549 4.7148183 4.2930533 15 P 0 ;0,1=53,2=0.000000
L 4.8976378 2.7037401 4.9212598 2.7037401 5 P 0
L 4.9094488 2.6919291 4.9094488 2.7155512 5 P 0
L 4.9318425 4.3170565 4.9368409 4.3120582 15 P 0 ;0,1=48,2=0.000000
L 4.9318425 4.3220549 4.9318425 4.3170565 15 P 0 ;0,1=48,2=0.000000
L 4.9348425 4.151063 4.9348425 4.161063 10 P 0
L 4.9348425 4.151063 5.1148425 4.151063 10 P 0
L 4.9348425 4.251063 4.9348425 4.261063 10 P 0
L 4.9348425 4.261063 5.1148425 4.261063 10 P 0
L 4.9368409 4.297063 4.9318425 4.3020614 15 P 0 ;0,1=48,2=0.000000
L 4.9368409 4.3120582 4.9468377 4.3120582 15 P 0 ;0,1=48,2=0.000000
L 4.9368409 4.3270533 4.9318425 4.3220549 15 P 0 ;0,1=48,2=0.000000
L 4.9468377 4.297063 4.9368409 4.297063 15 P 0 ;0,1=48,2=0.000000
L 4.9468377 4.3120582 4.951836 4.3070598 15 P 0 ;0,1=48,2=0.000000
L 4.9468377 4.3270533 4.9368409 4.3270533 15 P 0 ;0,1=48,2=0.000000
L 4.951836 4.3020614 4.9468377 4.297063 15 P 0 ;0,1=48,2=0.000000
L 4.951836 4.3070598 4.951836 4.3020614 15 P 0 ;0,1=48,2=0.000000
L 4.951836 4.3220549 4.9468377 4.3270533 15 P 0 ;0,1=48,2=0.000000
L 4.9618328 4.3020614 4.9668312 4.297063 15 P 0 ;0,1=48,2=0.000000
L 4.9618328 4.3120582 4.9618328 4.3020614 15 P 0 ;0,1=48,2=0.000000
L 4.9668312 4.297063 4.976828 4.297063 15 P 0 ;0,1=48,2=0.000000
L 4.9718296 4.3220549 4.9618328 4.3120582 15 P 0 ;0,1=48,2=0.000000
L 4.976828 4.297063 4.9818263 4.3020614 15 P 0 ;0,1=48,2=0.000000
L 4.976828 4.3120582 4.9618328 4.3120582 15 P 0 ;0,1=48,2=0.000000
L 4.9818263 4.3020614 4.9818263 4.3070598 15 P 0 ;0,1=48,2=0.000000
L 4.9818263 4.3070598 4.976828 4.3120582 15 P 0 ;0,1=48,2=0.000000
L 4.9818263 4.3270533 4.9718296 4.3220549 15 P 0 ;0,1=48,2=0.000000
L 5.0068897 2.8120079 5.2342519 2.8120079 5 P 0
L 5.0068897 3.9576771 5.2342519 3.9576771 5 P 0
L 5.1013779 4.0944882 5.1013779 4.1244785 15 P 0 ;0,1=50,2=0.000000
L 5.1013779 4.1244785 5.1163731 4.1244785 15 P 0 ;0,1=50,2=0.000000
L 5.1113747 4.104485 5.1213714 4.0944882 15 P 0 ;0,1=50,2=0.000000
L 5.1148425 4.151063 5.1148425 4.161063 10 P 0
L 5.1148425 4.251063 5.1148425 4.261063 10 P 0
L 5.1163731 4.104485 5.1013779 4.104485 15 P 0 ;0,1=50,2=0.000000
L 5.1163731 4.1244785 5.1213714 4.1194801 15 P 0 ;0,1=50,2=0.000000
L 5.1213714 4.1094834 5.1163731 4.104485 15 P 0 ;0,1=50,2=0.000000
L 5.1213714 4.1194801 5.1213714 4.1094834 15 P 0 ;0,1=50,2=0.000000
L 5.1313682 4.1194801 5.1363666 4.1244785 15 P 0 ;0,1=50,2=0.000000
L 5.1363666 4.0944882 5.1313682 4.0994866 15 P 0 ;0,1=50,2=0.000000
L 5.1363666 4.1244785 5.1463634 4.1244785 15 P 0 ;0,1=50,2=0.000000
L 5.141365 4.1094834 5.1463634 4.1094834 15 P 0 ;0,1=50,2=0.000000
L 5.1463634 4.0944882 5.1363666 4.0944882 15 P 0 ;0,1=50,2=0.000000
L 5.1463634 4.1094834 5.141365 4.1094834 15 P 0 ;0,1=50,2=0.000000
L 5.1463634 4.1094834 5.1513617 4.104485 15 P 0 ;0,1=50,2=0.000000
L 5.1463634 4.1244785 5.1513617 4.1194801 15 P 0 ;0,1=50,2=0.000000
L 5.1513617 4.0994866 5.1463634 4.0944882 15 P 0 ;0,1=50,2=0.000000
L 5.1513617 4.104485 5.1513617 4.0994866 15 P 0 ;0,1=50,2=0.000000
L 5.1513617 4.1144817 5.1463634 4.1094834 15 P 0 ;0,1=50,2=0.000000
L 5.1513617 4.1194801 5.1513617 4.1144817 15 P 0 ;0,1=50,2=0.000000
L 5.1613585 4.1094834 5.1713553 4.1144817 15 P 0 ;0,1=50,2=0.000000
L 5.1613585 4.1244785 5.1613585 4.1094834 15 P 0 ;0,1=50,2=0.000000
L 5.1663569 4.0944882 5.1613585 4.0994866 15 P 0 ;0,1=50,2=0.000000
L 5.1713553 4.1144817 5.1763537 4.1144817 15 P 0 ;0,1=50,2=0.000000
L 5.1763537 4.0944882 5.1663569 4.0944882 15 P 0 ;0,1=50,2=0.000000
L 5.1763537 4.1144817 5.181352 4.1094834 15 P 0 ;0,1=50,2=0.000000
L 5.181352 4.0994866 5.1763537 4.0944882 15 P 0 ;0,1=50,2=0.000000
L 5.181352 4.1094834 5.181352 4.0994866 15 P 0 ;0,1=50,2=0.000000
L 5.181352 4.1244785 5.1613585 4.1244785 15 P 0 ;0,1=50,2=0.000000
L 5.1998425 4.263063 5.1998425 4.2930533 15 P 0 ;0,1=52,2=0.000000
L 5.1998425 4.2930533 5.2148377 4.2930533 15 P 0 ;0,1=52,2=0.000000
L 5.2098393 4.2730598 5.219836 4.263063 15 P 0 ;0,1=52,2=0.000000
L 5.2148377 4.2730598 5.1998425 4.2730598 15 P 0 ;0,1=52,2=0.000000
L 5.2148377 4.2930533 5.219836 4.2880549 15 P 0 ;0,1=52,2=0.000000
L 5.219836 4.2780582 5.2148377 4.2730598 15 P 0 ;0,1=52,2=0.000000
L 5.219836 4.2880549 5.219836 4.2780582 15 P 0 ;0,1=52,2=0.000000
L 5.2298328 4.2880549 5.2348312 4.2930533 15 P 0 ;0,1=52,2=0.000000
L 5.2342519 2.8120079 5.2342519 3.9576771 5 P 0
L 5.2348312 4.263063 5.2298328 4.2680614 15 P 0 ;0,1=52,2=0.000000
L 5.2348312 4.2930533 5.244828 4.2930533 15 P 0 ;0,1=52,2=0.000000
L 5.2398296 4.2780582 5.244828 4.2780582 15 P 0 ;0,1=52,2=0.000000
L 5.2398425 4.106378 5.2398425 4.145748 8 P 0
L 5.2398425 4.186378 5.2398425 4.225748 8 P 0
L 5.244828 4.263063 5.2348312 4.263063 15 P 0 ;0,1=52,2=0.000000
L 5.244828 4.2780582 5.2398296 4.2780582 15 P 0 ;0,1=52,2=0.000000
L 5.244828 4.2780582 5.2498263 4.2730598 15 P 0 ;0,1=52,2=0.000000
L 5.244828 4.2930533 5.2498263 4.2880549 15 P 0 ;0,1=52,2=0.000000
L 5.2498263 4.2680614 5.244828 4.263063 15 P 0 ;0,1=52,2=0.000000
L 5.2498263 4.2730598 5.2498263 4.2680614 15 P 0 ;0,1=52,2=0.000000
L 5.2498263 4.2830565 5.244828 4.2780582 15 P 0 ;0,1=52,2=0.000000
L 5.2498263 4.2880549 5.2498263 4.2830565 15 P 0 ;0,1=52,2=0.000000
L 5.2598231 4.2880549 5.2648215 4.2930533 15 P 0 ;0,1=52,2=0.000000
L 5.2648215 4.263063 5.2598231 4.2680614 15 P 0 ;0,1=52,2=0.000000
L 5.2648215 4.2930533 5.2748183 4.2930533 15 P 0 ;0,1=52,2=0.000000
L 5.2698199 4.2780582 5.2748183 4.2780582 15 P 0 ;0,1=52,2=0.000000
L 5.2748183 4.263063 5.2648215 4.263063 15 P 0 ;0,1=52,2=0.000000
L 5.2748183 4.2780582 5.2698199 4.2780582 15 P 0 ;0,1=52,2=0.000000
L 5.2748183 4.2780582 5.2798166 4.2730598 15 P 0 ;0,1=52,2=0.000000
L 5.2748183 4.2930533 5.2798166 4.2880549 15 P 0 ;0,1=52,2=0.000000
L 5.2798166 4.2680614 5.2748183 4.263063 15 P 0 ;0,1=52,2=0.000000
L 5.2798166 4.2730598 5.2798166 4.2680614 15 P 0 ;0,1=52,2=0.000000
L 5.2798166 4.2830565 5.2748183 4.2780582 15 P 0 ;0,1=52,2=0.000000
L 5.2798166 4.2880549 5.2798166 4.2830565 15 P 0 ;0,1=52,2=0.000000
L 5.3917374 3.406989 5.3967358 3.4019907 15 P 0 ;0,1=47,2=0.000000
L 5.3917374 3.4119874 5.3917374 3.406989 15 P 0 ;0,1=47,2=0.000000
L 5.3967213 3.4644882 5.3967213 3.9824818 8 P 0
L 5.3967213 3.4644882 5.8312205 3.4644882 8 P 0
L 5.3967213 3.9824818 5.3967213 4.2244882 8 P 0
L 5.3967213 4.2244882 5.8312205 4.2244882 8 P 0
L 5.3967358 3.3869955 5.3917374 3.3919939 15 P 0 ;0,1=47,2=0.000000
L 5.3967358 3.4019907 5.4067326 3.4019907 15 P 0 ;0,1=47,2=0.000000
L 5.3967358 3.4169858 5.3917374 3.4119874 15 P 0 ;0,1=47,2=0.000000
L 5.4067326 3.3869955 5.3967358 3.3869955 15 P 0 ;0,1=47,2=0.000000
L 5.4067326 3.4019907 5.4117309 3.3969923 15 P 0 ;0,1=47,2=0.000000
L 5.4067326 3.4169858 5.3967358 3.4169858 15 P 0 ;0,1=47,2=0.000000
L 5.4117309 3.3919939 5.4067326 3.3869955 15 P 0 ;0,1=47,2=0.000000
L 5.4117309 3.3969923 5.4117309 3.3919939 15 P 0 ;0,1=47,2=0.000000
L 5.4117309 3.4119874 5.4067326 3.4169858 15 P 0 ;0,1=47,2=0.000000
L 5.4217277 3.3869955 5.4317245 3.3969923 15 P 0 ;0,1=47,2=0.000000
L 5.4217277 3.4169858 5.4217277 3.3869955 15 P 0 ;0,1=47,2=0.000000
L 5.4317245 3.3969923 5.4417212 3.3869955 15 P 0 ;0,1=47,2=0.000000
L 5.4417212 3.3869955 5.4417212 3.4169858 15 P 0 ;0,1=47,2=0.000000
L 5.451718 3.3869955 5.4617148 3.3869955 15 P 0 ;0,1=47,2=0.000000
L 5.4567164 3.3869955 5.4567164 3.4169858 15 P 0 ;0,1=47,2=0.000000
L 5.4567164 3.4169858 5.451718 3.4119874 15 P 0 ;0,1=47,2=0.000000
L 5.4617148 3.3869955 5.4567164 3.3869955 15 P 0 ;0,1=47,2=0.000000
L 5.5227559 0.8574803 5.5227559 2.4574803 5 P 0
L 5.60289 3.2467577 5.6078884 3.2417593 15 P 0 ;0,1=137,2=0.000000
L 5.60289 3.2667512 5.60289 3.2467577 15 P 0 ;0,1=137,2=0.000000
L 5.6078884 3.2417593 5.6178852 3.2417593 15 P 0 ;0,1=137,2=0.000000
L 5.6078884 3.2717496 5.60289 3.2667512 15 P 0 ;0,1=137,2=0.000000
L 5.6178852 3.2417593 5.6228835 3.2467577 15 P 0 ;0,1=137,2=0.000000
L 5.6178852 3.2717496 5.6078884 3.2717496 15 P 0 ;0,1=137,2=0.000000
L 5.6228835 3.2667512 5.6178852 3.2717496 15 P 0 ;0,1=137,2=0.000000
L 5.6328803 3.2417593 5.6528738 3.2617528 15 P 0 ;0,1=137,2=0.000000
L 5.6378787 3.2717496 5.6328803 3.2667512 15 P 0 ;0,1=137,2=0.000000
L 5.6478755 3.2717496 5.6378787 3.2717496 15 P 0 ;0,1=137,2=0.000000
L 5.6526107 2.7195687 5.6576091 2.7145703 15 P 0 ;0,1=40,2=0.000000
L 5.6526107 2.7445606 5.6526107 2.7195687 15 P 0 ;0,1=40,2=0.000000
L 5.6528738 3.2417593 5.6328803 3.2417593 15 P 0 ;0,1=137,2=0.000000
L 5.6528738 3.2617528 5.6528738 3.2667512 15 P 0 ;0,1=137,2=0.000000
L 5.6528738 3.2667512 5.6478755 3.2717496 15 P 0 ;0,1=137,2=0.000000
L 5.6576091 2.7145703 5.6676059 2.7145703 15 P 0 ;0,1=40,2=0.000000
L 5.6676059 2.7145703 5.6726042 2.7195687 15 P 0 ;0,1=40,2=0.000000
L 5.6726042 2.7195687 5.6726042 2.7445606 15 P 0 ;0,1=40,2=0.000000
L 5.682601 2.7145703 5.6925978 2.7145703 15 P 0 ;0,1=40,2=0.000000
L 5.6875994 2.7145703 5.6875994 2.7445606 15 P 0 ;0,1=40,2=0.000000
L 5.6875994 2.7445606 5.682601 2.7395622 15 P 0 ;0,1=40,2=0.000000
L 5.6925978 2.7145703 5.6875994 2.7145703 15 P 0 ;0,1=40,2=0.000000
L 5.7075929 2.7195687 5.7075929 2.7395622 15 P 0 ;0,1=40,2=0.000000
L 5.7075929 2.7395622 5.7125913 2.7445606 15 P 0 ;0,1=40,2=0.000000
L 5.7125913 2.7145703 5.7075929 2.7195687 15 P 0 ;0,1=40,2=0.000000
L 5.7125913 2.7445606 5.7225881 2.7445606 15 P 0 ;0,1=40,2=0.000000
L 5.7225881 2.7145703 5.7125913 2.7145703 15 P 0 ;0,1=40,2=0.000000
L 5.7225881 2.7445606 5.7275864 2.7395622 15 P 0 ;0,1=40,2=0.000000
L 5.7275864 2.7195687 5.7225881 2.7145703 15 P 0 ;0,1=40,2=0.000000
L 5.7275864 2.7395622 5.7275864 2.7195687 15 P 0 ;0,1=40,2=0.000000
L 5.7445845 3.2507262 5.7495829 3.2457278 15 P 0 ;0,1=138,2=0.000000
L 5.7445845 3.2707197 5.7445845 3.2507262 15 P 0 ;0,1=138,2=0.000000
L 5.7465748 3.3232205 5.8065748 3.3232205 8 P 0
L 5.7465748 3.3992205 5.8065748 3.3992205 8 P 0
L 5.7495829 3.2457278 5.7595797 3.2457278 15 P 0 ;0,1=138,2=0.000000
L 5.7495829 3.2757181 5.7445845 3.2707197 15 P 0 ;0,1=138,2=0.000000
L 5.7595797 3.2457278 5.764578 3.2507262 15 P 0 ;0,1=138,2=0.000000
L 5.7595797 3.2757181 5.7495829 3.2757181 15 P 0 ;0,1=138,2=0.000000
L 5.764578 3.2707197 5.7595797 3.2757181 15 P 0 ;0,1=138,2=0.000000
L 5.7745748 3.2457278 5.7845716 3.2457278 15 P 0 ;0,1=138,2=0.000000
L 5.7789398 0.6898312 5.7789398 2.6898312 4 P 0
L 5.7795732 3.2457278 5.7795732 3.2757181 15 P 0 ;0,1=138,2=0.000000
L 5.7795732 3.2757181 5.7745748 3.2707197 15 P 0 ;0,1=138,2=0.000000
L 5.7845716 3.2457278 5.7795732 3.2457278 15 P 0 ;0,1=138,2=0.000000
L 5.8312205 3.4644882 5.8312205 4.2244882 8 P 0
L 5.8988189 3.6636614 5.8988189 3.6685827 5 P 0
L 5.8988189 3.6636614 6.0208661 3.6636614 5 P 0
L 5.8988189 3.7335433 5.8988189 3.7384646 5 P 0
L 5.8988189 3.7384646 6.0208661 3.7384646 5 P 0
L 5.9098425 3.7922834 5.9098425 3.837559 10 P 0
L 5.9098425 3.7922834 6.0194488 3.7922834 10 P 0
L 5.9098425 4.0383464 5.9098425 4.2056693 10 P 0
L 5.9098425 4.2056693 6.3098425 4.2056693 10 P 0
L 5.9738522 1.8695703 5.9938457 1.8695703 15 P 0 ;0,1=79,2=0.000000
L 5.9738522 1.8995606 5.9738522 1.8695703 15 P 0 ;0,1=79,2=0.000000
L 5.9851575 2.366063 6.0245275 2.366063 8 P 0
L 5.986742 2.4616142 5.986742 2.4766094 15 P 0 ;0,1=68,2=90.000000
L 5.986742 2.4766094 5.9917404 2.4816077 15 P 0 ;0,1=68,2=90.000000
L 5.986742 2.4966029 5.9917404 2.4916045 15 P 0 ;0,1=68,2=90.000000
L 5.986742 2.5065997 5.986742 2.4966029 15 P 0 ;0,1=68,2=90.000000
L 5.9917404 2.4816077 6.0017371 2.4816077 15 P 0 ;0,1=68,2=90.000000
L 5.9917404 2.4916045 5.9967388 2.4916045 15 P 0 ;0,1=68,2=90.000000
L 5.9917404 2.511598 5.986742 2.5065997 15 P 0 ;0,1=68,2=90.000000
L 5.9967388 2.4916045 6.0017371 2.4966029 15 P 0 ;0,1=68,2=90.000000
L 6.0017371 2.4816077 6.0067355 2.4766094 15 P 0 ;0,1=68,2=90.000000
L 6.0017371 2.4966029 6.0017371 2.511598 15 P 0 ;0,1=68,2=90.000000
L 6.0038425 1.8695703 6.0138393 1.8695703 15 P 0 ;0,1=79,2=0.000000
L 6.0067355 2.471611 6.0167323 2.4816077 15 P 0 ;0,1=68,2=90.000000
L 6.0067355 2.4766094 6.0067355 2.4616142 15 P 0 ;0,1=68,2=90.000000
L 6.0088409 1.8695703 6.0088409 1.8995606 15 P 0 ;0,1=79,2=0.000000
L 6.0088409 1.8995606 6.0038425 1.8945622 15 P 0 ;0,1=79,2=0.000000
L 6.0117339 2.4916045 6.0167323 2.4966029 15 P 0 ;0,1=68,2=90.000000
L 6.0117339 2.511598 5.9917404 2.511598 15 P 0 ;0,1=68,2=90.000000
L 6.0133546 2.2355687 6.018353 2.2305703 15 P 0 ;0,1=45,2=0.000000
L 6.0133546 2.2605606 6.0133546 2.2355687 15 P 0 ;0,1=45,2=0.000000
L 6.0138393 1.8695703 6.0088409 1.8695703 15 P 0 ;0,1=79,2=0.000000
L 6.0167323 2.4616142 5.986742 2.4616142 15 P 0 ;0,1=68,2=90.000000
L 6.0167323 2.4966029 6.0167323 2.5065997 15 P 0 ;0,1=68,2=90.000000
L 6.0167323 2.5065997 6.0117339 2.511598 15 P 0 ;0,1=68,2=90.000000
L 6.018353 2.2305703 6.0283498 2.2305703 15 P 0 ;0,1=45,2=0.000000
L 6.0208661 3.6636614 6.0208661 3.6685827 5 P 0
L 6.0208661 3.7335433 6.0208661 3.7384646 5 P 0
L 6.0283498 2.2305703 6.0333481 2.2355687 15 P 0 ;0,1=45,2=0.000000
L 6.0333481 2.2355687 6.0333481 2.2605606 15 P 0 ;0,1=45,2=0.000000
L 6.0433449 2.2305703 6.0633384 2.2505638 15 P 0 ;0,1=45,2=0.000000
L 6.0467813 2.4242897 6.0517797 2.4192913 15 P 0 ;0,1=117,2=90.000000
L 6.0467813 2.4342865 6.0467813 2.4242897 15 P 0 ;0,1=117,2=90.000000
L 6.0467813 2.45428 6.0517797 2.4492816 15 P 0 ;0,1=117,2=90.000000
L 6.0467813 2.4642768 6.0467813 2.45428 15 P 0 ;0,1=117,2=90.000000
L 6.0467813 2.4842703 6.0517797 2.4792719 15 P 0 ;0,1=117,2=90.000000
L 6.0467813 2.4942671 6.0467813 2.4842703 15 P 0 ;0,1=117,2=90.000000
L 6.0483433 2.2605606 6.0433449 2.2555622 15 P 0 ;0,1=45,2=0.000000
L 6.0517797 2.4192913 6.0717732 2.4192913 15 P 0 ;0,1=117,2=90.000000
L 6.0517797 2.4392848 6.0467813 2.4342865 15 P 0 ;0,1=117,2=90.000000
L 6.0517797 2.4692751 6.0467813 2.4642768 15 P 0 ;0,1=117,2=90.000000
L 6.0517797 2.4992654 6.0467813 2.4942671 15 P 0 ;0,1=117,2=90.000000
L 6.0567781 2.4692751 6.0517797 2.4692751 15 P 0 ;0,1=117,2=90.000000
L 6.0567781 2.4992654 6.0517797 2.4992654 15 P 0 ;0,1=117,2=90.000000
L 6.0583401 2.2605606 6.0483433 2.2605606 15 P 0 ;0,1=45,2=0.000000
L 6.0628425 3.536378 6.0628425 3.575748 8 P 0
L 6.0633384 2.2305703 6.0433449 2.2305703 15 P 0 ;0,1=45,2=0.000000
L 6.0633384 2.2505638 6.0633384 2.2555622 15 P 0 ;0,1=45,2=0.000000
L 6.0633384 2.2555622 6.0583401 2.2605606 15 P 0 ;0,1=45,2=0.000000
L 6.067874 1.3880315 6.067874 1.9140945 4 P 0
L 6.067874 1.3880315 6.571811 1.3880315 4 P 0
L 6.067874 1.9140945 6.571811 1.9140945 4 P 0
L 6.0698522 3.6595703 6.0848474 3.6595703 15 P 0 ;0,1=103,2=0.000000
L 6.0698522 3.6895606 6.0698522 3.6595703 15 P 0 ;0,1=103,2=0.000000
L 6.0717732 2.4192913 6.0767716 2.4242897 15 P 0 ;0,1=117,2=90.000000
L 6.0767716 2.4242897 6.0767716 2.4342865 15 P 0 ;0,1=117,2=90.000000
L 6.0767716 2.4342865 6.0717732 2.4392848 15 P 0 ;0,1=117,2=90.000000
L 6.0767716 2.4492816 6.0567781 2.4692751 15 P 0 ;0,1=117,2=90.000000
L 6.0767716 2.4692751 6.0767716 2.4492816 15 P 0 ;0,1=117,2=90.000000
L 6.0767716 2.4792719 6.0567781 2.4992654 15 P 0 ;0,1=117,2=90.000000
L 6.0767716 2.4992654 6.0767716 2.4792719 15 P 0 ;0,1=117,2=90.000000
L 6.0816929 2.0935811 6.0866913 2.0885827 15 P 0 ;0,1=118,2=0.000000
L 6.0816929 2.1135746 6.0816929 2.0935811 15 P 0 ;0,1=118,2=0.000000
L 6.0848474 3.6595703 6.0898457 3.6645687 15 P 0 ;0,1=103,2=0.000000
L 6.0848474 3.6895606 6.0698522 3.6895606 15 P 0 ;0,1=103,2=0.000000
L 6.0866913 2.0885827 6.0966881 2.0885827 15 P 0 ;0,1=118,2=0.000000
L 6.0866913 2.118573 6.0816929 2.1135746 15 P 0 ;0,1=118,2=0.000000
L 6.0898457 3.6645687 6.0898457 3.6845622 15 P 0 ;0,1=103,2=0.000000
L 6.0898457 3.6845622 6.0848474 3.6895606 15 P 0 ;0,1=103,2=0.000000
L 6.0966881 2.0885827 6.1016864 2.0935811 15 P 0 ;0,1=118,2=0.000000
L 6.0966881 2.118573 6.0866913 2.118573 15 P 0 ;0,1=118,2=0.000000
L 6.0998425 2.143063 6.1498425 2.143063 8 P 0
L 6.0998425 2.199063 6.1498425 2.199063 8 P 0
L 6.0998425 3.6595703 6.1098393 3.6595703 15 P 0 ;0,1=103,2=0.000000
L 6.1016864 2.1135746 6.0966881 2.118573 15 P 0 ;0,1=118,2=0.000000
L 6.1031575 2.461063 6.1425275 2.461063 8 P 0
L 6.1048409 3.6595703 6.1048409 3.6895606 15 P 0 ;0,1=103,2=0.000000
L 6.1048409 3.6895606 6.0998425 3.6845622 15 P 0 ;0,1=103,2=0.000000
L 6.1048522 2.5255906 6.1048522 2.5405858 15 P 0 ;0,1=36,2=90.000000
L 6.1048522 2.5405858 6.1098506 2.5455841 15 P 0 ;0,1=36,2=90.000000
L 6.1048522 2.5555809 6.1198473 2.5555809 15 P 0 ;0,1=36,2=90.000000
L 6.1048522 2.5755744 6.1048522 2.5555809 15 P 0 ;0,1=36,2=90.000000
L 6.1098393 3.6595703 6.1048409 3.6595703 15 P 0 ;0,1=103,2=0.000000
L 6.1098506 2.5455841 6.1198473 2.5455841 15 P 0 ;0,1=36,2=90.000000
L 6.1116832 2.0885827 6.1316767 2.1085762 15 P 0 ;0,1=118,2=0.000000
L 6.114849 2.5655777 6.114849 2.5705761 15 P 0 ;0,1=36,2=90.000000
L 6.114849 2.5705761 6.1198473 2.5755744 15 P 0 ;0,1=36,2=90.000000
L 6.1166816 2.118573 6.1116832 2.1135746 15 P 0 ;0,1=118,2=0.000000
L 6.1198473 2.5455841 6.1248457 2.5405858 15 P 0 ;0,1=36,2=90.000000
L 6.1198473 2.5555809 6.114849 2.5655777 15 P 0 ;0,1=36,2=90.000000
L 6.1198473 2.5755744 6.1298441 2.5755744 15 P 0 ;0,1=36,2=90.000000
L 6.1218522 3.4195655 6.1218522 3.4045703 15 P 0 ;0,1=85,2=0.000000
L 6.1218522 3.4195655 6.131849 3.4195655 15 P 0 ;0,1=85,2=0.000000
L 6.1218522 3.4345606 6.1218522 3.4195655 15 P 0 ;0,1=85,2=0.000000
L 6.1248457 2.5355874 6.1348425 2.5455841 15 P 0 ;0,1=36,2=90.000000
L 6.1248457 2.5405858 6.1248457 2.5255906 15 P 0 ;0,1=36,2=90.000000
L 6.1266784 2.118573 6.1166816 2.118573 15 P 0 ;0,1=118,2=0.000000
L 6.1298441 2.5755744 6.1348425 2.5705761 15 P 0 ;0,1=36,2=90.000000
L 6.1316767 2.0885827 6.1116832 2.0885827 15 P 0 ;0,1=118,2=0.000000
L 6.1316767 2.1085762 6.1316767 2.1135746 15 P 0 ;0,1=118,2=0.000000
L 6.1316767 2.1135746 6.1266784 2.118573 15 P 0 ;0,1=118,2=0.000000
L 6.131849 3.4195655 6.1218522 3.4195655 15 P 0 ;0,1=85,2=0.000000
L 6.1348425 2.5255906 6.1048522 2.5255906 15 P 0 ;0,1=36,2=90.000000
L 6.1348425 2.5605793 6.1298441 2.5555809 15 P 0 ;0,1=36,2=90.000000
L 6.1348425 2.5705761 6.1348425 2.5605793 15 P 0 ;0,1=36,2=90.000000
L 6.1416735 2.0885827 6.1516703 2.0885827 15 P 0 ;0,1=118,2=0.000000
L 6.1418457 3.4345606 6.1218522 3.4345606 15 P 0 ;0,1=85,2=0.000000
L 6.1466719 2.0885827 6.1466719 2.118573 15 P 0 ;0,1=118,2=0.000000
L 6.1466719 2.118573 6.1416735 2.1135746 15 P 0 ;0,1=118,2=0.000000
L 6.1516703 2.0885827 6.1466719 2.0885827 15 P 0 ;0,1=118,2=0.000000
L 6.1518425 3.4045703 6.1618393 3.4045703 15 P 0 ;0,1=85,2=0.000000
L 6.1568409 3.4045703 6.1568409 3.4345606 15 P 0 ;0,1=85,2=0.000000
L 6.1568409 3.4345606 6.1518425 3.4295622 15 P 0 ;0,1=85,2=0.000000
L 6.1618393 3.4045703 6.1568409 3.4045703 15 P 0 ;0,1=85,2=0.000000
L 6.1747341 2.8888567 6.1797325 2.8838583 15 P 0 ;0,1=132,2=90.000000
L 6.1747341 2.8988535 6.1747341 2.8888567 15 P 0 ;0,1=132,2=90.000000
L 6.1747341 2.9138486 6.1747341 2.9338421 15 P 0 ;0,1=132,2=90.000000
L 6.1747341 2.9338421 6.1797325 2.9338421 15 P 0 ;0,1=132,2=90.000000
L 6.1761023 2.2176378 6.3887008 2.2176378 9 P 0
L 6.1761023 2.4144882 6.3335827 2.4144882 9 P 0
L 6.1771653 2.5325575 6.1821637 2.5275591 15 P 0 ;0,1=129,2=0.000000
L 6.1771653 2.552551 6.1771653 2.5325575 15 P 0 ;0,1=129,2=0.000000
L 6.1781496 2.5817701 6.183148 2.5767717 15 P 0 ;0,1=128,2=0.000000
L 6.1781496 2.6017636 6.1781496 2.5817701 15 P 0 ;0,1=128,2=0.000000
L 6.1791338 2.6309827 6.1841322 2.6259843 15 P 0 ;0,1=127,2=0.000000
L 6.1791338 2.6509762 6.1791338 2.6309827 15 P 0 ;0,1=127,2=0.000000
L 6.1791338 2.6821638 6.1841322 2.6771654 15 P 0 ;0,1=130,2=0.000000
L 6.1791338 2.7021573 6.1791338 2.6821638 15 P 0 ;0,1=130,2=0.000000
L 6.1797325 2.8838583 6.199726 2.8838583 15 P 0 ;0,1=132,2=90.000000
L 6.1797325 2.9038518 6.1747341 2.8988535 15 P 0 ;0,1=132,2=90.000000
L 6.1797325 2.9338421 6.199726 2.9138486 15 P 0 ;0,1=132,2=90.000000
L 6.1821637 2.5275591 6.1921605 2.5275591 15 P 0 ;0,1=129,2=0.000000
L 6.1821637 2.5575494 6.1771653 2.552551 15 P 0 ;0,1=129,2=0.000000
L 6.1830708 2.4409449 6.1830708 2.4709352 15 P 0 ;0,1=70,2=0.000000
L 6.1830708 2.4709352 6.198066 2.4709352 15 P 0 ;0,1=70,2=0.000000
L 6.183148 2.5767717 6.1931448 2.5767717 15 P 0 ;0,1=128,2=0.000000
L 6.183148 2.606762 6.1781496 2.6017636 15 P 0 ;0,1=128,2=0.000000
L 6.1841322 2.6259843 6.194129 2.6259843 15 P 0 ;0,1=127,2=0.000000
L 6.1841322 2.6559746 6.1791338 2.6509762 15 P 0 ;0,1=127,2=0.000000
L 6.1841322 2.6771654 6.194129 2.6771654 15 P 0 ;0,1=130,2=0.000000
L 6.1841322 2.7071557 6.1791338 2.7021573 15 P 0 ;0,1=130,2=0.000000
L 6.1921605 2.5275591 6.1971588 2.5325575 15 P 0 ;0,1=129,2=0.000000
L 6.1921605 2.5575494 6.1821637 2.5575494 15 P 0 ;0,1=129,2=0.000000
L 6.1930676 2.4509417 6.2030643 2.4409449 15 P 0 ;0,1=70,2=0.000000
L 6.1931448 2.5767717 6.1981431 2.5817701 15 P 0 ;0,1=128,2=0.000000
L 6.1931448 2.606762 6.183148 2.606762 15 P 0 ;0,1=128,2=0.000000
L 6.194129 2.6259843 6.1991273 2.6309827 15 P 0 ;0,1=127,2=0.000000
L 6.194129 2.6559746 6.1841322 2.6559746 15 P 0 ;0,1=127,2=0.000000
L 6.194129 2.6771654 6.1991273 2.6821638 15 P 0 ;0,1=130,2=0.000000
L 6.194129 2.7071557 6.1841322 2.7071557 15 P 0 ;0,1=130,2=0.000000
L 6.1971588 2.552551 6.1921605 2.5575494 15 P 0 ;0,1=129,2=0.000000
L 6.198066 2.4509417 6.1830708 2.4509417 15 P 0 ;0,1=70,2=0.000000
L 6.198066 2.4709352 6.2030643 2.4659368 15 P 0 ;0,1=70,2=0.000000
L 6.1981431 2.6017636 6.1931448 2.606762 15 P 0 ;0,1=128,2=0.000000
L 6.1991273 2.6509762 6.194129 2.6559746 15 P 0 ;0,1=127,2=0.000000
L 6.1991273 2.7021573 6.194129 2.7071557 15 P 0 ;0,1=130,2=0.000000
L 6.199726 2.8838583 6.2047244 2.8888567 15 P 0 ;0,1=132,2=90.000000
L 6.199726 2.9138486 6.2047244 2.9138486 15 P 0 ;0,1=132,2=90.000000
L 6.2030643 2.4559401 6.198066 2.4509417 15 P 0 ;0,1=70,2=0.000000
L 6.2030643 2.4659368 6.2030643 2.4559401 15 P 0 ;0,1=70,2=0.000000
L 6.2047244 2.8888567 6.2047244 2.8988535 15 P 0 ;0,1=132,2=90.000000
L 6.2047244 2.8988535 6.199726 2.9038518 15 P 0 ;0,1=132,2=90.000000
L 6.2063546 3.4505703 6.2213498 3.4505703 15 P 0 ;0,1=102,2=0.000000
L 6.2063546 3.4805606 6.2063546 3.4505703 15 P 0 ;0,1=102,2=0.000000
L 6.2071556 2.5275591 6.2171524 2.5275591 15 P 0 ;0,1=129,2=0.000000
L 6.2081399 2.5767717 6.2181367 2.5767717 15 P 0 ;0,1=128,2=0.000000
L 6.2088189 3.6636614 6.2088189 3.6685827 5 P 0
L 6.2088189 3.6636614 6.3308661 3.6636614 5 P 0
L 6.2088189 3.7335433 6.2088189 3.7384646 5 P 0
L 6.2088189 3.7384646 6.3308661 3.7384646 5 P 0
L 6.2091241 2.6259843 6.2191209 2.6259843 15 P 0 ;0,1=127,2=0.000000
L 6.2091241 2.6821638 6.2141225 2.6771654 15 P 0 ;0,1=130,2=0.000000
L 6.2091241 2.6971589 6.2141225 2.6921606 15 P 0 ;0,1=130,2=0.000000
L 6.2091241 2.7021573 6.2091241 2.6971589 15 P 0 ;0,1=130,2=0.000000
L 6.2096456 2.0580709 6.2096456 2.0880612 15 P 0 ;0,1=73,2=0.000000
L 6.2096456 2.0880612 6.2246408 2.0880612 15 P 0 ;0,1=73,2=0.000000
L 6.212154 2.5275591 6.212154 2.5575494 15 P 0 ;0,1=129,2=0.000000
L 6.212154 2.5575494 6.2071556 2.552551 15 P 0 ;0,1=129,2=0.000000
L 6.2130611 2.4459433 6.2130611 2.4409449 15 P 0 ;0,1=70,2=0.000000
L 6.2130611 2.4709352 6.2330546 2.4709352 15 P 0 ;0,1=70,2=0.000000
L 6.2131383 2.5767717 6.2131383 2.606762 15 P 0 ;0,1=128,2=0.000000
L 6.2131383 2.606762 6.2081399 2.6017636 15 P 0 ;0,1=128,2=0.000000
L 6.2138189 3.5286614 6.2138189 3.5335827 5 P 0
L 6.2138189 3.5286614 6.3358661 3.5286614 5 P 0
L 6.2138189 3.5985433 6.2138189 3.6034646 5 P 0
L 6.2138189 3.6034646 6.3358661 3.6034646 5 P 0
L 6.2141225 2.6259843 6.2141225 2.6559746 15 P 0 ;0,1=127,2=0.000000
L 6.2141225 2.6559746 6.2091241 2.6509762 15 P 0 ;0,1=127,2=0.000000
L 6.2141225 2.6771654 6.2241193 2.6771654 15 P 0 ;0,1=130,2=0.000000
L 6.2141225 2.6921606 6.2291176 2.6921606 15 P 0 ;0,1=130,2=0.000000
L 6.2141225 2.7071557 6.2091241 2.7021573 15 P 0 ;0,1=130,2=0.000000
L 6.2151575 2.156063 6.2545275 2.156063 8 P 0
L 6.215937 2.7613386 6.215937 2.8213386 8 P 0
L 6.2171524 2.5275591 6.212154 2.5275591 15 P 0 ;0,1=129,2=0.000000
L 6.2181367 2.5767717 6.2131383 2.5767717 15 P 0 ;0,1=128,2=0.000000
L 6.2191209 2.6259843 6.2141225 2.6259843 15 P 0 ;0,1=127,2=0.000000
L 6.2196424 2.0680677 6.2296391 2.0580709 15 P 0 ;0,1=73,2=0.000000
L 6.2213498 3.4505703 6.2263481 3.4555687 15 P 0 ;0,1=102,2=0.000000
L 6.2213498 3.4805606 6.2063546 3.4805606 15 P 0 ;0,1=102,2=0.000000
L 6.2241193 2.6771654 6.2291176 2.6821638 15 P 0 ;0,1=130,2=0.000000
L 6.2241193 2.7071557 6.2141225 2.7071557 15 P 0 ;0,1=130,2=0.000000
L 6.2241732 3.7922834 6.3098425 3.7922834 10 P 0
L 6.2246408 2.0680677 6.2096456 2.0680677 15 P 0 ;0,1=73,2=0.000000
L 6.2246408 2.0880612 6.2296391 2.0830628 15 P 0 ;0,1=73,2=0.000000
L 6.2263481 3.4555687 6.2263481 3.4755622 15 P 0 ;0,1=102,2=0.000000
L 6.2263481 3.4755622 6.2213498 3.4805606 15 P 0 ;0,1=102,2=0.000000
L 6.2291176 2.6821638 6.2291176 2.7021573 15 P 0 ;0,1=130,2=0.000000
L 6.2291176 2.7021573 6.2241193 2.7071557 15 P 0 ;0,1=130,2=0.000000
L 6.2296391 2.0730661 6.2246408 2.0680677 15 P 0 ;0,1=73,2=0.000000
L 6.2296391 2.0830628 6.2296391 2.0730661 15 P 0 ;0,1=73,2=0.000000
L 6.2321475 2.5325575 6.2321475 2.552551 15 P 0 ;0,1=129,2=0.000000
L 6.2321475 2.552551 6.2371459 2.5575494 15 P 0 ;0,1=129,2=0.000000
L 6.2330546 2.4659368 6.2130611 2.4459433 15 P 0 ;0,1=70,2=0.000000
L 6.2330546 2.4709352 6.2330546 2.4659368 15 P 0 ;0,1=70,2=0.000000
L 6.2331318 2.5767717 6.2431286 2.5767717 15 P 0 ;0,1=128,2=0.000000
L 6.234116 2.6259843 6.2541095 2.6459778 15 P 0 ;0,1=127,2=0.000000
L 6.2363449 3.4505703 6.2563384 3.4705638 15 P 0 ;0,1=102,2=0.000000
L 6.2371459 2.5275591 6.2321475 2.5325575 15 P 0 ;0,1=129,2=0.000000
L 6.2371459 2.5575494 6.2471427 2.5575494 15 P 0 ;0,1=129,2=0.000000
L 6.2381302 2.5767717 6.2381302 2.606762 15 P 0 ;0,1=128,2=0.000000
L 6.2381302 2.606762 6.2331318 2.6017636 15 P 0 ;0,1=128,2=0.000000
L 6.2391144 2.6559746 6.234116 2.6509762 15 P 0 ;0,1=127,2=0.000000
L 6.2396359 2.0830628 6.2446343 2.0880612 15 P 0 ;0,1=73,2=0.000000
L 6.2413433 3.4805606 6.2363449 3.4755622 15 P 0 ;0,1=102,2=0.000000
L 6.2431286 2.5767717 6.2381302 2.5767717 15 P 0 ;0,1=128,2=0.000000
L 6.2446343 2.0580709 6.2396359 2.0630693 15 P 0 ;0,1=73,2=0.000000
L 6.2446343 2.0880612 6.2546311 2.0880612 15 P 0 ;0,1=73,2=0.000000
L 6.2471427 2.5275591 6.2371459 2.5275591 15 P 0 ;0,1=129,2=0.000000
L 6.2471427 2.5575494 6.252141 2.552551 15 P 0 ;0,1=129,2=0.000000
L 6.2491112 2.6559746 6.2391144 2.6559746 15 P 0 ;0,1=127,2=0.000000
L 6.2496327 2.0730661 6.2546311 2.0730661 15 P 0 ;0,1=73,2=0.000000
L 6.2513401 3.4805606 6.2413433 3.4805606 15 P 0 ;0,1=102,2=0.000000
L 6.252141 2.5325575 6.2471427 2.5275591 15 P 0 ;0,1=129,2=0.000000
L 6.252141 2.552551 6.252141 2.5325575 15 P 0 ;0,1=129,2=0.000000
L 6.2541095 2.6259843 6.234116 2.6259843 15 P 0 ;0,1=127,2=0.000000
L 6.2541095 2.6459778 6.2541095 2.6509762 15 P 0 ;0,1=127,2=0.000000
L 6.2541095 2.6509762 6.2491112 2.6559746 15 P 0 ;0,1=127,2=0.000000
L 6.2546311 2.0580709 6.2446343 2.0580709 15 P 0 ;0,1=73,2=0.000000
L 6.2546311 2.0730661 6.2496327 2.0730661 15 P 0 ;0,1=73,2=0.000000
L 6.2546311 2.0730661 6.2596294 2.0680677 15 P 0 ;0,1=73,2=0.000000
L 6.2546311 2.0880612 6.2596294 2.0830628 15 P 0 ;0,1=73,2=0.000000
L 6.2563384 3.4505703 6.2363449 3.4505703 15 P 0 ;0,1=102,2=0.000000
L 6.2563384 3.4705638 6.2563384 3.4755622 15 P 0 ;0,1=102,2=0.000000
L 6.2563384 3.4755622 6.2513401 3.4805606 15 P 0 ;0,1=102,2=0.000000
L 6.2596294 2.0630693 6.2546311 2.0580709 15 P 0 ;0,1=73,2=0.000000
L 6.2596294 2.0680677 6.2596294 2.0630693 15 P 0 ;0,1=73,2=0.000000
L 6.2596294 2.0780644 6.2546311 2.0730661 15 P 0 ;0,1=73,2=0.000000
L 6.2596294 2.0830628 6.2596294 2.0780644 15 P 0 ;0,1=73,2=0.000000
L 6.2698619 3.0485687 6.2748603 3.0435703 15 P 0 ;0,1=114,2=0.000000
L 6.2698619 3.0685622 6.2698619 3.0485687 15 P 0 ;0,1=114,2=0.000000
L 6.2748603 3.0435703 6.2848571 3.0435703 15 P 0 ;0,1=114,2=0.000000
L 6.2748603 3.0735606 6.2698619 3.0685622 15 P 0 ;0,1=114,2=0.000000
L 6.2848571 3.0435703 6.2898554 3.0485687 15 P 0 ;0,1=114,2=0.000000
L 6.2848571 3.0735606 6.2748603 3.0735606 15 P 0 ;0,1=114,2=0.000000
L 6.2898554 3.0685622 6.2848571 3.0735606 15 P 0 ;0,1=114,2=0.000000
L 6.291937 2.7613386 6.291937 2.8213386 8 P 0
L 6.2968425 2.116063 6.2968425 2.176063 8 P 0
L 6.2998522 3.0585655 6.309849 3.0635638 15 P 0 ;0,1=114,2=0.000000
L 6.2998522 3.0735606 6.2998522 3.0585655 15 P 0 ;0,1=114,2=0.000000
L 6.3048506 3.0435703 6.2998522 3.0485687 15 P 0 ;0,1=114,2=0.000000
L 6.3061023 2.0374787 6.3111007 2.0324803 15 P 0 ;0,1=134,2=0.000000
L 6.3061023 2.0574722 6.3061023 2.0374787 15 P 0 ;0,1=134,2=0.000000
L 6.3076081 2.8859039 6.3126065 2.8809055 15 P 0 ;0,1=131,2=90.000000
L 6.3076081 2.8959007 6.3076081 2.8859039 15 P 0 ;0,1=131,2=90.000000
L 6.3076081 2.9158942 6.3076081 2.925891 15 P 0 ;0,1=131,2=90.000000
L 6.3076081 2.925891 6.3126065 2.9308893 15 P 0 ;0,1=131,2=90.000000
L 6.3098425 3.7922834 6.3098425 4.2056693 10 P 0
L 6.309849 3.0635638 6.3148474 3.0635638 15 P 0 ;0,1=114,2=0.000000
L 6.3111007 2.0324803 6.3210975 2.0324803 15 P 0 ;0,1=134,2=0.000000
L 6.3111007 2.0624706 6.3061023 2.0574722 15 P 0 ;0,1=134,2=0.000000
L 6.3126065 2.8809055 6.3326 2.8809055 15 P 0 ;0,1=131,2=90.000000
L 6.3126065 2.900899 6.3076081 2.8959007 15 P 0 ;0,1=131,2=90.000000
L 6.3126065 2.9108958 6.3076081 2.9158942 15 P 0 ;0,1=131,2=90.000000
L 6.3126065 2.9308893 6.3176049 2.9308893 15 P 0 ;0,1=131,2=90.000000
L 6.3148474 3.0435703 6.3048506 3.0435703 15 P 0 ;0,1=114,2=0.000000
L 6.3148474 3.0635638 6.3198457 3.0585655 15 P 0 ;0,1=114,2=0.000000
L 6.3176049 2.9108958 6.3126065 2.9108958 15 P 0 ;0,1=131,2=90.000000
L 6.3176049 2.9308893 6.3226032 2.925891 15 P 0 ;0,1=131,2=90.000000
L 6.3198457 3.0485687 6.3148474 3.0435703 15 P 0 ;0,1=114,2=0.000000
L 6.3198457 3.0585655 6.3198457 3.0485687 15 P 0 ;0,1=114,2=0.000000
L 6.3198457 3.0735606 6.2998522 3.0735606 15 P 0 ;0,1=114,2=0.000000
L 6.3210975 2.0324803 6.3260958 2.0374787 15 P 0 ;0,1=134,2=0.000000
L 6.3210975 2.0624706 6.3111007 2.0624706 15 P 0 ;0,1=134,2=0.000000
L 6.3226032 2.9158942 6.3176049 2.9108958 15 P 0 ;0,1=131,2=90.000000
L 6.3226032 2.9158942 6.3226032 2.925891 15 P 0 ;0,1=131,2=90.000000
L 6.3226032 2.925891 6.3276016 2.9308893 15 P 0 ;0,1=131,2=90.000000
L 6.3260958 2.0574722 6.3210975 2.0624706 15 P 0 ;0,1=134,2=0.000000
L 6.3276016 2.9108958 6.3226032 2.9158942 15 P 0 ;0,1=131,2=90.000000
L 6.3276016 2.9308893 6.3326 2.9308893 15 P 0 ;0,1=131,2=90.000000
L 6.3298425 3.0485687 6.3348409 3.0435703 15 P 0 ;0,1=114,2=0.000000
L 6.3298425 3.0585655 6.3298425 3.0485687 15 P 0 ;0,1=114,2=0.000000
L 6.3308661 3.6636614 6.3308661 3.6685827 5 P 0
L 6.3308661 3.7335433 6.3308661 3.7384646 5 P 0
L 6.3326 2.8809055 6.3375984 2.8859039 15 P 0 ;0,1=131,2=90.000000
L 6.3326 2.9108958 6.3276016 2.9108958 15 P 0 ;0,1=131,2=90.000000
L 6.3326 2.9308893 6.3375984 2.925891 15 P 0 ;0,1=131,2=90.000000
L 6.3340472 2.7613386 6.3340472 2.8213386 8 P 0
L 6.3348409 3.0435703 6.3448377 3.0435703 15 P 0 ;0,1=114,2=0.000000
L 6.3358661 3.5286614 6.3358661 3.5335827 5 P 0
L 6.3358661 3.5985433 6.3358661 3.6034646 5 P 0
L 6.3360926 2.0474755 6.3460894 2.0524738 15 P 0 ;0,1=134,2=0.000000
L 6.3360926 2.0624706 6.3360926 2.0474755 15 P 0 ;0,1=134,2=0.000000
L 6.3368506 4.1585703 6.3318522 4.1635687 15 P 0 ;0,1=82,2=0.000000
L 6.3375984 2.8859039 6.3375984 2.8959007 15 P 0 ;0,1=131,2=90.000000
L 6.3375984 2.8959007 6.3326 2.900899 15 P 0 ;0,1=131,2=90.000000
L 6.3375984 2.9158942 6.3326 2.9108958 15 P 0 ;0,1=131,2=90.000000
L 6.3375984 2.925891 6.3375984 2.9158942 15 P 0 ;0,1=131,2=90.000000
L 6.3398393 3.0685622 6.3298425 3.0585655 15 P 0 ;0,1=114,2=0.000000
L 6.3398425 2.431378 6.3398425 2.470748 8 P 0
L 6.341091 2.0324803 6.3360926 2.0374787 15 P 0 ;0,1=134,2=0.000000
L 6.3413546 3.7585703 6.3563498 3.7585703 15 P 0 ;0,1=101,2=0.000000
L 6.3413546 3.7885606 6.3413546 3.7585703 15 P 0 ;0,1=101,2=0.000000
L 6.341849 4.1585703 6.3368506 4.1585703 15 P 0 ;0,1=82,2=0.000000
L 6.341849 4.1885606 6.3468474 4.1885606 15 P 0 ;0,1=82,2=0.000000
L 6.3448377 3.0435703 6.349836 3.0485687 15 P 0 ;0,1=114,2=0.000000
L 6.3448377 3.0585655 6.3298425 3.0585655 15 P 0 ;0,1=114,2=0.000000
L 6.3460894 2.0524738 6.3510878 2.0524738 15 P 0 ;0,1=134,2=0.000000
L 6.3468474 4.1635687 6.341849 4.1585703 15 P 0 ;0,1=82,2=0.000000
L 6.3468474 4.1885606 6.3468474 4.1635687 15 P 0 ;0,1=82,2=0.000000
L 6.349836 3.0485687 6.349836 3.0535671 15 P 0 ;0,1=114,2=0.000000
L 6.349836 3.0535671 6.3448377 3.0585655 15 P 0 ;0,1=114,2=0.000000
L 6.349836 3.0735606 6.3398393 3.0685622 15 P 0 ;0,1=114,2=0.000000
L 6.3510878 2.0324803 6.341091 2.0324803 15 P 0 ;0,1=134,2=0.000000
L 6.3510878 2.0524738 6.3560861 2.0474755 15 P 0 ;0,1=134,2=0.000000
L 6.3518457 4.1885606 6.341849 4.1885606 15 P 0 ;0,1=82,2=0.000000
L 6.3560861 2.0374787 6.3510878 2.0324803 15 P 0 ;0,1=134,2=0.000000
L 6.3560861 2.0474755 6.3560861 2.0374787 15 P 0 ;0,1=134,2=0.000000
L 6.3560861 2.0624706 6.3360926 2.0624706 15 P 0 ;0,1=134,2=0.000000
L 6.3563498 3.7585703 6.3613481 3.7635687 15 P 0 ;0,1=101,2=0.000000
L 6.3563498 3.7885606 6.3413546 3.7885606 15 P 0 ;0,1=101,2=0.000000
L 6.3613481 3.7635687 6.3613481 3.7835622 15 P 0 ;0,1=101,2=0.000000
L 6.3613481 3.7835622 6.3563498 3.7885606 15 P 0 ;0,1=101,2=0.000000
L 6.3618425 4.1585703 6.3718393 4.1585703 15 P 0 ;0,1=82,2=0.000000
L 6.3648425 3.131063 6.3648425 3.351063 4 P 0
L 6.3648425 3.131063 6.5346456 3.131063 4 P 0
L 6.3648425 3.351063 6.5346456 3.351063 4 P 0
L 6.3668409 4.1585703 6.3668409 4.1885606 15 P 0 ;0,1=82,2=0.000000
L 6.3668409 4.1885606 6.3618425 4.1835622 15 P 0 ;0,1=82,2=0.000000
L 6.3688425 3.3900614 6.3738409 3.385063 15 P 0 ;0,1=42,2=0.000000
L 6.3688425 3.4150533 6.3688425 3.3900614 15 P 0 ;0,1=42,2=0.000000
L 6.3713449 3.7835622 6.3763433 3.7885606 15 P 0 ;0,1=101,2=0.000000
L 6.3718393 4.1585703 6.3668409 4.1585703 15 P 0 ;0,1=82,2=0.000000
L 6.3728425 2.116063 6.3728425 2.176063 8 P 0
L 6.3738409 3.385063 6.3838377 3.385063 15 P 0 ;0,1=42,2=0.000000
L 6.3763433 3.7585703 6.3713449 3.7635687 15 P 0 ;0,1=101,2=0.000000
L 6.3763433 3.7885606 6.3863401 3.7885606 15 P 0 ;0,1=101,2=0.000000
L 6.3813417 3.7735655 6.3863401 3.7735655 15 P 0 ;0,1=101,2=0.000000
L 6.3838377 3.385063 6.388836 3.3900614 15 P 0 ;0,1=42,2=0.000000
L 6.3863401 3.7585703 6.3763433 3.7585703 15 P 0 ;0,1=101,2=0.000000
L 6.3863401 3.7735655 6.3813417 3.7735655 15 P 0 ;0,1=101,2=0.000000
L 6.3863401 3.7735655 6.3913384 3.7685671 15 P 0 ;0,1=101,2=0.000000
L 6.3863401 3.7885606 6.3913384 3.7835622 15 P 0 ;0,1=101,2=0.000000
L 6.388836 3.3900614 6.388836 3.4150533 15 P 0 ;0,1=42,2=0.000000
L 6.3913384 3.7635687 6.3863401 3.7585703 15 P 0 ;0,1=101,2=0.000000
L 6.3913384 3.7685671 6.3913384 3.7635687 15 P 0 ;0,1=101,2=0.000000
L 6.3913384 3.7785638 6.3863401 3.7735655 15 P 0 ;0,1=101,2=0.000000
L 6.3913384 3.7835622 6.3913384 3.7785638 15 P 0 ;0,1=101,2=0.000000
L 6.3988328 3.3900614 6.3988328 3.3950598 15 P 0 ;0,1=42,2=0.000000
L 6.3988328 3.3950598 6.4038312 3.4000582 15 P 0 ;0,1=42,2=0.000000
L 6.3988328 3.4050565 6.3988328 3.4100549 15 P 0 ;0,1=42,2=0.000000
L 6.3988328 3.4100549 6.4038312 3.4150533 15 P 0 ;0,1=42,2=0.000000
L 6.4038312 3.385063 6.3988328 3.3900614 15 P 0 ;0,1=42,2=0.000000
L 6.4038312 3.4000582 6.3988328 3.4050565 15 P 0 ;0,1=42,2=0.000000
L 6.4038312 3.4000582 6.413828 3.4000582 15 P 0 ;0,1=42,2=0.000000
L 6.4038312 3.4150533 6.413828 3.4150533 15 P 0 ;0,1=42,2=0.000000
L 6.4100472 2.7613386 6.4100472 2.8213386 8 P 0
L 6.413828 3.385063 6.4038312 3.385063 15 P 0 ;0,1=42,2=0.000000
L 6.413828 3.4000582 6.4188263 3.3950598 15 P 0 ;0,1=42,2=0.000000
L 6.413828 3.4150533 6.4188263 3.4100549 15 P 0 ;0,1=42,2=0.000000
L 6.4188263 3.3900614 6.413828 3.385063 15 P 0 ;0,1=42,2=0.000000
L 6.4188263 3.3950598 6.4188263 3.3900614 15 P 0 ;0,1=42,2=0.000000
L 6.4188263 3.4050565 6.413828 3.4000582 15 P 0 ;0,1=42,2=0.000000
L 6.4188263 3.4100549 6.4188263 3.4050565 15 P 0 ;0,1=42,2=0.000000
L 6.427874 2.3480315 6.427874 2.8740945 4 P 0
L 6.427874 2.3480315 6.931811 2.3480315 4 P 0
L 6.427874 2.8740945 6.931811 2.8740945 4 P 0
L 6.4418425 2.246063 6.4418425 2.296063 8 P 0
L 6.4444882 3.5295276 6.4444882 4.3569484 10 P 0
L 6.4444882 3.5295276 7.0035442 3.5295276 10 P 0
L 6.4448425 3.033063 6.5048425 3.033063 8 P 0
L 6.4448425 3.109063 6.5048425 3.109063 8 P 0
L 6.4562302 2.151652 6.4612286 2.1466536 15 P 0 ;0,1=136,2=90.000000
L 6.4562302 2.1616488 6.4562302 2.151652 15 P 0 ;0,1=136,2=90.000000
L 6.4562302 2.1816423 6.4562302 2.1916391 15 P 0 ;0,1=136,2=90.000000
L 6.4562302 2.1916391 6.4612286 2.1966374 15 P 0 ;0,1=136,2=90.000000
L 6.4612286 2.1466536 6.4812221 2.1466536 15 P 0 ;0,1=136,2=90.000000
L 6.4612286 2.1666471 6.4562302 2.1616488 15 P 0 ;0,1=136,2=90.000000
L 6.4612286 2.1766439 6.4562302 2.1816423 15 P 0 ;0,1=136,2=90.000000
L 6.4612286 2.1966374 6.466227 2.1966374 15 P 0 ;0,1=136,2=90.000000
L 6.466227 2.1966374 6.4712253 2.1916391 15 P 0 ;0,1=136,2=90.000000
L 6.4712253 2.1866407 6.4712253 2.1916391 15 P 0 ;0,1=136,2=90.000000
L 6.4712253 2.1916391 6.4712253 2.1866407 15 P 0 ;0,1=136,2=90.000000
L 6.4712253 2.1916391 6.4762237 2.1966374 15 P 0 ;0,1=136,2=90.000000
L 6.4762237 2.1966374 6.4812221 2.1966374 15 P 0 ;0,1=136,2=90.000000
L 6.4812221 2.1466536 6.4862205 2.151652 15 P 0 ;0,1=136,2=90.000000
L 6.4812221 2.1966374 6.4862205 2.1916391 15 P 0 ;0,1=136,2=90.000000
L 6.4862205 2.151652 6.4862205 2.1616488 15 P 0 ;0,1=136,2=90.000000
L 6.4862205 2.1616488 6.4812221 2.1666471 15 P 0 ;0,1=136,2=90.000000
L 6.4862205 2.1816423 6.4812221 2.1766439 15 P 0 ;0,1=136,2=90.000000
L 6.4862205 2.1916391 6.4862205 2.1816423 15 P 0 ;0,1=136,2=90.000000
L 6.4918425 1.961063 6.4918425 2.011063 8 P 0
L 6.4978425 2.246063 6.4978425 2.296063 8 P 0
L 6.5005215 2.0709433 6.5055199 2.0659449 15 P 0 ;0,1=135,2=90.000000
L 6.5005215 2.0809401 6.5005215 2.0709433 15 P 0 ;0,1=135,2=90.000000
L 6.5005215 2.1109304 6.5155166 2.0959352 15 P 0 ;0,1=135,2=90.000000
L 6.5055199 2.0659449 6.5255134 2.0659449 15 P 0 ;0,1=135,2=90.000000
L 6.5055199 2.0859384 6.5005215 2.0809401 15 P 0 ;0,1=135,2=90.000000
L 6.5155166 2.0959352 6.5155166 2.1159287 15 P 0 ;0,1=135,2=90.000000
L 6.5255134 2.0659449 6.5305118 2.0709433 15 P 0 ;0,1=135,2=90.000000
L 6.5305118 2.0709433 6.5305118 2.0809401 15 P 0 ;0,1=135,2=90.000000
L 6.5305118 2.0809401 6.5255134 2.0859384 15 P 0 ;0,1=135,2=90.000000
L 6.5305118 2.1109304 6.5005215 2.1109304 15 P 0 ;0,1=135,2=90.000000
L 6.5346456 3.131063 6.5346456 3.351063 4 P 0
L 6.5478425 1.961063 6.5478425 2.011063 8 P 0
L 6.5610236 2.0817701 6.566022 2.0767717 15 P 0 ;0,1=46,2=0.000000
L 6.5610236 2.106762 6.5610236 2.0817701 15 P 0 ;0,1=46,2=0.000000
L 6.566022 2.0767717 6.5760188 2.0767717 15 P 0 ;0,1=46,2=0.000000
L 6.571811 1.3880315 6.571811 1.9140945 4 P 0
L 6.5748619 2.9625687 6.5798603 2.9575703 15 P 0 ;0,1=113,2=0.000000
L 6.5748619 2.9825622 6.5748619 2.9625687 15 P 0 ;0,1=113,2=0.000000
L 6.5760188 2.0767717 6.5810171 2.0817701 15 P 0 ;0,1=46,2=0.000000
L 6.5768425 3.136063 6.5768425 3.186063 8 P 0
L 6.5768425 3.271063 6.5768425 3.321063 8 P 0
L 6.5798603 2.9575703 6.5898571 2.9575703 15 P 0 ;0,1=113,2=0.000000
L 6.5798603 2.9875606 6.5748619 2.9825622 15 P 0 ;0,1=113,2=0.000000
L 6.5810171 2.0817701 6.5810171 2.106762 15 P 0 ;0,1=46,2=0.000000
L 6.5858619 3.3795687 6.5908603 3.3745703 15 P 0 ;0,1=29,2=0.000000
L 6.5858619 3.3995622 6.5858619 3.3795687 15 P 0 ;0,1=29,2=0.000000
L 6.5898571 2.9575703 6.5948554 2.9625687 15 P 0 ;0,1=113,2=0.000000
L 6.5898571 2.9875606 6.5798603 2.9875606 15 P 0 ;0,1=113,2=0.000000
L 6.5908603 3.3745703 6.6008571 3.3745703 15 P 0 ;0,1=29,2=0.000000
L 6.5908603 3.4045606 6.5858619 3.3995622 15 P 0 ;0,1=29,2=0.000000
L 6.5910139 2.0767717 6.6010107 2.0767717 15 P 0 ;0,1=46,2=0.000000
L 6.5948554 2.9825622 6.5898571 2.9875606 15 P 0 ;0,1=113,2=0.000000
L 6.5960123 2.0767717 6.5960123 2.106762 15 P 0 ;0,1=46,2=0.000000
L 6.5960123 2.106762 6.5910139 2.1017636 15 P 0 ;0,1=46,2=0.000000
L 6.6008571 3.3745703 6.6058554 3.3795687 15 P 0 ;0,1=29,2=0.000000
L 6.6008571 3.4045606 6.5908603 3.4045606 15 P 0 ;0,1=29,2=0.000000
L 6.6009842 2.0544882 6.8135827 2.0544882 9 P 0
L 6.6010107 2.0767717 6.5960123 2.0767717 15 P 0 ;0,1=46,2=0.000000
L 6.6048522 2.9725655 6.614849 2.9775638 15 P 0 ;0,1=113,2=0.000000
L 6.6048522 2.9875606 6.6048522 2.9725655 15 P 0 ;0,1=113,2=0.000000
L 6.6058554 3.3995622 6.6008571 3.4045606 15 P 0 ;0,1=29,2=0.000000
L 6.6098506 2.9575703 6.6048522 2.9625687 15 P 0 ;0,1=113,2=0.000000
L 6.614849 2.9775638 6.6198474 2.9775638 15 P 0 ;0,1=113,2=0.000000
L 6.6158522 3.3795687 6.6158522 3.3845671 15 P 0 ;0,1=29,2=0.000000
L 6.6158522 3.3845671 6.6208506 3.3895655 15 P 0 ;0,1=29,2=0.000000
L 6.6158522 3.3945638 6.6158522 3.3995622 15 P 0 ;0,1=29,2=0.000000
L 6.6158522 3.3995622 6.6208506 3.4045606 15 P 0 ;0,1=29,2=0.000000
L 6.6198474 2.9575703 6.6098506 2.9575703 15 P 0 ;0,1=113,2=0.000000
L 6.6198474 2.9775638 6.6248457 2.9725655 15 P 0 ;0,1=113,2=0.000000
L 6.6208506 3.3745703 6.6158522 3.3795687 15 P 0 ;0,1=29,2=0.000000
L 6.6208506 3.3895655 6.6158522 3.3945638 15 P 0 ;0,1=29,2=0.000000
L 6.6208506 3.3895655 6.6308474 3.3895655 15 P 0 ;0,1=29,2=0.000000
L 6.6208506 3.4045606 6.6308474 3.4045606 15 P 0 ;0,1=29,2=0.000000
L 6.621063 1.8070866 6.621063 1.8370769 15 P 0 ;0,1=71,2=0.000000
L 6.621063 1.8370769 6.6360582 1.8370769 15 P 0 ;0,1=71,2=0.000000
L 6.6218425 2.101063 6.6218425 2.161063 8 P 0
L 6.6248457 2.9625687 6.6198474 2.9575703 15 P 0 ;0,1=113,2=0.000000
L 6.6248457 2.9725655 6.6248457 2.9625687 15 P 0 ;0,1=113,2=0.000000
L 6.6248457 2.9875606 6.6048522 2.9875606 15 P 0 ;0,1=113,2=0.000000
L 6.6308474 3.3745703 6.6208506 3.3745703 15 P 0 ;0,1=29,2=0.000000
L 6.6308474 3.3895655 6.6358457 3.3845671 15 P 0 ;0,1=29,2=0.000000
L 6.6308474 3.4045606 6.6358457 3.3995622 15 P 0 ;0,1=29,2=0.000000
L 6.6310598 1.8170834 6.6410565 1.8070866 15 P 0 ;0,1=71,2=0.000000
L 6.6328425 3.136063 6.6328425 3.186063 8 P 0
L 6.6328425 3.271063 6.6328425 3.321063 8 P 0
L 6.6348425 1.383063 6.6948425 1.383063 8 P 0
L 6.6348425 1.459063 6.6948425 1.459063 8 P 0
L 6.6348425 1.493063 6.6948425 1.493063 8 P 0
L 6.6348425 1.569063 6.6948425 1.569063 8 P 0
L 6.6348425 2.9625687 6.6348425 2.9575703 15 P 0 ;0,1=113,2=0.000000
L 6.6348425 2.9875606 6.654836 2.9875606 15 P 0 ;0,1=113,2=0.000000
L 6.6348619 3.0565687 6.6398603 3.0515703 15 P 0 ;0,1=28,2=0.000000
L 6.6348619 3.0765622 6.6348619 3.0565687 15 P 0 ;0,1=28,2=0.000000
L 6.6358457 3.3795687 6.6308474 3.3745703 15 P 0 ;0,1=29,2=0.000000
L 6.6358457 3.3845671 6.6358457 3.3795687 15 P 0 ;0,1=29,2=0.000000
L 6.6358457 3.3945638 6.6308474 3.3895655 15 P 0 ;0,1=29,2=0.000000
L 6.6358457 3.3995622 6.6358457 3.3945638 15 P 0 ;0,1=29,2=0.000000
L 6.6360582 1.8170834 6.621063 1.8170834 15 P 0 ;0,1=71,2=0.000000
L 6.6360582 1.8370769 6.6410565 1.8320785 15 P 0 ;0,1=71,2=0.000000
L 6.6398603 3.0515703 6.6498571 3.0515703 15 P 0 ;0,1=28,2=0.000000
L 6.6398603 3.0815606 6.6348619 3.0765622 15 P 0 ;0,1=28,2=0.000000
L 6.6410565 1.8220818 6.6360582 1.8170834 15 P 0 ;0,1=71,2=0.000000
L 6.6410565 1.8320785 6.6410565 1.8220818 15 P 0 ;0,1=71,2=0.000000
L 6.6452065 2.2166126 6.6502049 2.2116142 15 P 0 ;0,1=133,2=90.000000
L 6.6452065 2.2266094 6.6452065 2.2166126 15 P 0 ;0,1=133,2=90.000000
L 6.6452065 2.261598 6.6502049 2.2516013 15 P 0 ;0,1=133,2=90.000000
L 6.6458425 3.3795687 6.6508409 3.3745703 15 P 0 ;0,1=29,2=0.000000
L 6.6458425 3.3895655 6.6458425 3.3795687 15 P 0 ;0,1=29,2=0.000000
L 6.6498571 3.0515703 6.6548554 3.0565687 15 P 0 ;0,1=28,2=0.000000
L 6.6498571 3.0815606 6.6398603 3.0815606 15 P 0 ;0,1=28,2=0.000000
L 6.6502049 2.2116142 6.6701984 2.2116142 15 P 0 ;0,1=133,2=90.000000
L 6.6502049 2.2316077 6.6452065 2.2266094 15 P 0 ;0,1=133,2=90.000000
L 6.6502049 2.2516013 6.6602016 2.2416045 15 P 0 ;0,1=133,2=90.000000
L 6.6508409 3.3745703 6.6608377 3.3745703 15 P 0 ;0,1=29,2=0.000000
L 6.6510533 1.812085 6.6560517 1.8070866 15 P 0 ;0,1=71,2=0.000000
L 6.6510533 1.8220818 6.6510533 1.812085 15 P 0 ;0,1=71,2=0.000000
L 6.654836 2.9825622 6.6348425 2.9625687 15 P 0 ;0,1=113,2=0.000000
L 6.654836 2.9875606 6.654836 2.9825622 15 P 0 ;0,1=113,2=0.000000
L 6.6548554 3.0765622 6.6498571 3.0815606 15 P 0 ;0,1=28,2=0.000000
L 6.6558393 3.3995622 6.6458425 3.3895655 15 P 0 ;0,1=29,2=0.000000
L 6.6560517 1.8070866 6.6660485 1.8070866 15 P 0 ;0,1=71,2=0.000000
L 6.6561023 1.8576378 6.8135827 1.8576378 9 P 0
L 6.6598425 3.156063 6.6598425 3.306063 8 P 0
L 6.6598425 3.156063 6.6748425 3.156063 8 P 0
L 6.6598425 3.306063 6.6748425 3.306063 8 P 0
L 6.6602016 2.2416045 6.6701984 2.2416045 15 P 0 ;0,1=133,2=90.000000
L 6.6602016 2.2565997 6.6602016 2.2416045 15 P 0 ;0,1=133,2=90.000000
L 6.6608377 3.3745703 6.665836 3.3795687 15 P 0 ;0,1=29,2=0.000000
L 6.6608377 3.3895655 6.6458425 3.3895655 15 P 0 ;0,1=29,2=0.000000
L 6.6610501 1.8320785 6.6510533 1.8220818 15 P 0 ;0,1=71,2=0.000000
L 6.6648522 3.0565687 6.6648522 3.0615671 15 P 0 ;0,1=28,2=0.000000
L 6.6648522 3.0615671 6.6698506 3.0665655 15 P 0 ;0,1=28,2=0.000000
L 6.6648522 3.0715638 6.6648522 3.0765622 15 P 0 ;0,1=28,2=0.000000
L 6.6648522 3.0765622 6.6698506 3.0815606 15 P 0 ;0,1=28,2=0.000000
L 6.6652 2.261598 6.6602016 2.2565997 15 P 0 ;0,1=133,2=90.000000
L 6.665836 3.3795687 6.665836 3.3845671 15 P 0 ;0,1=29,2=0.000000
L 6.665836 3.3845671 6.6608377 3.3895655 15 P 0 ;0,1=29,2=0.000000
L 6.665836 3.4045606 6.6558393 3.3995622 15 P 0 ;0,1=29,2=0.000000
L 6.6660485 1.8070866 6.6710468 1.812085 15 P 0 ;0,1=71,2=0.000000
L 6.6660485 1.8220818 6.6510533 1.8220818 15 P 0 ;0,1=71,2=0.000000
L 6.6698506 3.0515703 6.6648522 3.0565687 15 P 0 ;0,1=28,2=0.000000
L 6.6698506 3.0665655 6.6648522 3.0715638 15 P 0 ;0,1=28,2=0.000000
L 6.6698506 3.0665655 6.6798474 3.0665655 15 P 0 ;0,1=28,2=0.000000
L 6.6698506 3.0815606 6.6798474 3.0815606 15 P 0 ;0,1=28,2=0.000000
L 6.6701984 2.2116142 6.6751968 2.2166126 15 P 0 ;0,1=133,2=90.000000
L 6.6701984 2.2416045 6.6751968 2.2466029 15 P 0 ;0,1=133,2=90.000000
L 6.6701984 2.261598 6.6652 2.261598 15 P 0 ;0,1=133,2=90.000000
L 6.6710468 1.812085 6.6710468 1.8170834 15 P 0 ;0,1=71,2=0.000000
L 6.6710468 1.8170834 6.6660485 1.8220818 15 P 0 ;0,1=71,2=0.000000
L 6.6710468 1.8370769 6.6610501 1.8320785 15 P 0 ;0,1=71,2=0.000000
L 6.6751968 2.2166126 6.6751968 2.2266094 15 P 0 ;0,1=133,2=90.000000
L 6.6751968 2.2266094 6.6701984 2.2316077 15 P 0 ;0,1=133,2=90.000000
L 6.6751968 2.2466029 6.6751968 2.2565997 15 P 0 ;0,1=133,2=90.000000
L 6.6751968 2.2565997 6.6701984 2.261598 15 P 0 ;0,1=133,2=90.000000
L 6.6798474 3.0515703 6.6698506 3.0515703 15 P 0 ;0,1=28,2=0.000000
L 6.6798474 3.0665655 6.6848457 3.0615671 15 P 0 ;0,1=28,2=0.000000
L 6.6798474 3.0815606 6.6848457 3.0765622 15 P 0 ;0,1=28,2=0.000000
L 6.6848425 3.181063 6.6848425 3.281063 8 P 0
L 6.6848457 3.0565687 6.6798474 3.0515703 15 P 0 ;0,1=28,2=0.000000
L 6.6848457 3.0615671 6.6848457 3.0565687 15 P 0 ;0,1=28,2=0.000000
L 6.6848457 3.0715638 6.6798474 3.0665655 15 P 0 ;0,1=28,2=0.000000
L 6.6848457 3.0765622 6.6848457 3.0715638 15 P 0 ;0,1=28,2=0.000000
L 6.6948425 3.0665655 6.7048393 3.0715638 15 P 0 ;0,1=28,2=0.000000
L 6.6948425 3.0815606 6.6948425 3.0665655 15 P 0 ;0,1=28,2=0.000000
L 6.6978425 2.101063 6.6978425 2.161063 8 P 0
L 6.6998409 3.0515703 6.6948425 3.0565687 15 P 0 ;0,1=28,2=0.000000
L 6.7048393 3.0715638 6.7098377 3.0715638 15 P 0 ;0,1=28,2=0.000000
L 6.7076107 1.6085687 6.7126091 1.6035703 15 P 0 ;0,1=123,2=0.000000
L 6.7076107 1.6285622 6.7076107 1.6085687 15 P 0 ;0,1=123,2=0.000000
L 6.7076107 1.7385687 6.7126091 1.7335703 15 P 0 ;0,1=121,2=0.000000
L 6.7076107 1.7585622 6.7076107 1.7385687 15 P 0 ;0,1=121,2=0.000000
L 6.7086107 1.6735687 6.7136091 1.6685703 15 P 0 ;0,1=122,2=0.000000
L 6.7086107 1.6935622 6.7086107 1.6735687 15 P 0 ;0,1=122,2=0.000000
L 6.7098377 3.0515703 6.6998409 3.0515703 15 P 0 ;0,1=28,2=0.000000
L 6.7098377 3.0715638 6.714836 3.0665655 15 P 0 ;0,1=28,2=0.000000
L 6.7126091 1.6035703 6.7226059 1.6035703 15 P 0 ;0,1=123,2=0.000000
L 6.7126091 1.6335606 6.7076107 1.6285622 15 P 0 ;0,1=123,2=0.000000
L 6.7126091 1.7335703 6.7226059 1.7335703 15 P 0 ;0,1=121,2=0.000000
L 6.7126091 1.7635606 6.7076107 1.7585622 15 P 0 ;0,1=121,2=0.000000
L 6.7136091 1.6685703 6.7236059 1.6685703 15 P 0 ;0,1=122,2=0.000000
L 6.7136091 1.6985606 6.7086107 1.6935622 15 P 0 ;0,1=122,2=0.000000
L 6.714836 3.0565687 6.7098377 3.0515703 15 P 0 ;0,1=28,2=0.000000
L 6.714836 3.0665655 6.714836 3.0565687 15 P 0 ;0,1=28,2=0.000000
L 6.714836 3.0815606 6.6948425 3.0815606 15 P 0 ;0,1=28,2=0.000000
L 6.7226059 1.6035703 6.7276042 1.6085687 15 P 0 ;0,1=123,2=0.000000
L 6.7226059 1.6335606 6.7126091 1.6335606 15 P 0 ;0,1=123,2=0.000000
L 6.7226059 1.7335703 6.7276042 1.7385687 15 P 0 ;0,1=121,2=0.000000
L 6.7226059 1.7635606 6.7126091 1.7635606 15 P 0 ;0,1=121,2=0.000000
L 6.7236059 1.6685703 6.7286042 1.6735687 15 P 0 ;0,1=122,2=0.000000
L 6.7236059 1.6985606 6.7136091 1.6985606 15 P 0 ;0,1=122,2=0.000000
L 6.7276042 1.6285622 6.7226059 1.6335606 15 P 0 ;0,1=123,2=0.000000
L 6.7276042 1.7585622 6.7226059 1.7635606 15 P 0 ;0,1=121,2=0.000000
L 6.7286042 1.6935622 6.7236059 1.6985606 15 P 0 ;0,1=122,2=0.000000
L 6.7301575 2.116063 6.7695275 2.116063 8 P 0
L 6.736742 2.1742126 6.736742 2.1892078 15 P 0 ;0,1=74,2=90.000000
L 6.736742 2.1892078 6.7417404 2.1942061 15 P 0 ;0,1=74,2=90.000000
L 6.736742 2.2092013 6.7417404 2.2042029 15 P 0 ;0,1=74,2=90.000000
L 6.736742 2.2191981 6.736742 2.2092013 15 P 0 ;0,1=74,2=90.000000
L 6.737601 1.6035703 6.7475978 1.6035703 15 P 0 ;0,1=123,2=0.000000
L 6.737601 1.7335703 6.7475978 1.7335703 15 P 0 ;0,1=121,2=0.000000
L 6.738601 1.6685703 6.7485978 1.6685703 15 P 0 ;0,1=122,2=0.000000
L 6.7416107 1.4025687 6.7466091 1.3975703 15 P 0 ;0,1=126,2=0.000000
L 6.7416107 1.4225622 6.7416107 1.4025687 15 P 0 ;0,1=126,2=0.000000
L 6.7416107 1.5425687 6.7466091 1.5375703 15 P 0 ;0,1=124,2=0.000000
L 6.7416107 1.5625622 6.7416107 1.5425687 15 P 0 ;0,1=124,2=0.000000
L 6.7417404 2.1942061 6.7517371 2.1942061 15 P 0 ;0,1=74,2=90.000000
L 6.7417404 2.2241964 6.736742 2.2191981 15 P 0 ;0,1=74,2=90.000000
L 6.7425994 1.6035703 6.7425994 1.6335606 15 P 0 ;0,1=123,2=0.000000
L 6.7425994 1.6335606 6.737601 1.6285622 15 P 0 ;0,1=123,2=0.000000
L 6.7425994 1.7335703 6.7425994 1.7635606 15 P 0 ;0,1=121,2=0.000000
L 6.7425994 1.7635606 6.737601 1.7585622 15 P 0 ;0,1=121,2=0.000000
L 6.7426107 1.4765687 6.7476091 1.4715703 15 P 0 ;0,1=125,2=0.000000
L 6.7426107 1.4965622 6.7426107 1.4765687 15 P 0 ;0,1=125,2=0.000000
L 6.7435994 1.6685703 6.7435994 1.6985606 15 P 0 ;0,1=122,2=0.000000
L 6.7435994 1.6985606 6.738601 1.6935622 15 P 0 ;0,1=122,2=0.000000
L 6.7466091 1.3975703 6.7566059 1.3975703 15 P 0 ;0,1=126,2=0.000000
L 6.7466091 1.4275606 6.7416107 1.4225622 15 P 0 ;0,1=126,2=0.000000
L 6.7466091 1.5375703 6.7566059 1.5375703 15 P 0 ;0,1=124,2=0.000000
L 6.7466091 1.5675606 6.7416107 1.5625622 15 P 0 ;0,1=124,2=0.000000
L 6.7467388 2.2241964 6.7417404 2.2241964 15 P 0 ;0,1=74,2=90.000000
L 6.7475978 1.6035703 6.7425994 1.6035703 15 P 0 ;0,1=123,2=0.000000
L 6.7475978 1.7335703 6.7425994 1.7335703 15 P 0 ;0,1=121,2=0.000000
L 6.7476091 1.4715703 6.7576059 1.4715703 15 P 0 ;0,1=125,2=0.000000
L 6.7476091 1.5015606 6.7426107 1.4965622 15 P 0 ;0,1=125,2=0.000000
L 6.7485978 1.6685703 6.7435994 1.6685703 15 P 0 ;0,1=122,2=0.000000
L 6.7517371 2.1942061 6.7567355 2.1892078 15 P 0 ;0,1=74,2=90.000000
L 6.7548425 1.796378 6.7548425 1.835748 8 P 0
L 6.7566059 1.3975703 6.7616042 1.4025687 15 P 0 ;0,1=126,2=0.000000
L 6.7566059 1.4275606 6.7466091 1.4275606 15 P 0 ;0,1=126,2=0.000000
L 6.7566059 1.5375703 6.7616042 1.5425687 15 P 0 ;0,1=124,2=0.000000
L 6.7566059 1.5675606 6.7466091 1.5675606 15 P 0 ;0,1=124,2=0.000000
L 6.7567355 2.1842094 6.7667323 2.1942061 15 P 0 ;0,1=74,2=90.000000
L 6.7567355 2.1892078 6.7567355 2.1742126 15 P 0 ;0,1=74,2=90.000000
L 6.7576059 1.4715703 6.7626042 1.4765687 15 P 0 ;0,1=125,2=0.000000
L 6.7576059 1.5015606 6.7476091 1.5015606 15 P 0 ;0,1=125,2=0.000000
L 6.7616042 1.4225622 6.7566059 1.4275606 15 P 0 ;0,1=126,2=0.000000
L 6.7616042 1.5625622 6.7566059 1.5675606 15 P 0 ;0,1=124,2=0.000000
L 6.7625929 1.6085687 6.7675913 1.6035703 15 P 0 ;0,1=123,2=0.000000
L 6.7625929 1.6185655 6.7625929 1.6085687 15 P 0 ;0,1=123,2=0.000000
L 6.7625929 1.7385687 6.7625929 1.7435671 15 P 0 ;0,1=121,2=0.000000
L 6.7625929 1.7435671 6.7675913 1.7485655 15 P 0 ;0,1=121,2=0.000000
L 6.7625929 1.7535638 6.7625929 1.7585622 15 P 0 ;0,1=121,2=0.000000
L 6.7625929 1.7585622 6.7675913 1.7635606 15 P 0 ;0,1=121,2=0.000000
L 6.7626042 1.4965622 6.7576059 1.5015606 15 P 0 ;0,1=125,2=0.000000
L 6.7635929 1.6735687 6.7635929 1.6685703 15 P 0 ;0,1=122,2=0.000000
L 6.7635929 1.6985606 6.7835864 1.6985606 15 P 0 ;0,1=122,2=0.000000
L 6.7667323 2.1742126 6.736742 2.1742126 15 P 0 ;0,1=74,2=90.000000
L 6.7667323 2.2042029 6.7467388 2.2241964 15 P 0 ;0,1=74,2=90.000000
L 6.7667323 2.2241964 6.7667323 2.2042029 15 P 0 ;0,1=74,2=90.000000
L 6.7675913 1.6035703 6.7775881 1.6035703 15 P 0 ;0,1=123,2=0.000000
L 6.7675913 1.7335703 6.7625929 1.7385687 15 P 0 ;0,1=121,2=0.000000
L 6.7675913 1.7485655 6.7625929 1.7535638 15 P 0 ;0,1=121,2=0.000000
L 6.7675913 1.7485655 6.7775881 1.7485655 15 P 0 ;0,1=121,2=0.000000
L 6.7675913 1.7635606 6.7775881 1.7635606 15 P 0 ;0,1=121,2=0.000000
L 6.771601 1.3975703 6.7815978 1.3975703 15 P 0 ;0,1=126,2=0.000000
L 6.771601 1.5375703 6.7815978 1.5375703 15 P 0 ;0,1=124,2=0.000000
L 6.7725897 1.6285622 6.7625929 1.6185655 15 P 0 ;0,1=123,2=0.000000
L 6.772601 1.4715703 6.7825978 1.4715703 15 P 0 ;0,1=125,2=0.000000
L 6.7765994 1.3975703 6.7765994 1.4275606 15 P 0 ;0,1=126,2=0.000000
L 6.7765994 1.4275606 6.771601 1.4225622 15 P 0 ;0,1=126,2=0.000000
L 6.7765994 1.5375703 6.7765994 1.5675606 15 P 0 ;0,1=124,2=0.000000
L 6.7765994 1.5675606 6.771601 1.5625622 15 P 0 ;0,1=124,2=0.000000
L 6.7775881 1.6035703 6.7825864 1.6085687 15 P 0 ;0,1=123,2=0.000000
L 6.7775881 1.6185655 6.7625929 1.6185655 15 P 0 ;0,1=123,2=0.000000
L 6.7775881 1.7335703 6.7675913 1.7335703 15 P 0 ;0,1=121,2=0.000000
L 6.7775881 1.7485655 6.7825864 1.7435671 15 P 0 ;0,1=121,2=0.000000
L 6.7775881 1.7635606 6.7825864 1.7585622 15 P 0 ;0,1=121,2=0.000000
L 6.7775994 1.4715703 6.7775994 1.5015606 15 P 0 ;0,1=125,2=0.000000
L 6.7775994 1.5015606 6.772601 1.4965622 15 P 0 ;0,1=125,2=0.000000
L 6.7798425 3.156063 6.8898425 3.156063 8 P 0
L 6.7798425 3.306063 6.8898425 3.306063 8 P 0
L 6.7815978 1.3975703 6.7765994 1.3975703 15 P 0 ;0,1=126,2=0.000000
L 6.7815978 1.5375703 6.7765994 1.5375703 15 P 0 ;0,1=124,2=0.000000
L 6.7825864 1.6085687 6.7825864 1.6135671 15 P 0 ;0,1=123,2=0.000000
L 6.7825864 1.6135671 6.7775881 1.6185655 15 P 0 ;0,1=123,2=0.000000
L 6.7825864 1.6335606 6.7725897 1.6285622 15 P 0 ;0,1=123,2=0.000000
L 6.7825864 1.7385687 6.7775881 1.7335703 15 P 0 ;0,1=121,2=0.000000
L 6.7825864 1.7435671 6.7825864 1.7385687 15 P 0 ;0,1=121,2=0.000000
L 6.7825864 1.7535638 6.7775881 1.7485655 15 P 0 ;0,1=121,2=0.000000
L 6.7825864 1.7585622 6.7825864 1.7535638 15 P 0 ;0,1=121,2=0.000000
L 6.7825978 1.4715703 6.7775994 1.4715703 15 P 0 ;0,1=125,2=0.000000
L 6.7835864 1.6935622 6.7635929 1.6735687 15 P 0 ;0,1=122,2=0.000000
L 6.7835864 1.6985606 6.7835864 1.6935622 15 P 0 ;0,1=122,2=0.000000
L 6.7965929 1.4225622 6.8015913 1.4275606 15 P 0 ;0,1=126,2=0.000000
L 6.7965929 1.5525655 6.8065897 1.5575638 15 P 0 ;0,1=124,2=0.000000
L 6.7965929 1.5675606 6.7965929 1.5525655 15 P 0 ;0,1=124,2=0.000000
L 6.7975929 1.4865655 6.8175864 1.4865655 15 P 0 ;0,1=125,2=0.000000
L 6.8015913 1.3975703 6.7965929 1.4025687 15 P 0 ;0,1=126,2=0.000000
L 6.8015913 1.4275606 6.8115881 1.4275606 15 P 0 ;0,1=126,2=0.000000
L 6.8015913 1.5375703 6.7965929 1.5425687 15 P 0 ;0,1=124,2=0.000000
L 6.8065897 1.4125655 6.8115881 1.4125655 15 P 0 ;0,1=126,2=0.000000
L 6.8065897 1.5575638 6.8115881 1.5575638 15 P 0 ;0,1=124,2=0.000000
L 6.8115881 1.3975703 6.8015913 1.3975703 15 P 0 ;0,1=126,2=0.000000
L 6.8115881 1.4125655 6.8065897 1.4125655 15 P 0 ;0,1=126,2=0.000000
L 6.8115881 1.4125655 6.8165864 1.4075671 15 P 0 ;0,1=126,2=0.000000
L 6.8115881 1.4275606 6.8165864 1.4225622 15 P 0 ;0,1=126,2=0.000000
L 6.8115881 1.5375703 6.8015913 1.5375703 15 P 0 ;0,1=124,2=0.000000
L 6.8115881 1.5575638 6.8165864 1.5525655 15 P 0 ;0,1=124,2=0.000000
L 6.8125881 1.4715703 6.8125881 1.5015606 15 P 0 ;0,1=125,2=0.000000
L 6.8125881 1.5015606 6.7975929 1.4865655 15 P 0 ;0,1=125,2=0.000000
L 6.8165864 1.4025687 6.8115881 1.3975703 15 P 0 ;0,1=126,2=0.000000
L 6.8165864 1.4075671 6.8165864 1.4025687 15 P 0 ;0,1=126,2=0.000000
L 6.8165864 1.4175638 6.8115881 1.4125655 15 P 0 ;0,1=126,2=0.000000
L 6.8165864 1.4225622 6.8165864 1.4175638 15 P 0 ;0,1=126,2=0.000000
L 6.8165864 1.5425687 6.8115881 1.5375703 15 P 0 ;0,1=124,2=0.000000
L 6.8165864 1.5525655 6.8165864 1.5425687 15 P 0 ;0,1=124,2=0.000000
L 6.8165864 1.5675606 6.7965929 1.5675606 15 P 0 ;0,1=124,2=0.000000
L 6.8336614 2.1496834 6.8386598 2.144685 15 P 0 ;0,1=120,2=0.000000
L 6.8336614 2.1696769 6.8336614 2.1496834 15 P 0 ;0,1=120,2=0.000000
L 6.8386598 2.144685 6.8486566 2.144685 15 P 0 ;0,1=120,2=0.000000
L 6.8386598 2.1746753 6.8336614 2.1696769 15 P 0 ;0,1=120,2=0.000000
L 6.8454724 1.75 6.8454724 1.7799903 15 P 0 ;0,1=72,2=0.000000
L 6.8454724 1.7799903 6.8604676 1.7799903 15 P 0 ;0,1=72,2=0.000000
L 6.8486566 2.144685 6.8536549 2.1496834 15 P 0 ;0,1=120,2=0.000000
L 6.8486566 2.1746753 6.8386598 2.1746753 15 P 0 ;0,1=120,2=0.000000
L 6.8498425 2.068063 6.8998425 2.068063 8 P 0
L 6.8498425 2.124063 6.8998425 2.124063 8 P 0
L 6.8536549 2.1696769 6.8486566 2.1746753 15 P 0 ;0,1=120,2=0.000000
L 6.8554692 1.7599968 6.8654659 1.75 15 P 0 ;0,1=72,2=0.000000
L 6.8604676 1.7599968 6.8454724 1.7599968 15 P 0 ;0,1=72,2=0.000000
L 6.8604676 1.7799903 6.8654659 1.7749919 15 P 0 ;0,1=72,2=0.000000
L 6.8636517 2.144685 6.8736485 2.144685 15 P 0 ;0,1=120,2=0.000000
L 6.8654659 1.7649952 6.8604676 1.7599968 15 P 0 ;0,1=72,2=0.000000
L 6.8654659 1.7749919 6.8654659 1.7649952 15 P 0 ;0,1=72,2=0.000000
L 6.8663546 2.9095703 6.8863481 2.9095703 15 P 0 ;0,1=78,2=0.000000
L 6.8663546 2.9395606 6.8663546 2.9095703 15 P 0 ;0,1=78,2=0.000000
L 6.8686501 2.144685 6.8686501 2.1746753 15 P 0 ;0,1=120,2=0.000000
L 6.8686501 2.1746753 6.8636517 2.1696769 15 P 0 ;0,1=120,2=0.000000
L 6.8698425 1.796378 6.8698425 1.835748 8 P 0
L 6.8736485 2.144685 6.8686501 2.144685 15 P 0 ;0,1=120,2=0.000000
L 6.8754627 1.7649952 6.8954562 1.7649952 15 P 0 ;0,1=72,2=0.000000
L 6.8886436 2.1496834 6.893642 2.144685 15 P 0 ;0,1=120,2=0.000000
L 6.8886436 2.1646785 6.893642 2.1596802 15 P 0 ;0,1=120,2=0.000000
L 6.8886436 2.1696769 6.8886436 2.1646785 15 P 0 ;0,1=120,2=0.000000
L 6.8904579 1.75 6.8904579 1.7799903 15 P 0 ;0,1=72,2=0.000000
L 6.8904579 1.7799903 6.8754627 1.7649952 15 P 0 ;0,1=72,2=0.000000
L 6.893642 2.144685 6.9036388 2.144685 15 P 0 ;0,1=120,2=0.000000
L 6.893642 2.1596802 6.9086371 2.1596802 15 P 0 ;0,1=120,2=0.000000
L 6.893642 2.1746753 6.8886436 2.1696769 15 P 0 ;0,1=120,2=0.000000
L 6.8963449 2.9095703 6.9163384 2.9295638 15 P 0 ;0,1=78,2=0.000000
L 6.9013433 2.9395606 6.8963449 2.9345622 15 P 0 ;0,1=78,2=0.000000
L 6.9036388 2.144685 6.9086371 2.1496834 15 P 0 ;0,1=120,2=0.000000
L 6.9036388 2.1746753 6.893642 2.1746753 15 P 0 ;0,1=120,2=0.000000
L 6.9086371 2.1496834 6.9086371 2.1696769 15 P 0 ;0,1=120,2=0.000000
L 6.9086371 2.1696769 6.9036388 2.1746753 15 P 0 ;0,1=120,2=0.000000
L 6.9113401 2.9395606 6.9013433 2.9395606 15 P 0 ;0,1=78,2=0.000000
L 6.9163384 2.9095703 6.8963449 2.9095703 15 P 0 ;0,1=78,2=0.000000
L 6.9163384 2.9295638 6.9163384 2.9345622 15 P 0 ;0,1=78,2=0.000000
L 6.9163384 2.9345622 6.9113401 2.9395606 15 P 0 ;0,1=78,2=0.000000
L 6.9198128 1.9636598 6.9248112 1.9586614 15 P 0 ;0,1=119,2=90.000000
L 6.9198128 1.9736566 6.9198128 1.9636598 15 P 0 ;0,1=119,2=90.000000
L 6.9198128 1.9936501 6.9248112 1.9886517 15 P 0 ;0,1=119,2=90.000000
L 6.9198128 2.0036469 6.9198128 1.9936501 15 P 0 ;0,1=119,2=90.000000
L 6.9198128 2.0236404 6.9198128 2.0336372 15 P 0 ;0,1=119,2=90.000000
L 6.9198128 2.0336372 6.9248112 2.0386355 15 P 0 ;0,1=119,2=90.000000
L 6.9248112 1.9586614 6.9448047 1.9586614 15 P 0 ;0,1=119,2=90.000000
L 6.9248112 1.9786549 6.9198128 1.9736566 15 P 0 ;0,1=119,2=90.000000
L 6.9248112 2.0086452 6.9198128 2.0036469 15 P 0 ;0,1=119,2=90.000000
L 6.9248112 2.018642 6.9198128 2.0236404 15 P 0 ;0,1=119,2=90.000000
L 6.9248112 2.0386355 6.9448047 2.0386355 15 P 0 ;0,1=119,2=90.000000
L 6.9298096 2.0086452 6.9248112 2.0086452 15 P 0 ;0,1=119,2=90.000000
L 6.931811 2.3480315 6.931811 2.8740945 4 P 0
L 6.9361007 3.4694882 6.9311023 3.4744866 15 P 0 ;0,1=81,2=0.000000
L 6.9410991 3.4694882 6.9361007 3.4694882 15 P 0 ;0,1=81,2=0.000000
L 6.9410991 3.4994785 6.9460975 3.4994785 15 P 0 ;0,1=81,2=0.000000
L 6.9448047 1.9586614 6.9498031 1.9636598 15 P 0 ;0,1=119,2=90.000000
L 6.9448047 2.018642 6.9248112 2.018642 15 P 0 ;0,1=119,2=90.000000
L 6.9448047 2.0386355 6.9498031 2.0336372 15 P 0 ;0,1=119,2=90.000000
L 6.9460975 3.4744866 6.9410991 3.4694882 15 P 0 ;0,1=81,2=0.000000
L 6.9460975 3.4994785 6.9460975 3.4744866 15 P 0 ;0,1=81,2=0.000000
L 6.9498031 1.9636598 6.9498031 1.9736566 15 P 0 ;0,1=119,2=90.000000
L 6.9498031 1.9736566 6.9448047 1.9786549 15 P 0 ;0,1=119,2=90.000000
L 6.9498031 1.9886517 6.9298096 2.0086452 15 P 0 ;0,1=119,2=90.000000
L 6.9498031 2.0086452 6.9498031 1.9886517 15 P 0 ;0,1=119,2=90.000000
L 6.9498031 2.0236404 6.9448047 2.018642 15 P 0 ;0,1=119,2=90.000000
L 6.9498031 2.0336372 6.9498031 2.0236404 15 P 0 ;0,1=119,2=90.000000
L 6.9510958 3.4994785 6.9410991 3.4994785 15 P 0 ;0,1=81,2=0.000000
L 6.9518522 3.3915606 6.9718457 3.3615703 15 P 0 ;0,1=37,2=0.000000
L 6.9610926 3.4694882 6.9810861 3.4894817 15 P 0 ;0,1=81,2=0.000000
L 6.966091 3.4994785 6.9610926 3.4944801 15 P 0 ;0,1=81,2=0.000000
L 6.9718457 3.3915606 6.9518522 3.3615703 15 P 0 ;0,1=37,2=0.000000
L 6.9760878 3.4994785 6.966091 3.4994785 15 P 0 ;0,1=81,2=0.000000
L 6.9810861 3.4694882 6.9610926 3.4694882 15 P 0 ;0,1=81,2=0.000000
L 6.9810861 3.4894817 6.9810861 3.4944801 15 P 0 ;0,1=81,2=0.000000
L 6.9810861 3.4944801 6.9760878 3.4994785 15 P 0 ;0,1=81,2=0.000000
L 6.9818425 3.3615703 6.9918393 3.3615703 15 P 0 ;0,1=37,2=0.000000
L 6.9868409 3.3615703 6.9868409 3.3915606 15 P 0 ;0,1=37,2=0.000000
L 6.9868409 3.3915606 6.9818425 3.3865622 15 P 0 ;0,1=37,2=0.000000
L 6.9901575 1.911063 7.0295275 1.911063 8 P 0
L 6.9918393 3.3615703 6.9868409 3.3615703 15 P 0 ;0,1=37,2=0.000000
L 6.9948425 3.156063 7.0098425 3.156063 8 P 0
L 6.9948425 3.306063 7.0098425 3.306063 8 P 0
L 6.9975687 1.9655512 6.9975687 1.9805464 15 P 0 ;0,1=69,2=90.000000
L 6.9975687 1.9805464 7.0025671 1.9855447 15 P 0 ;0,1=69,2=90.000000
L 6.9975687 2.0005399 6.9975687 2.0105367 15 P 0 ;0,1=69,2=90.000000
L 6.9975687 2.0105367 7.0025671 2.015535 15 P 0 ;0,1=69,2=90.000000
L 7.0025671 1.9855447 7.0125638 1.9855447 15 P 0 ;0,1=69,2=90.000000
L 7.0025671 1.9955415 6.9975687 2.0005399 15 P 0 ;0,1=69,2=90.000000
L 7.0025671 2.015535 7.0075655 2.015535 15 P 0 ;0,1=69,2=90.000000
L 7.0035442 3.5299036 7.0035442 3.5721068 14 P 0
L 7.0035442 3.5721068 7.0035442 4.3569484 10 P 0
L 7.0075655 1.9955415 7.0025671 1.9955415 15 P 0 ;0,1=69,2=90.000000
L 7.0075655 2.015535 7.0125638 2.0105367 15 P 0 ;0,1=69,2=90.000000
L 7.0098425 3.156063 7.0098425 3.166063 8 P 0
L 7.0098425 3.166063 7.0098425 3.296063 8 P 0
L 7.0098425 3.296063 7.0098425 3.306063 8 P 0
L 7.0125638 1.9855447 7.0175622 1.9805464 15 P 0 ;0,1=69,2=90.000000
L 7.0125638 2.0005399 7.0075655 1.9955415 15 P 0 ;0,1=69,2=90.000000
L 7.0125638 2.0005399 7.0125638 2.0105367 15 P 0 ;0,1=69,2=90.000000
L 7.0125638 2.0105367 7.0175622 2.015535 15 P 0 ;0,1=69,2=90.000000
L 7.0175622 1.975548 7.027559 1.9855447 15 P 0 ;0,1=69,2=90.000000
L 7.0175622 1.9805464 7.0175622 1.9655512 15 P 0 ;0,1=69,2=90.000000
L 7.0175622 1.9955415 7.0125638 2.0005399 15 P 0 ;0,1=69,2=90.000000
L 7.0175622 2.015535 7.0225606 2.015535 15 P 0 ;0,1=69,2=90.000000
L 7.0225606 1.9955415 7.0175622 1.9955415 15 P 0 ;0,1=69,2=90.000000
L 7.0225606 2.015535 7.027559 2.0105367 15 P 0 ;0,1=69,2=90.000000
L 7.027559 1.9655512 6.9975687 1.9655512 15 P 0 ;0,1=69,2=90.000000
L 7.027559 2.0005399 7.0225606 1.9955415 15 P 0 ;0,1=69,2=90.000000
L 7.027559 2.0105367 7.027559 2.0005399 15 P 0 ;0,1=69,2=90.000000
P 6.5573425 3.151063 16 P 0 0
S P 0
OB 1.3066695 4.1391688 I
OS 1.3066695 4.1368228
OS 1.2917379 4.1368228
OS 1.2917517 4.136809
OS 1.2917793 4.1367814
OS 1.2918207 4.13674
OS 1.2918759 4.136671
OS 1.2919449 4.1365882
OS 1.2920415 4.1364778
OS 1.2921381 4.1363536
OS 1.2922485 4.1362294
OS 1.2923589 4.1360638
OS 1.2924969 4.1358982
OS 1.2926211 4.1357188
OS 1.2927729 4.1355256
OS 1.2929109 4.1353048
OS 1.2930627 4.135084
OS 1.2933663 4.1345872
OS 1.2933801 4.1345734
OS 1.2934077 4.134532
OS 1.2934491 4.1344492
OS 1.2934905 4.1343526
OS 1.2935595 4.1342422
OS 1.2936423 4.1341042
OS 1.2937251 4.1339386
OS 1.2938217 4.133773
OS 1.2940149 4.1333866
OS 1.2942081 4.1329726
OS 1.2944013 4.1325448
OS 1.2945669 4.1321308
OS 1.2923037 4.1321308
OS 1.2922899 4.1321584
OS 1.2922623 4.1322136
OS 1.2922071 4.132324
OS 1.2921381 4.132462
OS 1.2920553 4.1326276
OS 1.2919449 4.1328346
OS 1.2918207 4.1330554
OS 1.2916827 4.13329
OS 1.2915171 4.1335522
OS 1.2913515 4.1338282
OS 1.2909651 4.1344078
OS 1.2905373 4.1350012
OS 1.2900681 4.135567
OS 1.2900543 4.1355808
OS 1.2900129 4.135636
OS 1.2899439 4.135705
OS 1.2898473 4.1358016
OS 1.2897231 4.1359258
OS 1.2895851 4.1360638
OS 1.2894195 4.1362156
OS 1.2892539 4.1363812
OS 1.2890607 4.1365468
OS 1.2888537 4.1367262
OS 1.2884259 4.1370712
OS 1.2879705 4.1373886
OS 1.2877359 4.1375266
OS 1.2875013 4.1376508
OS 1.2875013 4.1391688
OS 1.3066695 4.1391688
OE
OB 1.2875151 4.1516578 I
OS 1.2875151 4.151782
OS 1.2875289 4.1519476
OS 1.2875565 4.1521132
OS 1.2875841 4.1523064
OS 1.2876531 4.1527204
OS 1.2877635 4.1531758
OS 1.2879153 4.153645
OS 1.2880119 4.1538658
OS 1.2881223 4.1540866
OS 1.2881223 4.1541004
OS 1.2881499 4.1541418
OS 1.2881913 4.154197
OS 1.2882327 4.1542798
OS 1.2883017 4.1543764
OS 1.2883845 4.1544868
OS 1.2884673 4.1546248
OS 1.2885777 4.1547628
OS 1.2888261 4.1550664
OS 1.2891435 4.1553838
OS 1.2895023 4.1557012
OS 1.2899163 4.155991
OS 1.2899301 4.1560048
OS 1.2899715 4.1560186
OS 1.2900405 4.15606
OS 1.2901233 4.1561152
OS 1.2902337 4.1561842
OS 1.2903717 4.1562532
OS 1.2905235 4.156336
OS 1.2907029 4.1564188
OS 1.2908961 4.1565154
OS 1.2911169 4.156612
OS 1.2913515 4.1567086
OS 1.2915999 4.156819
OS 1.2918621 4.1569156
OS 1.2921381 4.1569984
OS 1.2924417 4.157095
OS 1.2927453 4.1571778
OS 1.2927591 4.1571778
OS 1.2928281 4.1571916
OS 1.2929109 4.1572192
OS 1.2930489 4.1572468
OS 1.2932145 4.1572744
OS 1.2934215 4.1573158
OS 1.2936561 4.1573572
OS 1.2939321 4.1573986
OS 1.2942357 4.15744
OS 1.2945807 4.1574814
OS 1.2949533 4.1575228
OS 1.2953535 4.1575504
OS 1.2957813 4.157578
OS 1.2962505 4.1576056
OS 1.2967335 4.1576194
OS 1.2972579 4.1576194
OS 1.2972717 4.1576194
OS 1.2972993 4.1576194
OS 1.2973407 4.1576194
OS 1.2974097 4.1576194
OS 1.2974787 4.1576194
OS 1.2975753 4.1576194
OS 1.2976857 4.1576056
OS 1.2978099 4.1576056
OS 1.2980997 4.1575918
OS 1.2984309 4.157578
OS 1.2987897 4.1575642
OS 1.2991899 4.1575366
OS 1.2996177 4.1574952
OS 1.3000593 4.1574538
OS 1.3009563 4.1573296
OS 1.3014117 4.1572468
OS 1.3018533 4.1571502
OS 1.3022811 4.1570398
OS 1.3026813 4.1569156
OS 1.3027089 4.1569018
OS 1.3027779 4.156888
OS 1.3028745 4.1568466
OS 1.3030263 4.1567914
OS 1.3031919 4.1567086
OS 1.3033989 4.1566258
OS 1.3036197 4.1565154
OS 1.3038543 4.156405
OS 1.3041027 4.156267
OS 1.3043649 4.1561014
OS 1.3046271 4.1559358
OS 1.3049031 4.1557564
OS 1.3051653 4.1555494
OS 1.3054137 4.1553286
OS 1.3056483 4.155094
OS 1.3058691 4.1548456
OS 1.3058829 4.1548318
OS 1.3059105 4.1547766
OS 1.3059657 4.1547076
OS 1.3060485 4.1545972
OS 1.3061313 4.1544592
OS 1.3062279 4.1543074
OS 1.3063245 4.1541142
OS 1.3064211 4.1539072
OS 1.3065315 4.1536588
OS 1.3066281 4.1533966
OS 1.3067247 4.1531206
OS 1.3068075 4.152817
OS 1.3068765 4.1524858
OS 1.3069317 4.1521408
OS 1.3069731 4.151782
OS 1.3069869 4.1513956
OS 1.3069869 4.1512714
OS 1.3069731 4.1511334
OS 1.3069593 4.1509402
OS 1.3069317 4.1507056
OS 1.3068765 4.1504296
OS 1.3068213 4.1501398
OS 1.3067385 4.1498086
OS 1.3066419 4.1494636
OS 1.3065039 4.1491186
OS 1.3063521 4.1487598
OS 1.3061589 4.1483872
OS 1.3059381 4.1480284
OS 1.3056759 4.1476834
OS 1.3053723 4.1473522
OS 1.3050273 4.1470486
OS 1.3050135 4.1470486
OS 1.3049997 4.1470348
OS 1.3049583 4.1470072
OS 1.3049169 4.1469658
OS 1.3048479 4.1469244
OS 1.3047651 4.1468692
OS 1.3046823 4.146814
OS 1.3045719 4.1467588
OS 1.3044477 4.1466898
OS 1.3043097 4.146607
OS 1.3041579 4.146538
OS 1.3039923 4.1464552
OS 1.3037991 4.1463724
OS 1.3036059 4.1462896
OS 1.3033851 4.146193
OS 1.3031643 4.1461102
OS 1.3029159 4.1460274
OS 1.3026537 4.1459308
OS 1.3023777 4.145848
OS 1.3020741 4.1457652
OS 1.3017705 4.1456824
OS 1.3014393 4.1456134
OS 1.3011081 4.1455306
OS 1.3007355 4.1454616
OS 1.3003629 4.1454064
OS 1.2999765 4.1453512
OS 1.2995625 4.145296
OS 1.2991347 4.1452546
OS 1.2986931 4.1452132
OS 1.2982377 4.1451994
OS 1.2977547 4.1451718
OS 1.2972579 4.1451718
OS 1.2972441 4.1451718
OS 1.2972165 4.1451718
OS 1.2971751 4.1451718
OS 1.2971061 4.1451718
OS 1.2970233 4.1451718
OS 1.2969267 4.1451718
OS 1.2968163 4.1451856
OS 1.2966921 4.1451856
OS 1.2964161 4.1451994
OS 1.2960849 4.1452132
OS 1.2957123 4.145227
OS 1.2953121 4.1452546
OS 1.2948843 4.145296
OS 1.2944427 4.1453374
OS 1.2935319 4.1454616
OS 1.2930765 4.1455444
OS 1.2926349 4.145641
OS 1.2922071 4.1457376
OS 1.2918069 4.1458618
OS 1.2917793 4.1458756
OS 1.2917103 4.1458894
OS 1.2916137 4.1459308
OS 1.2914619 4.145986
OS 1.2912963 4.1460688
OS 1.2910893 4.1461516
OS 1.2908685 4.146262
OS 1.2906339 4.1463862
OS 1.2903855 4.1465104
OS 1.2901233 4.146676
OS 1.2898473 4.1468416
OS 1.2895851 4.147021
OS 1.2893229 4.147228
OS 1.2890745 4.1474488
OS 1.2888399 4.1476834
OS 1.2886191 4.1479318
OS 1.2886053 4.1479456
OS 1.2885639 4.1480008
OS 1.2885087 4.1480698
OS 1.2884397 4.1481802
OS 1.2883569 4.1483182
OS 1.2882603 4.1484838
OS 1.2881637 4.1486632
OS 1.2880533 4.148884
OS 1.2879567 4.1491186
OS 1.2878601 4.1493808
OS 1.2877635 4.1496706
OS 1.2876807 4.1499742
OS 1.2875979 4.1503054
OS 1.2875427 4.1506504
OS 1.2875151 4.1510092
OS 1.2875013 4.1513956
OS 1.2875013 4.1515474
OS 1.2875151 4.1516578
OE
OB 1.2875841 4.120939 I
OS 1.2875841 4.1211598
OS 1.2875979 4.1214082
OS 1.2876117 4.1216704
OS 1.2876393 4.121974
OS 1.2876669 4.1222776
OS 1.2876945 4.122595
OS 1.2877911 4.1232436
OS 1.2878463 4.1235472
OS 1.2879153 4.1238508
OS 1.2879981 4.1241406
OS 1.2880947 4.1244028
OS 1.2880947 4.1244166
OS 1.2881223 4.124458
OS 1.2881499 4.124527
OS 1.2881913 4.1246236
OS 1.2882465 4.124734
OS 1.2883293 4.1248582
OS 1.2884121 4.12501
OS 1.2885087 4.1251618
OS 1.2886329 4.1253274
OS 1.2887571 4.1255068
OS 1.2889089 4.1256862
OS 1.2890745 4.1258656
OS 1.2892677 4.1260312
OS 1.2894609 4.1262106
OS 1.2896817 4.1263762
OS 1.2899163 4.126528
OS 1.2899301 4.1265418
OS 1.2899715 4.1265694
OS 1.2900405 4.126597
OS 1.2901371 4.1266522
OS 1.2902613 4.1267074
OS 1.2904131 4.1267764
OS 1.2905787 4.1268592
OS 1.2907581 4.1269282
OS 1.2909651 4.1269972
OS 1.2911859 4.12708
OS 1.2914205 4.127149
OS 1.2916689 4.1272042
OS 1.2919311 4.1272594
OS 1.2922071 4.1273008
OS 1.2924969 4.1273146
OS 1.2927867 4.1273284
OS 1.2928143 4.1273284
OS 1.2928695 4.1273284
OS 1.2929799 4.1273146
OS 1.2931317 4.1273146
OS 1.2932973 4.127287
OS 1.2935043 4.1272594
OS 1.2937251 4.127218
OS 1.2939735 4.1271628
OS 1.2942357 4.1270938
OS 1.2945117 4.127011
OS 1.2948015 4.1269006
OS 1.2950913 4.1267764
OS 1.2953811 4.1266246
OS 1.2956571 4.1264452
OS 1.2959469 4.1262382
OS 1.2962091 4.1260036
OS 1.2962229 4.1259898
OS 1.2962643 4.1259484
OS 1.2963333 4.1258656
OS 1.2964299 4.1257552
OS 1.2965403 4.1256172
OS 1.2966645 4.1254378
OS 1.2968025 4.1252446
OS 1.2969543 4.12501
OS 1.2971061 4.124734
OS 1.2972579 4.1244442
OS 1.2973959 4.1240992
OS 1.2975477 4.1237404
OS 1.2976719 4.1233402
OS 1.2977961 4.1229124
OS 1.2978927 4.1224432
OS 1.2979755 4.1219464
OS 1.2979755 4.1219602
OS 1.2980031 4.1219878
OS 1.2980169 4.122043
OS 1.2980583 4.122112
OS 1.2980997 4.1221948
OS 1.2981549 4.1222914
OS 1.2982791 4.1225122
OS 1.2984171 4.1227606
OS 1.2985827 4.123009
OS 1.2987483 4.1232436
OS 1.2989277 4.1234644
OS 1.2989415 4.1234782
OS 1.2989691 4.1235196
OS 1.2990381 4.1235748
OS 1.2991071 4.1236576
OS 1.2992175 4.1237542
OS 1.2993279 4.1238646
OS 1.2994659 4.1240026
OS 1.2996315 4.1241406
OS 1.2998109 4.1242924
OS 1.3000041 4.124458
OS 1.3002111 4.1246374
OS 1.3004319 4.1248168
OS 1.3006803 4.1249962
OS 1.3009287 4.1251894
OS 1.3014807 4.125562
OS 1.3066695 4.1288602
OS 1.3066695 4.1257
OS 1.3026951 4.1231746
OS 1.3026813 4.1231608
OS 1.3026261 4.1231194
OS 1.3025295 4.1230642
OS 1.3024191 4.1229952
OS 1.3022673 4.1228986
OS 1.3021017 4.1227882
OS 1.3019223 4.122664
OS 1.3017291 4.1225398
OS 1.3013013 4.12225
OS 1.3008597 4.1219464
OS 1.3004457 4.1216428
OS 1.3002525 4.121491
OS 1.3000731 4.121353
OS 1.3000593 4.1213392
OS 1.3000317 4.1213254
OS 1.2999903 4.121284
OS 1.2999213 4.1212288
OS 1.2997557 4.1210908
OS 1.2995625 4.1209252
OS 1.2993555 4.1207182
OS 1.2991347 4.1205112
OS 1.2989415 4.1202904
OS 1.2987897 4.1200696
OS 1.2987759 4.120042
OS 1.2987345 4.119973
OS 1.2986655 4.1198626
OS 1.2985965 4.1197108
OS 1.2985137 4.1195452
OS 1.2984171 4.119352
OS 1.2983481 4.119145
OS 1.2982791 4.1189242
OS 1.2982791 4.1189104
OS 1.2982653 4.1188414
OS 1.2982515 4.118731
OS 1.2982239 4.118593
OS 1.2982101 4.1183998
OS 1.2981963 4.1181514
OS 1.2981825 4.1178616
OS 1.2981825 4.114591
OS 1.3066695 4.114591
OS 1.3066695 4.1120656
OS 1.2875703 4.1120656
OS 1.2875703 4.1207734
OS 1.2875841 4.120939
OE
OB 1.2896817 4.1206216 H
OS 1.2896817 4.114591
OS 1.2959883 4.114591
OS 1.2959883 4.1203042
OS 1.2959745 4.1204422
OS 1.2959745 4.1206216
OS 1.2959607 4.120801
OS 1.2959469 4.121008
OS 1.2959055 4.1214358
OS 1.2958365 4.1218912
OS 1.2957537 4.1223328
OS 1.2956985 4.122526
OS 1.2956433 4.1227192
OS 1.2956433 4.122733
OS 1.2956295 4.1227606
OS 1.2956019 4.1228158
OS 1.2955743 4.1228848
OS 1.2955329 4.1229676
OS 1.2954915 4.1230504
OS 1.2953673 4.1232712
OS 1.2952017 4.1235196
OS 1.2950085 4.123768
OS 1.2947739 4.1240026
OS 1.2944979 4.1242096
OS 1.2944841 4.1242096
OS 1.2944565 4.1242372
OS 1.2944151 4.124251
OS 1.2943599 4.1242924
OS 1.2942909 4.1243338
OS 1.2941943 4.1243752
OS 1.2939873 4.1244718
OS 1.2937389 4.1245546
OS 1.2934491 4.1246374
OS 1.2931317 4.1246926
OS 1.2927867 4.1247202
OS 1.2927729 4.1247202
OS 1.2927315 4.1247202
OS 1.2926625 4.1247202
OS 1.2925659 4.1247064
OS 1.2924417 4.1246926
OS 1.2923175 4.124665
OS 1.2921657 4.1246374
OS 1.2920001 4.124596
OS 1.2918345 4.1245408
OS 1.2916551 4.1244718
OS 1.2914619 4.1244028
OS 1.2912825 4.1243062
OS 1.2910893 4.124182
OS 1.2909099 4.1240578
OS 1.2907305 4.123906
OS 1.2905649 4.1237266
OS 1.2905511 4.1237128
OS 1.2905235 4.1236852
OS 1.2904821 4.1236162
OS 1.2904269 4.1235472
OS 1.2903579 4.1234368
OS 1.2902889 4.1232988
OS 1.2902061 4.123147
OS 1.2901233 4.1229676
OS 1.2900405 4.1227744
OS 1.2899577 4.1225398
OS 1.2898887 4.1222776
OS 1.2898197 4.1220016
OS 1.2897645 4.121698
OS 1.2897231 4.1213668
OS 1.2896955 4.121008
OS 1.2896817 4.1206216
OE
OB 1.2894471 4.151368 H
OS 1.2894471 4.151299
OS 1.2894609 4.1512162
OS 1.2894747 4.1511058
OS 1.2894885 4.1509678
OS 1.2895161 4.1508022
OS 1.2895575 4.1506366
OS 1.2896127 4.1504434
OS 1.2896955 4.1502364
OS 1.2897783 4.1500294
OS 1.2898887 4.1498086
OS 1.2900267 4.1496016
OS 1.2901785 4.1493808
OS 1.2903579 4.1491738
OS 1.2905787 4.1489806
OS 1.2908133 4.1487874
OS 1.2908271 4.1487736
OS 1.2908961 4.1487322
OS 1.2910065 4.148677
OS 1.2911583 4.1485942
OS 1.2913653 4.1485114
OS 1.2916137 4.1484148
OS 1.2919173 4.1483044
OS 1.2922761 4.148194
OS 1.2924693 4.148125
OS 1.2926901 4.1480698
OS 1.2929109 4.1480146
OS 1.2931593 4.1479732
OS 1.2934077 4.147918
OS 1.2936837 4.1478628
OS 1.2939735 4.1478214
OS 1.2942771 4.14778
OS 1.2945945 4.1477386
OS 1.2949257 4.1476972
OS 1.2952707 4.1476696
OS 1.2956295 4.147642
OS 1.2960159 4.1476144
OS 1.2964161 4.1476006
OS 1.2968301 4.1475868
OS 1.2972579 4.1475868
OS 1.2972717 4.1475868
OS 1.2973131 4.1475868
OS 1.2973683 4.1475868
OS 1.2974649 4.1475868
OS 1.2975753 4.1475868
OS 1.2976995 4.1476006
OS 1.2978513 4.1476006
OS 1.2980169 4.1476006
OS 1.2981963 4.1476144
OS 1.2983895 4.1476144
OS 1.2988311 4.147642
OS 1.2993003 4.1476834
OS 1.2997971 4.1477248
OS 1.3003215 4.14778
OS 1.3008459 4.147849
OS 1.3013703 4.1479456
OS 1.3018809 4.1480422
OS 1.3023639 4.1481664
OS 1.3027917 4.1483182
OS 1.3029987 4.148401
OS 1.3031781 4.1484838
OS 1.3033575 4.1485804
OS 1.3035093 4.148677
OS 1.3035231 4.1486908
OS 1.3035783 4.1487322
OS 1.3036473 4.1487874
OS 1.3037439 4.1488702
OS 1.3038681 4.1489806
OS 1.3039923 4.1491186
OS 1.3041441 4.1492566
OS 1.3042821 4.149436
OS 1.3044201 4.1496154
OS 1.3045719 4.1498224
OS 1.3046961 4.1500432
OS 1.3048065 4.1502916
OS 1.3049169 4.15054
OS 1.3049859 4.150816
OS 1.3050411 4.1511058
OS 1.3050549 4.1513956
OS 1.3050549 4.1514646
OS 1.3050411 4.1515474
OS 1.3050273 4.1516578
OS 1.3050135 4.1517958
OS 1.3049721 4.1519614
OS 1.3049307 4.1521408
OS 1.3048617 4.152334
OS 1.3047789 4.152541
OS 1.3046823 4.1527618
OS 1.3045581 4.1529826
OS 1.3044063 4.1532172
OS 1.3042269 4.153438
OS 1.3040199 4.1536726
OS 1.3037853 4.1538934
OS 1.3035093 4.1541004
OS 1.3034955 4.1541142
OS 1.3034265 4.1541418
OS 1.3033299 4.154197
OS 1.3031919 4.1542798
OS 1.3029987 4.1543626
OS 1.3027641 4.1544454
OS 1.3024881 4.1545558
OS 1.3021431 4.1546524
OS 1.3019499 4.1547076
OS 1.3017429 4.154749
OS 1.3015359 4.1548042
OS 1.3013013 4.1548594
OS 1.3010529 4.1549008
OS 1.3007907 4.1549422
OS 1.3005147 4.1549974
OS 1.3002111 4.1550388
OS 1.2999075 4.1550664
OS 1.2995763 4.1551078
OS 1.2992313 4.1551354
OS 1.2988725 4.155163
OS 1.2984999 4.1551768
OS 1.2980997 4.1551906
OS 1.2976857 4.1552044
OS 1.2972579 4.1552044
OS 1.2972441 4.1552044
OS 1.2972027 4.1552044
OS 1.2971337 4.1552044
OS 1.2970509 4.1552044
OS 1.2969405 4.1552044
OS 1.2968163 4.1552044
OS 1.2966645 4.1551906
OS 1.2964989 4.1551906
OS 1.2963195 4.1551768
OS 1.2961125 4.1551768
OS 1.2956847 4.1551492
OS 1.2952155 4.1551078
OS 1.2947049 4.1550664
OS 1.2941943 4.1550112
OS 1.2936699 4.1549422
OS 1.2931455 4.1548456
OS 1.2926349 4.1547352
OS 1.2921519 4.154611
OS 1.2917241 4.1544592
OS 1.2915171 4.1543764
OS 1.2913377 4.1542936
OS 1.2911583 4.154197
OS 1.2910065 4.1541004
OS 1.2909927 4.1540866
OS 1.2909375 4.1540452
OS 1.2908685 4.15399
OS 1.2907581 4.1539072
OS 1.2906477 4.1537968
OS 1.2905097 4.1536726
OS 1.2903717 4.1535208
OS 1.2902199 4.1533552
OS 1.2900819 4.153162
OS 1.2899439 4.152955
OS 1.2898059 4.1527342
OS 1.2896955 4.1524858
OS 1.2895851 4.1522236
OS 1.2895161 4.1519614
OS 1.2894609 4.1516716
OS 1.2894471 4.151368
OE
SE
S P 0
OB 1.3097808 4.028772 I
OS 1.3097808 4.026426
OS 1.2948492 4.026426
OS 1.294863 4.0264122
OS 1.2948906 4.0263846
OS 1.294932 4.0263432
OS 1.2949872 4.0262742
OS 1.2950562 4.0261914
OS 1.2951528 4.026081
OS 1.2952494 4.0259568
OS 1.2953598 4.0258326
OS 1.2954702 4.025667
OS 1.2956082 4.0255014
OS 1.2957324 4.025322
OS 1.2958842 4.0251288
OS 1.2960222 4.024908
OS 1.296174 4.0246872
OS 1.2964776 4.0241904
OS 1.2964914 4.0241766
OS 1.296519 4.0241352
OS 1.2965604 4.0240524
OS 1.2966018 4.0239558
OS 1.2966708 4.0238454
OS 1.2967536 4.0237074
OS 1.2968364 4.0235418
OS 1.296933 4.0233762
OS 1.2971262 4.0229898
OS 1.2973194 4.0225758
OS 1.2975126 4.022148
OS 1.2976782 4.021734
OS 1.295415 4.021734
OS 1.2954012 4.0217616
OS 1.2953736 4.0218168
OS 1.2953184 4.0219272
OS 1.2952494 4.0220652
OS 1.2951666 4.0222308
OS 1.2950562 4.0224378
OS 1.294932 4.0226586
OS 1.294794 4.0228932
OS 1.2946284 4.0231554
OS 1.2944628 4.0234314
OS 1.2940764 4.024011
OS 1.2936486 4.0246044
OS 1.2931794 4.0251702
OS 1.2931656 4.025184
OS 1.2931242 4.0252392
OS 1.2930552 4.0253082
OS 1.2929586 4.0254048
OS 1.2928344 4.025529
OS 1.2926964 4.025667
OS 1.2925308 4.0258188
OS 1.2923652 4.0259844
OS 1.292172 4.02615
OS 1.291965 4.0263294
OS 1.2915372 4.0266744
OS 1.2910818 4.0269918
OS 1.2908472 4.0271298
OS 1.2906126 4.027254
OS 1.2906126 4.028772
OS 1.3097808 4.028772
OE
OB 1.3097808 4.043607 I
OS 1.3097808 4.041261
OS 1.2948492 4.041261
OS 1.294863 4.0412472
OS 1.2948906 4.0412196
OS 1.294932 4.0411782
OS 1.2949872 4.0411092
OS 1.2950562 4.0410264
OS 1.2951528 4.040916
OS 1.2952494 4.0407918
OS 1.2953598 4.0406676
OS 1.2954702 4.040502
OS 1.2956082 4.0403364
OS 1.2957324 4.040157
OS 1.2958842 4.0399638
OS 1.2960222 4.039743
OS 1.296174 4.0395222
OS 1.2964776 4.0390254
OS 1.2964914 4.0390116
OS 1.296519 4.0389702
OS 1.2965604 4.0388874
OS 1.2966018 4.0387908
OS 1.2966708 4.0386804
OS 1.2967536 4.0385424
OS 1.2968364 4.0383768
OS 1.296933 4.0382112
OS 1.2971262 4.0378248
OS 1.2973194 4.0374108
OS 1.2975126 4.036983
OS 1.2976782 4.036569
OS 1.295415 4.036569
OS 1.2954012 4.0365966
OS 1.2953736 4.0366518
OS 1.2953184 4.0367622
OS 1.2952494 4.0369002
OS 1.2951666 4.0370658
OS 1.2950562 4.0372728
OS 1.294932 4.0374936
OS 1.294794 4.0377282
OS 1.2946284 4.0379904
OS 1.2944628 4.0382664
OS 1.2940764 4.038846
OS 1.2936486 4.0394394
OS 1.2931794 4.0400052
OS 1.2931656 4.040019
OS 1.2931242 4.0400742
OS 1.2930552 4.0401432
OS 1.2929586 4.0402398
OS 1.2928344 4.040364
OS 1.2926964 4.040502
OS 1.2925308 4.0406538
OS 1.2923652 4.0408194
OS 1.292172 4.040985
OS 1.291965 4.0411644
OS 1.2915372 4.0415094
OS 1.2910818 4.0418268
OS 1.2908472 4.0419648
OS 1.2906126 4.042089
OS 1.2906126 4.043607
OS 1.3097808 4.043607
OE
OB 1.2906954 4.0105422 I
OS 1.2906954 4.010763
OS 1.2907092 4.0110114
OS 1.290723 4.0112736
OS 1.2907506 4.0115772
OS 1.2907782 4.0118808
OS 1.2908058 4.0121982
OS 1.2909024 4.0128468
OS 1.2909576 4.0131504
OS 1.2910266 4.013454
OS 1.2911094 4.0137438
OS 1.291206 4.014006
OS 1.291206 4.0140198
OS 1.2912336 4.0140612
OS 1.2912612 4.0141302
OS 1.2913026 4.0142268
OS 1.2913578 4.0143372
OS 1.2914406 4.0144614
OS 1.2915234 4.0146132
OS 1.29162 4.014765
OS 1.2917442 4.0149306
OS 1.2918684 4.01511
OS 1.2920202 4.0152894
OS 1.2921858 4.0154688
OS 1.292379 4.0156344
OS 1.2925722 4.0158138
OS 1.292793 4.0159794
OS 1.2930276 4.0161312
OS 1.2930414 4.016145
OS 1.2930828 4.0161726
OS 1.2931518 4.0162002
OS 1.2932484 4.0162554
OS 1.2933726 4.0163106
OS 1.2935244 4.0163796
OS 1.29369 4.0164624
OS 1.2938694 4.0165314
OS 1.2940764 4.0166004
OS 1.2942972 4.0166832
OS 1.2945318 4.0167522
OS 1.2947802 4.0168074
OS 1.2950424 4.0168626
OS 1.2953184 4.016904
OS 1.2956082 4.0169178
OS 1.295898 4.0169316
OS 1.2959256 4.0169316
OS 1.2959808 4.0169316
OS 1.2960912 4.0169178
OS 1.296243 4.0169178
OS 1.2964086 4.0168902
OS 1.2966156 4.0168626
OS 1.2968364 4.0168212
OS 1.2970848 4.016766
OS 1.297347 4.016697
OS 1.297623 4.0166142
OS 1.2979128 4.0165038
OS 1.2982026 4.0163796
OS 1.2984924 4.0162278
OS 1.2987684 4.0160484
OS 1.2990582 4.0158414
OS 1.2993204 4.0156068
OS 1.2993342 4.015593
OS 1.2993756 4.0155516
OS 1.2994446 4.0154688
OS 1.2995412 4.0153584
OS 1.2996516 4.0152204
OS 1.2997758 4.015041
OS 1.2999138 4.0148478
OS 1.3000656 4.0146132
OS 1.3002174 4.0143372
OS 1.3003692 4.0140474
OS 1.3005072 4.0137024
OS 1.300659 4.0133436
OS 1.3007832 4.0129434
OS 1.3009074 4.0125156
OS 1.301004 4.0120464
OS 1.3010868 4.0115496
OS 1.3010868 4.0115634
OS 1.3011144 4.011591
OS 1.3011282 4.0116462
OS 1.3011696 4.0117152
OS 1.301211 4.011798
OS 1.3012662 4.0118946
OS 1.3013904 4.0121154
OS 1.3015284 4.0123638
OS 1.301694 4.0126122
OS 1.3018596 4.0128468
OS 1.302039 4.0130676
OS 1.3020528 4.0130814
OS 1.3020804 4.0131228
OS 1.3021494 4.013178
OS 1.3022184 4.0132608
OS 1.3023288 4.0133574
OS 1.3024392 4.0134678
OS 1.3025772 4.0136058
OS 1.3027428 4.0137438
OS 1.3029222 4.0138956
OS 1.3031154 4.0140612
OS 1.3033224 4.0142406
OS 1.3035432 4.01442
OS 1.3037916 4.0145994
OS 1.30404 4.0147926
OS 1.304592 4.0151652
OS 1.3097808 4.0184634
OS 1.3097808 4.0153032
OS 1.3058064 4.0127778
OS 1.3057926 4.012764
OS 1.3057374 4.0127226
OS 1.3056408 4.0126674
OS 1.3055304 4.0125984
OS 1.3053786 4.0125018
OS 1.305213 4.0123914
OS 1.3050336 4.0122672
OS 1.3048404 4.012143
OS 1.3044126 4.0118532
OS 1.303971 4.0115496
OS 1.303557 4.011246
OS 1.3033638 4.0110942
OS 1.3031844 4.0109562
OS 1.3031706 4.0109424
OS 1.303143 4.0109286
OS 1.3031016 4.0108872
OS 1.3030326 4.010832
OS 1.302867 4.010694
OS 1.3026738 4.0105284
OS 1.3024668 4.0103214
OS 1.302246 4.0101144
OS 1.3020528 4.0098936
OS 1.301901 4.0096728
OS 1.3018872 4.0096452
OS 1.3018458 4.0095762
OS 1.3017768 4.0094658
OS 1.3017078 4.009314
OS 1.301625 4.0091484
OS 1.3015284 4.0089552
OS 1.3014594 4.0087482
OS 1.3013904 4.0085274
OS 1.3013904 4.0085136
OS 1.3013766 4.0084446
OS 1.3013628 4.0083342
OS 1.3013352 4.0081962
OS 1.3013214 4.008003
OS 1.3013076 4.0077546
OS 1.3012938 4.0074648
OS 1.3012938 4.0041942
OS 1.3097808 4.0041942
OS 1.3097808 4.0016688
OS 1.2906816 4.0016688
OS 1.2906816 4.0103766
OS 1.2906954 4.0105422
OE
OB 1.292793 4.0102248 H
OS 1.292793 4.0041942
OS 1.2990996 4.0041942
OS 1.2990996 4.0099074
OS 1.2990858 4.0100454
OS 1.2990858 4.0102248
OS 1.299072 4.0104042
OS 1.2990582 4.0106112
OS 1.2990168 4.011039
OS 1.2989478 4.0114944
OS 1.298865 4.011936
OS 1.2988098 4.0121292
OS 1.2987546 4.0123224
OS 1.2987546 4.0123362
OS 1.2987408 4.0123638
OS 1.2987132 4.012419
OS 1.2986856 4.012488
OS 1.2986442 4.0125708
OS 1.2986028 4.0126536
OS 1.2984786 4.0128744
OS 1.298313 4.0131228
OS 1.2981198 4.0133712
OS 1.2978852 4.0136058
OS 1.2976092 4.0138128
OS 1.2975954 4.0138128
OS 1.2975678 4.0138404
OS 1.2975264 4.0138542
OS 1.2974712 4.0138956
OS 1.2974022 4.013937
OS 1.2973056 4.0139784
OS 1.2970986 4.014075
OS 1.2968502 4.0141578
OS 1.2965604 4.0142406
OS 1.296243 4.0142958
OS 1.295898 4.0143234
OS 1.2958842 4.0143234
OS 1.2958428 4.0143234
OS 1.2957738 4.0143234
OS 1.2956772 4.0143096
OS 1.295553 4.0142958
OS 1.2954288 4.0142682
OS 1.295277 4.0142406
OS 1.2951114 4.0141992
OS 1.2949458 4.014144
OS 1.2947664 4.014075
OS 1.2945732 4.014006
OS 1.2943938 4.0139094
OS 1.2942006 4.0137852
OS 1.2940212 4.013661
OS 1.2938418 4.0135092
OS 1.2936762 4.0133298
OS 1.2936624 4.013316
OS 1.2936348 4.0132884
OS 1.2935934 4.0132194
OS 1.2935382 4.0131504
OS 1.2934692 4.01304
OS 1.2934002 4.012902
OS 1.2933174 4.0127502
OS 1.2932346 4.0125708
OS 1.2931518 4.0123776
OS 1.293069 4.012143
OS 1.293 4.0118808
OS 1.292931 4.0116048
OS 1.2928758 4.0113012
OS 1.2928344 4.01097
OS 1.2928068 4.0106112
OS 1.292793 4.0102248
OE
SE
S P 0
OB 2.1591076 3.9429751 I
OS 2.1591076 3.9427543
OS 2.1590938 3.9425059
OS 2.15908 3.9422437
OS 2.1590524 3.9419401
OS 2.1590248 3.9416365
OS 2.1589972 3.9413191
OS 2.1589006 3.9406705
OS 2.1588454 3.9403669
OS 2.1587764 3.9400633
OS 2.1586936 3.9397735
OS 2.158597 3.9395113
OS 2.158597 3.9394975
OS 2.1585694 3.9394561
OS 2.1585418 3.9393871
OS 2.1585004 3.9392905
OS 2.1584452 3.9391801
OS 2.1583624 3.9390559
OS 2.1582796 3.9389041
OS 2.158183 3.9387523
OS 2.1580588 3.9385867
OS 2.1579346 3.9384073
OS 2.1577828 3.9382279
OS 2.1576172 3.9380485
OS 2.157424 3.9378829
OS 2.1572308 3.9377035
OS 2.15701 3.9375379
OS 2.1567754 3.9373861
OS 2.1567616 3.9373723
OS 2.1567202 3.9373447
OS 2.1566512 3.9373171
OS 2.1565546 3.9372619
OS 2.1564304 3.9372067
OS 2.1562786 3.9371377
OS 2.156113 3.9370549
OS 2.1559336 3.9369859
OS 2.1557266 3.9369169
OS 2.1555058 3.9368341
OS 2.1552712 3.9367651
OS 2.1550228 3.9367099
OS 2.1547606 3.9366547
OS 2.1544846 3.9366133
OS 2.1541948 3.9365995
OS 2.153905 3.9365857
OS 2.1538774 3.9365857
OS 2.1538222 3.9365857
OS 2.1537118 3.9365995
OS 2.15356 3.9365995
OS 2.1533944 3.9366271
OS 2.1531874 3.9366547
OS 2.1529666 3.9366961
OS 2.1527182 3.9367513
OS 2.152456 3.9368203
OS 2.15218 3.9369031
OS 2.1518902 3.9370135
OS 2.1516004 3.9371377
OS 2.1513106 3.9372895
OS 2.1510346 3.9374689
OS 2.1507448 3.9376759
OS 2.1504826 3.9379105
OS 2.1504688 3.9379243
OS 2.1504274 3.9379657
OS 2.1503584 3.9380485
OS 2.1502618 3.9381589
OS 2.1501514 3.9382969
OS 2.1500272 3.9384763
OS 2.1498892 3.9386695
OS 2.1497374 3.9389041
OS 2.1495856 3.9391801
OS 2.1494338 3.9394699
OS 2.1492958 3.9398149
OS 2.149144 3.9401737
OS 2.1490198 3.9405739
OS 2.1488956 3.9410017
OS 2.148799 3.9414709
OS 2.1487162 3.9419677
OS 2.1487162 3.9419539
OS 2.1486886 3.9419263
OS 2.1486748 3.9418711
OS 2.1486334 3.9418021
OS 2.148592 3.9417193
OS 2.1485368 3.9416227
OS 2.1484126 3.9414019
OS 2.1482746 3.9411535
OS 2.148109 3.9409051
OS 2.1479434 3.9406705
OS 2.147764 3.9404497
OS 2.1477502 3.9404359
OS 2.1477226 3.9403945
OS 2.1476536 3.9403393
OS 2.1475846 3.9402565
OS 2.1474742 3.9401599
OS 2.1473638 3.9400495
OS 2.1472258 3.9399115
OS 2.1470602 3.9397735
OS 2.1468808 3.9396217
OS 2.1466876 3.9394561
OS 2.1464806 3.9392767
OS 2.1462598 3.9390973
OS 2.1460114 3.9389179
OS 2.145763 3.9387247
OS 2.145211 3.9383521
OS 2.1400222 3.9350539
OS 2.1400222 3.9382141
OS 2.1439966 3.9407395
OS 2.1440104 3.9407533
OS 2.1440656 3.9407947
OS 2.1441622 3.9408499
OS 2.1442726 3.9409189
OS 2.1444244 3.9410155
OS 2.14459 3.9411259
OS 2.1447694 3.9412501
OS 2.1449626 3.9413743
OS 2.1453904 3.9416641
OS 2.145832 3.9419677
OS 2.146246 3.9422713
OS 2.1464392 3.9424231
OS 2.1466186 3.9425611
OS 2.1466324 3.9425749
OS 2.14666 3.9425887
OS 2.1467014 3.9426301
OS 2.1467704 3.9426853
OS 2.146936 3.9428233
OS 2.1471292 3.9429889
OS 2.1473362 3.9431959
OS 2.147557 3.9434029
OS 2.1477502 3.9436237
OS 2.147902 3.9438445
OS 2.1479158 3.9438721
OS 2.1479572 3.9439411
OS 2.1480262 3.9440515
OS 2.1480952 3.9442033
OS 2.148178 3.9443689
OS 2.1482746 3.9445621
OS 2.1483436 3.9447691
OS 2.1484126 3.9449899
OS 2.1484126 3.9450037
OS 2.1484264 3.9450727
OS 2.1484402 3.9451831
OS 2.1484678 3.9453211
OS 2.1484816 3.9455143
OS 2.1484954 3.9457627
OS 2.1485092 3.9460525
OS 2.1485092 3.9493231
OS 2.1400222 3.9493231
OS 2.1400222 3.9518485
OS 2.1591214 3.9518485
OS 2.1591214 3.9431407
OS 2.1591076 3.9429751
OE
OB 2.1400222 3.9247453 I
OS 2.1400222 3.9270913
OS 2.1549538 3.9270913
OS 2.15494 3.9271051
OS 2.1549124 3.9271327
OS 2.154871 3.9271741
OS 2.1548158 3.9272431
OS 2.1547468 3.9273259
OS 2.1546502 3.9274363
OS 2.1545536 3.9275605
OS 2.1544432 3.9276847
OS 2.1543328 3.9278503
OS 2.1541948 3.9280159
OS 2.1540706 3.9281953
OS 2.1539188 3.9283885
OS 2.1537808 3.9286093
OS 2.153629 3.9288301
OS 2.1533254 3.9293269
OS 2.1533116 3.9293407
OS 2.153284 3.9293821
OS 2.1532426 3.9294649
OS 2.1532012 3.9295615
OS 2.1531322 3.9296719
OS 2.1530494 3.9298099
OS 2.1529666 3.9299755
OS 2.15287 3.9301411
OS 2.1526768 3.9305275
OS 2.1524836 3.9309415
OS 2.1522904 3.9313693
OS 2.1521248 3.9317833
OS 2.154388 3.9317833
OS 2.1544018 3.9317557
OS 2.1544294 3.9317005
OS 2.1544846 3.9315901
OS 2.1545536 3.9314521
OS 2.1546364 3.9312865
OS 2.1547468 3.9310795
OS 2.154871 3.9308587
OS 2.155009 3.9306241
OS 2.1551746 3.9303619
OS 2.1553402 3.9300859
OS 2.1557266 3.9295063
OS 2.1561544 3.9289129
OS 2.1566236 3.9283471
OS 2.1566374 3.9283333
OS 2.1566788 3.9282781
OS 2.1567478 3.9282091
OS 2.1568444 3.9281125
OS 2.1569686 3.9279883
OS 2.1571066 3.9278503
OS 2.1572722 3.9276985
OS 2.1574378 3.9275329
OS 2.157631 3.9273673
OS 2.157838 3.9271879
OS 2.1582658 3.9268429
OS 2.1587212 3.9265255
OS 2.1589558 3.9263875
OS 2.1591904 3.9262633
OS 2.1591904 3.9247453
OS 2.1400222 3.9247453
OE
OB 2.1591766 3.9121459 I
OS 2.1591628 3.9119527
OS 2.159149 3.9117181
OS 2.1591076 3.9114559
OS 2.1590662 3.9111523
OS 2.1589972 3.9108349
OS 2.1589144 3.9104899
OS 2.1588178 3.9101449
OS 2.1586936 3.9097723
OS 2.1585418 3.9094135
OS 2.1583624 3.9090547
OS 2.1581692 3.9087097
OS 2.1579346 3.9083785
OS 2.1576586 3.9080611
OS 2.1576448 3.9080473
OS 2.1575896 3.9079921
OS 2.1575068 3.9079093
OS 2.1573826 3.9078127
OS 2.1572446 3.9076885
OS 2.1570652 3.9075505
OS 2.1568582 3.9073987
OS 2.1566236 3.9072469
OS 2.1563614 3.9071089
OS 2.1560716 3.9069571
OS 2.1557542 3.9068191
OS 2.155423 3.9066949
OS 2.1550642 3.9065983
OS 2.1546916 3.9065155
OS 2.1542914 3.9064603
OS 2.1538774 3.9064465
OS 2.1538636 3.9064465
OS 2.1538222 3.9064465
OS 2.153767 3.9064465
OS 2.1536842 3.9064465
OS 2.1535738 3.9064603
OS 2.1534634 3.9064741
OS 2.1533254 3.9064879
OS 2.1531736 3.9065017
OS 2.1528286 3.9065569
OS 2.1524422 3.9066397
OS 2.152042 3.9067639
OS 2.151628 3.9069157
OS 2.1516142 3.9069157
OS 2.1515728 3.9069433
OS 2.1515176 3.9069709
OS 2.1514348 3.9070123
OS 2.1513382 3.9070537
OS 2.151214 3.9071227
OS 2.151076 3.9071917
OS 2.1509242 3.9072883
OS 2.1507586 3.9073849
OS 2.1505792 3.9074953
OS 2.150179 3.9077713
OS 2.149972 3.9079231
OS 2.1497512 3.9080887
OS 2.1495304 3.9082819
OS 2.1492958 3.9084751
OS 2.149282 3.9084889
OS 2.1492406 3.9085303
OS 2.1491716 3.9085855
OS 2.149075 3.9086821
OS 2.1489508 3.9088063
OS 2.148799 3.9089581
OS 2.1486196 3.9091237
OS 2.1484126 3.9093307
OS 2.1481918 3.9095653
OS 2.1479434 3.9098413
OS 2.1476674 3.9101311
OS 2.1473638 3.9104623
OS 2.1470464 3.9108211
OS 2.1467014 3.9112075
OS 2.1463288 3.9116353
OS 2.1459424 3.9120907
OS 2.1459286 3.9121183
OS 2.1458596 3.9121873
OS 2.1457768 3.9122839
OS 2.1456526 3.9124219
OS 2.1455146 3.9126013
OS 2.145349 3.9127807
OS 2.1451696 3.9129877
OS 2.1449764 3.9132085
OS 2.1445762 3.9136777
OS 2.1443692 3.9138985
OS 2.144176 3.9141193
OS 2.1439828 3.9143263
OS 2.1438172 3.9145057
OS 2.1436654 3.9146713
OS 2.1435274 3.9147955
OS 2.1434998 3.9148231
OS 2.143417 3.9148921
OS 2.1432928 3.9150025
OS 2.143141 3.9151405
OS 2.1429478 3.9152923
OS 2.1427408 3.9154579
OS 2.1425062 3.9156235
OS 2.1422716 3.9157753
OS 2.1422716 3.9064189
OS 2.1400222 3.9064189
OS 2.1400222 3.9190321
OS 2.140036 3.9190321
OS 2.1400636 3.9190321
OS 2.140105 3.9190321
OS 2.1401602 3.9190321
OS 2.140243 3.9190321
OS 2.1403258 3.9190183
OS 2.1405466 3.9190045
OS 2.1407812 3.9189769
OS 2.1410572 3.9189355
OS 2.141347 3.9188665
OS 2.1416368 3.9187699
OS 2.1416506 3.9187699
OS 2.141692 3.9187423
OS 2.141761 3.9187147
OS 2.1418576 3.9186733
OS 2.1419818 3.9186319
OS 2.1421198 3.9185629
OS 2.1422716 3.9184801
OS 2.1424372 3.9183973
OS 2.1426304 3.9183007
OS 2.1428236 3.9181765
OS 2.1432514 3.9179143
OS 2.1437068 3.9175969
OS 2.144176 3.9172243
OS 2.1441898 3.9172105
OS 2.1442312 3.9171691
OS 2.1443002 3.9171139
OS 2.1443968 3.9170311
OS 2.144521 3.9169207
OS 2.144659 3.9167827
OS 2.1448246 3.9166309
OS 2.145004 3.9164377
OS 2.145211 3.9162307
OS 2.1454318 3.9160099
OS 2.1456664 3.9157615
OS 2.1459286 3.9154855
OS 2.1461908 3.9151819
OS 2.1464668 3.9148645
OS 2.1467566 3.9145195
OS 2.1470602 3.9141607
OS 2.147074 3.9141469
OS 2.1470878 3.9141193
OS 2.1471292 3.9140779
OS 2.1471706 3.9140227
OS 2.1472396 3.9139537
OS 2.1473086 3.9138709
OS 2.147488 3.9136639
OS 2.147695 3.9134017
OS 2.1479572 3.9131257
OS 2.1482332 3.9128083
OS 2.1485368 3.9124771
OS 2.1488542 3.9121183
OS 2.1491854 3.9117733
OS 2.1495166 3.9114145
OS 2.1498616 3.9110833
OS 2.1501928 3.9107521
OS 2.1505102 3.9104623
OS 2.1508276 3.9101863
OS 2.1511174 3.9099655
OS 2.1511312 3.9099517
OS 2.1511864 3.9099241
OS 2.1512692 3.9098689
OS 2.1513658 3.9097861
OS 2.1515038 3.9097033
OS 2.1516556 3.9096205
OS 2.151835 3.9095101
OS 2.1520282 3.9094135
OS 2.1522352 3.9093169
OS 2.152456 3.9092065
OS 2.152939 3.9090271
OS 2.1531874 3.9089581
OS 2.1534358 3.9089029
OS 2.1536842 3.9088753
OS 2.1539326 3.9088615
OS 2.1539464 3.9088615
OS 2.1540016 3.9088615
OS 2.1540706 3.9088615
OS 2.1541672 3.9088753
OS 2.1542914 3.9088891
OS 2.1544294 3.9089167
OS 2.1545812 3.9089443
OS 2.1547468 3.9089857
OS 2.1549262 3.9090409
OS 2.1551194 3.9091099
OS 2.1553126 3.9091927
OS 2.1555058 3.9092893
OS 2.1557128 3.9093997
OS 2.155906 3.9095377
OS 2.1560992 3.9096895
OS 2.1562786 3.9098689
OS 2.1562924 3.9098827
OS 2.15632 3.9099103
OS 2.1563614 3.9099655
OS 2.1564304 3.9100483
OS 2.1564994 3.9101449
OS 2.1565822 3.9102691
OS 2.1566788 3.9104071
OS 2.1567616 3.9105589
OS 2.1568582 3.9107383
OS 2.156941 3.9109315
OS 2.1570238 3.9111523
OS 2.1570928 3.9113731
OS 2.1571618 3.9116215
OS 2.1572032 3.9118837
OS 2.1572308 3.9121597
OS 2.1572446 3.9124495
OS 2.1572446 3.9126151
OS 2.1572308 3.9127255
OS 2.157217 3.9128773
OS 2.1571894 3.9130429
OS 2.1571618 3.9132223
OS 2.1571204 3.9134293
OS 2.1570652 3.9136363
OS 2.1569962 3.9138571
OS 2.1569134 3.9140779
OS 2.1568168 3.9143125
OS 2.1566926 3.9145333
OS 2.1565546 3.9147541
OS 2.1564028 3.9149749
OS 2.1562234 3.9151681
OS 2.1562096 3.9151819
OS 2.156182 3.9152095
OS 2.156113 3.9152647
OS 2.156044 3.9153199
OS 2.1559336 3.9154027
OS 2.1558094 3.9154855
OS 2.1556576 3.9155821
OS 2.155492 3.9156649
OS 2.1553126 3.9157615
OS 2.1550918 3.9158581
OS 2.154871 3.9159409
OS 2.1546226 3.9160237
OS 2.1543466 3.9160789
OS 2.1540568 3.9161341
OS 2.1537532 3.9161617
OS 2.153422 3.9161755
OS 2.1536704 3.9185905
OS 2.1536842 3.9185905
OS 2.153698 3.9185905
OS 2.1537394 3.9185767
OS 2.1537946 3.9185767
OS 2.1539326 3.9185629
OS 2.154112 3.9185215
OS 2.1543328 3.9184801
OS 2.154595 3.9184249
OS 2.1548848 3.9183559
OS 2.1551884 3.9182731
OS 2.1555196 3.9181627
OS 2.1558508 3.9180385
OS 2.1561958 3.9178867
OS 2.1565408 3.9177073
OS 2.156872 3.9175141
OS 2.1571894 3.9172795
OS 2.157493 3.9170311
OS 2.157769 3.9167413
OS 2.1577828 3.9167275
OS 2.1578242 3.9166723
OS 2.157907 3.9165757
OS 2.1579898 3.9164515
OS 2.1581002 3.9162859
OS 2.1582244 3.9160927
OS 2.1583486 3.9158581
OS 2.1584866 3.9155959
OS 2.1586108 3.9152923
OS 2.158735 3.9149749
OS 2.1588592 3.9146161
OS 2.1589696 3.9142297
OS 2.1590662 3.9138157
OS 2.1591352 3.9133741
OS 2.1591766 3.9129049
OS 2.1591904 3.9124081
OS 2.1591904 3.9122839
OS 2.1591766 3.9121459
OE
OB 2.15701 3.9432925 H
OS 2.15701 3.9493231
OS 2.1507034 3.9493231
OS 2.1507034 3.9436099
OS 2.1507172 3.9434719
OS 2.1507172 3.9432925
OS 2.150731 3.9431131
OS 2.1507448 3.9429061
OS 2.1507862 3.9424783
OS 2.1508552 3.9420229
OS 2.150938 3.9415813
OS 2.1509932 3.9413881
OS 2.1510484 3.9411949
OS 2.1510484 3.9411811
OS 2.1510622 3.9411535
OS 2.1510898 3.9410983
OS 2.1511174 3.9410293
OS 2.1511588 3.9409465
OS 2.1512002 3.9408637
OS 2.1513244 3.9406429
OS 2.15149 3.9403945
OS 2.1516832 3.9401461
OS 2.1519178 3.9399115
OS 2.1521938 3.9397045
OS 2.1522076 3.9397045
OS 2.1522352 3.9396769
OS 2.1522766 3.9396631
OS 2.1523318 3.9396217
OS 2.1524008 3.9395803
OS 2.1524974 3.9395389
OS 2.1527044 3.9394423
OS 2.1529528 3.9393595
OS 2.1532426 3.9392767
OS 2.15356 3.9392215
OS 2.153905 3.9391939
OS 2.1539188 3.9391939
OS 2.1539602 3.9391939
OS 2.1540292 3.9391939
OS 2.1541258 3.9392077
OS 2.15425 3.9392215
OS 2.1543742 3.9392491
OS 2.154526 3.9392767
OS 2.1546916 3.9393181
OS 2.1548572 3.9393733
OS 2.1550366 3.9394423
OS 2.1552298 3.9395113
OS 2.1554092 3.9396079
OS 2.1556024 3.9397321
OS 2.1557818 3.9398563
OS 2.1559612 3.9400081
OS 2.1561268 3.9401875
OS 2.1561406 3.9402013
OS 2.1561682 3.9402289
OS 2.1562096 3.9402979
OS 2.1562648 3.9403669
OS 2.1563338 3.9404773
OS 2.1564028 3.9406153
OS 2.1564856 3.9407671
OS 2.1565684 3.9409465
OS 2.1566512 3.9411397
OS 2.156734 3.9413743
OS 2.156803 3.9416365
OS 2.156872 3.9419125
OS 2.1569272 3.9422161
OS 2.1569686 3.9425473
OS 2.1569962 3.9429061
OS 2.15701 3.9432925
OE
SE
S P 0
OB 2.221288 3.9440559 I
OS 2.221288 3.9438351
OS 2.2212742 3.9435867
OS 2.2212604 3.9433245
OS 2.2212328 3.9430209
OS 2.2212052 3.9427173
OS 2.2211776 3.9423999
OS 2.221081 3.9417513
OS 2.2210258 3.9414477
OS 2.2209568 3.9411441
OS 2.220874 3.9408543
OS 2.2207774 3.9405921
OS 2.2207774 3.9405783
OS 2.2207498 3.9405369
OS 2.2207222 3.9404679
OS 2.2206808 3.9403713
OS 2.2206256 3.9402609
OS 2.2205428 3.9401367
OS 2.22046 3.9399849
OS 2.2203634 3.9398331
OS 2.2202392 3.9396675
OS 2.220115 3.9394881
OS 2.2199632 3.9393087
OS 2.2197976 3.9391293
OS 2.2196044 3.9389637
OS 2.2194112 3.9387843
OS 2.2191904 3.9386187
OS 2.2189558 3.9384669
OS 2.218942 3.9384531
OS 2.2189006 3.9384255
OS 2.2188316 3.9383979
OS 2.218735 3.9383427
OS 2.2186108 3.9382875
OS 2.218459 3.9382185
OS 2.2182934 3.9381357
OS 2.218114 3.9380667
OS 2.217907 3.9379977
OS 2.2176862 3.9379149
OS 2.2174516 3.9378459
OS 2.2172032 3.9377907
OS 2.216941 3.9377355
OS 2.216665 3.9376941
OS 2.2163752 3.9376803
OS 2.2160854 3.9376665
OS 2.2160578 3.9376665
OS 2.2160026 3.9376665
OS 2.2158922 3.9376803
OS 2.2157404 3.9376803
OS 2.2155748 3.9377079
OS 2.2153678 3.9377355
OS 2.215147 3.9377769
OS 2.2148986 3.9378321
OS 2.2146364 3.9379011
OS 2.2143604 3.9379839
OS 2.2140706 3.9380943
OS 2.2137808 3.9382185
OS 2.213491 3.9383703
OS 2.213215 3.9385497
OS 2.2129252 3.9387567
OS 2.212663 3.9389913
OS 2.2126492 3.9390051
OS 2.2126078 3.9390465
OS 2.2125388 3.9391293
OS 2.2124422 3.9392397
OS 2.2123318 3.9393777
OS 2.2122076 3.9395571
OS 2.2120696 3.9397503
OS 2.2119178 3.9399849
OS 2.211766 3.9402609
OS 2.2116142 3.9405507
OS 2.2114762 3.9408957
OS 2.2113244 3.9412545
OS 2.2112002 3.9416547
OS 2.211076 3.9420825
OS 2.2109794 3.9425517
OS 2.2108966 3.9430485
OS 2.2108966 3.9430347
OS 2.210869 3.9430071
OS 2.2108552 3.9429519
OS 2.2108138 3.9428829
OS 2.2107724 3.9428001
OS 2.2107172 3.9427035
OS 2.210593 3.9424827
OS 2.210455 3.9422343
OS 2.2102894 3.9419859
OS 2.2101238 3.9417513
OS 2.2099444 3.9415305
OS 2.2099306 3.9415167
OS 2.209903 3.9414753
OS 2.209834 3.9414201
OS 2.209765 3.9413373
OS 2.2096546 3.9412407
OS 2.2095442 3.9411303
OS 2.2094062 3.9409923
OS 2.2092406 3.9408543
OS 2.2090612 3.9407025
OS 2.208868 3.9405369
OS 2.208661 3.9403575
OS 2.2084402 3.9401781
OS 2.2081918 3.9399987
OS 2.2079434 3.9398055
OS 2.2073914 3.9394329
OS 2.2022026 3.9361347
OS 2.2022026 3.9392949
OS 2.206177 3.9418203
OS 2.2061908 3.9418341
OS 2.206246 3.9418755
OS 2.2063426 3.9419307
OS 2.206453 3.9419997
OS 2.2066048 3.9420963
OS 2.2067704 3.9422067
OS 2.2069498 3.9423309
OS 2.207143 3.9424551
OS 2.2075708 3.9427449
OS 2.2080124 3.9430485
OS 2.2084264 3.9433521
OS 2.2086196 3.9435039
OS 2.208799 3.9436419
OS 2.2088128 3.9436557
OS 2.2088404 3.9436695
OS 2.2088818 3.9437109
OS 2.2089508 3.9437661
OS 2.2091164 3.9439041
OS 2.2093096 3.9440697
OS 2.2095166 3.9442767
OS 2.2097374 3.9444837
OS 2.2099306 3.9447045
OS 2.2100824 3.9449253
OS 2.2100962 3.9449529
OS 2.2101376 3.9450219
OS 2.2102066 3.9451323
OS 2.2102756 3.9452841
OS 2.2103584 3.9454497
OS 2.210455 3.9456429
OS 2.210524 3.9458499
OS 2.210593 3.9460707
OS 2.210593 3.9460845
OS 2.2106068 3.9461535
OS 2.2106206 3.9462639
OS 2.2106482 3.9464019
OS 2.210662 3.9465951
OS 2.2106758 3.9468435
OS 2.2106896 3.9471333
OS 2.2106896 3.9504039
OS 2.2022026 3.9504039
OS 2.2022026 3.9529293
OS 2.2213018 3.9529293
OS 2.2213018 3.9442215
OS 2.221288 3.9440559
OE
OB 2.2022026 3.9258261 I
OS 2.2022026 3.9281721
OS 2.2171342 3.9281721
OS 2.2171204 3.9281859
OS 2.2170928 3.9282135
OS 2.2170514 3.9282549
OS 2.2169962 3.9283239
OS 2.2169272 3.9284067
OS 2.2168306 3.9285171
OS 2.216734 3.9286413
OS 2.2166236 3.9287655
OS 2.2165132 3.9289311
OS 2.2163752 3.9290967
OS 2.216251 3.9292761
OS 2.2160992 3.9294693
OS 2.2159612 3.9296901
OS 2.2158094 3.9299109
OS 2.2155058 3.9304077
OS 2.215492 3.9304215
OS 2.2154644 3.9304629
OS 2.215423 3.9305457
OS 2.2153816 3.9306423
OS 2.2153126 3.9307527
OS 2.2152298 3.9308907
OS 2.215147 3.9310563
OS 2.2150504 3.9312219
OS 2.2148572 3.9316083
OS 2.214664 3.9320223
OS 2.2144708 3.9324501
OS 2.2143052 3.9328641
OS 2.2165684 3.9328641
OS 2.2165822 3.9328365
OS 2.2166098 3.9327813
OS 2.216665 3.9326709
OS 2.216734 3.9325329
OS 2.2168168 3.9323673
OS 2.2169272 3.9321603
OS 2.2170514 3.9319395
OS 2.2171894 3.9317049
OS 2.217355 3.9314427
OS 2.2175206 3.9311667
OS 2.217907 3.9305871
OS 2.2183348 3.9299937
OS 2.218804 3.9294279
OS 2.2188178 3.9294141
OS 2.2188592 3.9293589
OS 2.2189282 3.9292899
OS 2.2190248 3.9291933
OS 2.219149 3.9290691
OS 2.219287 3.9289311
OS 2.2194526 3.9287793
OS 2.2196182 3.9286137
OS 2.2198114 3.9284481
OS 2.2200184 3.9282687
OS 2.2204462 3.9279237
OS 2.2209016 3.9276063
OS 2.2211362 3.9274683
OS 2.2213708 3.9273441
OS 2.2213708 3.9258261
OS 2.2022026 3.9258261
OE
OB 2.221357 3.9135717 I
OS 2.221357 3.9134337
OS 2.2213294 3.9132681
OS 2.2213156 3.9130887
OS 2.221288 3.9128955
OS 2.2212466 3.9126747
OS 2.2212052 3.9124539
OS 2.221081 3.9119709
OS 2.221012 3.9117087
OS 2.2209154 3.9114603
OS 2.2208188 3.9112119
OS 2.2206946 3.9109635
OS 2.2206808 3.9109497
OS 2.220667 3.9109083
OS 2.2206256 3.9108393
OS 2.2205704 3.9107427
OS 2.2205014 3.9106323
OS 2.2204186 3.9105081
OS 2.220322 3.9103701
OS 2.2202116 3.9102183
OS 2.2199494 3.9098871
OS 2.219632 3.9095559
OS 2.2192732 3.9092385
OS 2.2190662 3.9090867
OS 2.2188592 3.9089487
OS 2.2188454 3.9089349
OS 2.218804 3.9089211
OS 2.2187488 3.9088797
OS 2.2186522 3.9088383
OS 2.2185556 3.9087831
OS 2.2184176 3.9087279
OS 2.2182796 3.9086589
OS 2.218114 3.9085899
OS 2.2179346 3.9085347
OS 2.2177552 3.9084657
OS 2.2173412 3.9083553
OS 2.2168858 3.9082725
OS 2.2166512 3.9082587
OS 2.2164028 3.9082449
OS 2.216389 3.9082449
OS 2.2163476 3.9082449
OS 2.2162786 3.9082449
OS 2.2161958 3.9082587
OS 2.2160854 3.9082587
OS 2.2159612 3.9082863
OS 2.2158094 3.9083001
OS 2.2156576 3.9083277
OS 2.2152988 3.9084105
OS 2.2149262 3.9085347
OS 2.214733 3.9086037
OS 2.214526 3.9087003
OS 2.2143328 3.9087969
OS 2.2141396 3.9089211
OS 2.2141258 3.9089349
OS 2.2140982 3.9089487
OS 2.214043 3.9089901
OS 2.213974 3.9090453
OS 2.2138912 3.9091143
OS 2.2137946 3.9091971
OS 2.2136842 3.9092937
OS 2.21356 3.9094179
OS 2.2134358 3.9095421
OS 2.2133116 3.9096939
OS 2.2131736 3.9098457
OS 2.2130356 3.9100251
OS 2.2129114 3.9102183
OS 2.2127734 3.9104253
OS 2.2126492 3.9106461
OS 2.2125388 3.9108807
OS 2.2125388 3.9108669
OS 2.212525 3.9108117
OS 2.2124974 3.9107151
OS 2.212456 3.9106047
OS 2.2124146 3.9104529
OS 2.2123456 3.9102873
OS 2.2122766 3.9101079
OS 2.21218 3.9099147
OS 2.2120834 3.9097077
OS 2.2119592 3.9094869
OS 2.211835 3.9092661
OS 2.2116832 3.9090453
OS 2.2115176 3.9088383
OS 2.2113382 3.9086313
OS 2.2111312 3.9084243
OS 2.2109104 3.9082449
OS 2.2108966 3.9082311
OS 2.2108552 3.9082035
OS 2.2107862 3.9081621
OS 2.2106896 3.9080931
OS 2.2105654 3.9080241
OS 2.2104274 3.9079413
OS 2.2102618 3.9078585
OS 2.2100686 3.9077757
OS 2.2098478 3.9076929
OS 2.2096132 3.9075963
OS 2.2093648 3.9075273
OS 2.2090888 3.9074583
OS 2.208799 3.9073893
OS 2.2084954 3.9073479
OS 2.208178 3.9073203
OS 2.207833 3.9073065
OS 2.2078054 3.9073065
OS 2.2077226 3.9073065
OS 2.2075846 3.9073203
OS 2.207419 3.9073341
OS 2.2071982 3.9073617
OS 2.2069498 3.9074031
OS 2.2066738 3.9074583
OS 2.2063702 3.9075411
OS 2.206039 3.9076377
OS 2.2057078 3.9077481
OS 2.205349 3.9078999
OS 2.2049902 3.9080793
OS 2.2046314 3.9082863
OS 2.2042726 3.9085347
OS 2.2039276 3.9088245
OS 2.2035964 3.9091419
OS 2.2035826 3.9091695
OS 2.2035274 3.9092247
OS 2.2034308 3.9093213
OS 2.2033204 3.9094731
OS 2.2031962 3.9096525
OS 2.2030444 3.9098595
OS 2.2028926 3.9101217
OS 2.202727 3.9103977
OS 2.2025614 3.9107151
OS 2.2024096 3.9110739
OS 2.2022578 3.9114465
OS 2.2021336 3.9118605
OS 2.2020232 3.9122883
OS 2.2019266 3.9127575
OS 2.2018714 3.9132405
OS 2.2018576 3.9137511
OS 2.2018576 3.9138615
OS 2.2018714 3.9139995
OS 2.2018852 3.9141651
OS 2.201899 3.9143859
OS 2.2019404 3.9146343
OS 2.2019818 3.9149103
OS 2.2020508 3.9152139
OS 2.2021198 3.9155313
OS 2.2022164 3.9158763
OS 2.2023406 3.9162213
OS 2.2024924 3.9165801
OS 2.202658 3.9169251
OS 2.2028512 3.9172701
OS 2.2030858 3.9176151
OS 2.203348 3.9179325
OS 2.2033618 3.9179463
OS 2.203417 3.9180015
OS 2.2034998 3.9180843
OS 2.203624 3.9181947
OS 2.2037758 3.9183189
OS 2.2039552 3.9184707
OS 2.2041622 3.9186225
OS 2.2043968 3.9187881
OS 2.204659 3.9189537
OS 2.2049626 3.9191193
OS 2.20528 3.9192711
OS 2.205625 3.9194229
OS 2.2059976 3.9195471
OS 2.206384 3.9196713
OS 2.206798 3.9197541
OS 2.2072396 3.9198093
OS 2.207557 3.9174633
OS 2.2075294 3.9174633
OS 2.2074742 3.9174495
OS 2.2073638 3.9174219
OS 2.2072258 3.9173805
OS 2.2070602 3.9173391
OS 2.2068808 3.9172839
OS 2.2066738 3.9172149
OS 2.206453 3.9171459
OS 2.20597 3.9169527
OS 2.2055008 3.9167181
OS 2.2052662 3.9165801
OS 2.2050454 3.9164283
OS 2.2048522 3.9162765
OS 2.2046728 3.9160971
OS 2.204659 3.9160833
OS 2.2046314 3.9160557
OS 2.20459 3.9160005
OS 2.2045348 3.9159177
OS 2.2044658 3.9158349
OS 2.2043968 3.9157107
OS 2.204314 3.9155865
OS 2.204245 3.9154347
OS 2.2041622 3.9152691
OS 2.2040794 3.9150897
OS 2.2040104 3.9148965
OS 2.2039414 3.9146895
OS 2.2038862 3.9144687
OS 2.2038448 3.9142341
OS 2.2038172 3.9139995
OS 2.2038034 3.9137373
OS 2.2038034 3.9136683
OS 2.2038172 3.9135717
OS 2.2038172 3.9134613
OS 2.2038448 3.9133095
OS 2.2038586 3.9131439
OS 2.2039 3.9129645
OS 2.2039414 3.9127575
OS 2.2040104 3.9125505
OS 2.2040794 3.9123159
OS 2.204176 3.9120813
OS 2.2042864 3.9118467
OS 2.2044244 3.9116121
OS 2.2045762 3.9113775
OS 2.2047418 3.9111567
OS 2.2049488 3.9109359
OS 2.2049626 3.9109221
OS 2.205004 3.9108807
OS 2.2050592 3.9108255
OS 2.2051558 3.9107565
OS 2.2052662 3.9106737
OS 2.2054042 3.9105771
OS 2.205556 3.9104667
OS 2.2057354 3.9103563
OS 2.2059286 3.9102597
OS 2.2061494 3.9101493
OS 2.2063702 3.9100527
OS 2.2066324 3.9099699
OS 2.2068946 3.9099009
OS 2.2071706 3.9098457
OS 2.2074742 3.9098043
OS 2.2077778 3.9097905
OS 2.2077916 3.9097905
OS 2.2078468 3.9097905
OS 2.2079296 3.9097905
OS 2.2080538 3.9098043
OS 2.208178 3.9098181
OS 2.2083436 3.9098457
OS 2.208523 3.9098733
OS 2.2087162 3.9099285
OS 2.2089232 3.9099837
OS 2.209144 3.9100527
OS 2.2093648 3.9101355
OS 2.2095856 3.9102321
OS 2.2098064 3.9103563
OS 2.2100272 3.9105081
OS 2.2102342 3.9106599
OS 2.2104412 3.9108531
OS 2.210455 3.9108669
OS 2.2104826 3.9108945
OS 2.2105378 3.9109635
OS 2.2106068 3.9110463
OS 2.2106896 3.9111429
OS 2.2107724 3.9112671
OS 2.210869 3.9114189
OS 2.2109656 3.9115845
OS 2.2110622 3.9117639
OS 2.2111588 3.9119709
OS 2.2112416 3.9121917
OS 2.2113244 3.9124263
OS 2.2113934 3.9126747
OS 2.2114486 3.9129507
OS 2.2114762 3.9132267
OS 2.21149 3.9135303
OS 2.21149 3.9136545
OS 2.2114762 3.9137925
OS 2.2114624 3.9139857
OS 2.2114348 3.9142341
OS 2.2113796 3.9145101
OS 2.2113244 3.9148275
OS 2.2112416 3.9151863
OS 2.2132978 3.9149241
OS 2.2132978 3.9148827
OS 2.213284 3.9148413
OS 2.213284 3.9147861
OS 2.2132702 3.9146619
OS 2.2132702 3.9143997
OS 2.213284 3.9143031
OS 2.2132978 3.9141651
OS 2.2133116 3.9140133
OS 2.2133392 3.9138477
OS 2.2133668 3.9136545
OS 2.2134082 3.9134475
OS 2.2134634 3.9132405
OS 2.2136014 3.9127851
OS 2.2136842 3.9125505
OS 2.2137946 3.9123159
OS 2.213905 3.9120813
OS 2.214043 3.9118605
OS 2.2140568 3.9118467
OS 2.2140844 3.9118053
OS 2.2141258 3.9117501
OS 2.2141948 3.9116673
OS 2.2142776 3.9115845
OS 2.2143742 3.9114741
OS 2.2144984 3.9113775
OS 2.2146364 3.9112533
OS 2.214802 3.9111429
OS 2.2149814 3.9110325
OS 2.2151746 3.9109359
OS 2.2153954 3.9108531
OS 2.21563 3.9107703
OS 2.2158922 3.9107151
OS 2.2161682 3.9106737
OS 2.216458 3.9106599
OS 2.2164718 3.9106599
OS 2.2165132 3.9106599
OS 2.2165822 3.9106599
OS 2.2166788 3.9106737
OS 2.2167754 3.9106875
OS 2.2169134 3.9107013
OS 2.2170514 3.9107289
OS 2.2172032 3.9107703
OS 2.2175344 3.9108807
OS 2.2177138 3.9109497
OS 2.2178932 3.9110325
OS 2.2180726 3.9111291
OS 2.218252 3.9112533
OS 2.2184176 3.9113913
OS 2.2185832 3.9115431
OS 2.218597 3.9115569
OS 2.2186246 3.9115845
OS 2.218666 3.9116259
OS 2.2187212 3.9116949
OS 2.2187764 3.9117915
OS 2.2188592 3.9118881
OS 2.2189282 3.9120123
OS 2.219011 3.9121503
OS 2.2190938 3.9123021
OS 2.2191628 3.9124677
OS 2.2192456 3.9126609
OS 2.2193008 3.9128541
OS 2.219356 3.9130749
OS 2.2193974 3.9132957
OS 2.219425 3.9135441
OS 2.2194388 3.9137925
OS 2.2194388 3.9139305
OS 2.219425 3.9140133
OS 2.2194112 3.9141375
OS 2.2193974 3.9142755
OS 2.2193698 3.9144273
OS 2.2193284 3.9145929
OS 2.2192318 3.9149517
OS 2.2191628 3.9151311
OS 2.2190662 3.9153243
OS 2.2189696 3.9155175
OS 2.2188592 3.9157107
OS 2.2187212 3.9158901
OS 2.2185694 3.9160695
OS 2.2185556 3.9160833
OS 2.218528 3.9161109
OS 2.2184728 3.9161523
OS 2.2184038 3.9162213
OS 2.218321 3.9162903
OS 2.2182106 3.9163731
OS 2.2180726 3.9164559
OS 2.2179346 3.9165525
OS 2.2177552 3.9166491
OS 2.217562 3.9167457
OS 2.217355 3.9168561
OS 2.2171204 3.9169389
OS 2.216872 3.9170355
OS 2.2166098 3.9171045
OS 2.21632 3.9171735
OS 2.2160026 3.9172287
OS 2.2164166 3.9195747
OS 2.2164304 3.9195747
OS 2.2164442 3.9195747
OS 2.216527 3.9195471
OS 2.2166374 3.9195195
OS 2.216803 3.9194781
OS 2.21701 3.9194229
OS 2.2172308 3.9193539
OS 2.2174792 3.9192711
OS 2.2177552 3.9191745
OS 2.218045 3.9190503
OS 2.2183486 3.9189123
OS 2.2186522 3.9187467
OS 2.2189558 3.9185673
OS 2.2192594 3.9183741
OS 2.2195492 3.9181533
OS 2.2198252 3.9179049
OS 2.2200736 3.9176289
OS 2.2200874 3.9176151
OS 2.2201288 3.9175599
OS 2.2201978 3.9174771
OS 2.2202806 3.9173529
OS 2.2203772 3.9172011
OS 2.2204876 3.9170217
OS 2.220598 3.9168147
OS 2.2207222 3.9165801
OS 2.2208464 3.9163179
OS 2.2209568 3.9160281
OS 2.2210672 3.9157245
OS 2.2211638 3.9153933
OS 2.2212466 3.9150345
OS 2.2213156 3.9146481
OS 2.221357 3.9142479
OS 2.2213708 3.9138339
OS 2.2213708 3.9136821
OS 2.221357 3.9135717
OE
OB 2.2191904 3.9443733 H
OS 2.2191904 3.9504039
OS 2.2128838 3.9504039
OS 2.2128838 3.9446907
OS 2.2128976 3.9445527
OS 2.2128976 3.9443733
OS 2.2129114 3.9441939
OS 2.2129252 3.9439869
OS 2.2129666 3.9435591
OS 2.2130356 3.9431037
OS 2.2131184 3.9426621
OS 2.2131736 3.9424689
OS 2.2132288 3.9422757
OS 2.2132288 3.9422619
OS 2.2132426 3.9422343
OS 2.2132702 3.9421791
OS 2.2132978 3.9421101
OS 2.2133392 3.9420273
OS 2.2133806 3.9419445
OS 2.2135048 3.9417237
OS 2.2136704 3.9414753
OS 2.2138636 3.9412269
OS 2.2140982 3.9409923
OS 2.2143742 3.9407853
OS 2.214388 3.9407853
OS 2.2144156 3.9407577
OS 2.214457 3.9407439
OS 2.2145122 3.9407025
OS 2.2145812 3.9406611
OS 2.2146778 3.9406197
OS 2.2148848 3.9405231
OS 2.2151332 3.9404403
OS 2.215423 3.9403575
OS 2.2157404 3.9403023
OS 2.2160854 3.9402747
OS 2.2160992 3.9402747
OS 2.2161406 3.9402747
OS 2.2162096 3.9402747
OS 2.2163062 3.9402885
OS 2.2164304 3.9403023
OS 2.2165546 3.9403299
OS 2.2167064 3.9403575
OS 2.216872 3.9403989
OS 2.2170376 3.9404541
OS 2.217217 3.9405231
OS 2.2174102 3.9405921
OS 2.2175896 3.9406887
OS 2.2177828 3.9408129
OS 2.2179622 3.9409371
OS 2.2181416 3.9410889
OS 2.2183072 3.9412683
OS 2.218321 3.9412821
OS 2.2183486 3.9413097
OS 2.21839 3.9413787
OS 2.2184452 3.9414477
OS 2.2185142 3.9415581
OS 2.2185832 3.9416961
OS 2.218666 3.9418479
OS 2.2187488 3.9420273
OS 2.2188316 3.9422205
OS 2.2189144 3.9424551
OS 2.2189834 3.9427173
OS 2.2190524 3.9429933
OS 2.2191076 3.9432969
OS 2.219149 3.9436281
OS 2.2191766 3.9439869
OS 2.2191904 3.9443733
OE
SE

### steps/pcb/layers/top_paste/features
#Layer_Color=8421504
#
#Feature symbol names
#
$0 r3.937
$1 r1
$2 oval78.7402x23.622
$3 rect39.3701x74.8031
$4 rect70.8661x74.8031
$5 rect55.9055x61.0236
$6 rect17.7165x54.3307
$7 rect64.9606x51.1811
$8 rect78.7402x98.4252
$9 rect19.685x90.5512
$10 rect41.3386x39.3701
$11 rect86.6142x41.3386
$12 rect19.685x35.4331
$13 oval57.0866x17.7165
$14 rect77.5591x22.4409
$15 rect25.5906x41.3386
$16 rect51.1811x74.8031
$17 rect39.3701x70.8661
$18 rect39.3701x90.5512
$19 rect41.3386x45.2756
$20 rect27.5591x45.2756
$21 rect53.1496x27.5591
$22 rect50x200
$23 rect57.0866x37.4016
$24 rect28.3465x39.3701
$25 rect25.5906x23.622
$26 rect28x165
$27 rect28x126
$28 rect31.4961x66.9291
$29 rect70.8661x9.8425
$30 rect26.5748x9.8425
$31 rect9.8425x22.6378
$32 rect27.5591x35.4331
$33 rect38.5827x34.252
$34 rect212.5984x114.1732
$35 rect165.3543x125.9843
$36 rect96.4567x124.0157
$37 rect33.4646x39.3701
$38 rect57.0866x45.2756
$39 rect37.4016x39.3701
$40 rect25.1969x26.7717
$41 rect10.8268x9.8425
$42 rect9.8425x10.8268
$43 rect61.02x9.84
$44 rect66.93x53.15
$45 rect9.84x61.02
$46 rect53.15x66.93
$47 rect45.2756x57.0866
$48 rect26.7717x25.1969
$49 rect39.3701x37.4016
$50 rect39.3701x33.4646
$51 rect39.3701x28.3465
$52 rect23.622x25.5906
$53 rect82.874x44.0945
$54 rect35.4331x27.5591

#
#Feature attribute names
#
@0 .geometry
@1 .pad_usage

#
#Feature attribute text strings
#
&0 SMD_OvalX78.7402Y23.6220
&1 SMD_RectX39.3701Y74.8031
&2 SMD_RectX70.8661Y74.8031
&3 SMD_RectX55.9055Y61.0236
&4 SMD_RectX17.7165Y54.3307
&5 SMD_RectX64.9606Y51.1811
&6 SMD_RectX78.7402Y98.4252
&7 SMD_RectX19.6850Y90.5512
&8 SMD_RectX41.3386Y39.3701
&9 SMD_RectX86.6142Y41.3386
&10 SMD_RectX19.6850Y35.4331
&11 SMD_OvalX57.0866Y17.7165
&12 SMD_RectX77.5591Y22.4409
&13 SMD_RectX25.5906Y41.3386
&14 SMD_RectX51.1811Y74.8031
&15 SMD_RectX39.3701Y70.8661
&16 SMD_RectX39.3701Y90.5512
&17 SMD_RectX41.3386Y45.2756
&18 SMD_RectX27.5591Y45.2756
&19 SMD_RectX53.1496Y27.5591
&20 SMD_RectX50.0000Y200.0000
&21 SMD_RectX57.0866Y37.4016
&22 SMD_RectX28.3465Y39.3701
&23 SMD_RectX25.5906Y23.6220
&24 SMD_RectX28.0000Y165.0000
&25 SMD_RectX28.0000Y126.0000
&26 SMD_RectX31.4961Y66.9291
&27 SMD_RectX70.8661Y9.8425
&28 SMD_RectX26.5748Y9.8425
&29 SMD_RectX9.8425Y22.6378
&30 SMD_RectX27.5591Y35.4331
&31 SMD_RectX38.5827Y34.2520
&32 SMD_RectX212.5984Y114.1732
&33 SMD_RectX165.3543Y125.9843
&34 SMD_RectX96.4567Y124.0157
&35 SMD_RectX33.4646Y39.3701
&36 SMD_RectX57.0866Y45.2756
&37 SMD_RectX37.4016Y39.3701
&38 SMD_RectX25.1969Y26.7717
&39 SMD_RectX10.8268Y9.8425
&40 SMD_RectX9.8425Y10.8268
&41 SMD_RectX61.0200Y9.8400
&42 SMD_RectX66.9300Y53.1500
&43 SMD_RectX9.8400Y61.0200
&44 SMD_RectX53.1500Y66.9300
&45 SMD_RectX45.2756Y57.0866
&46 SMD_RectX26.7717Y25.1969
&47 SMD_RectX39.3701Y37.4016
&48 SMD_RectX39.3701Y33.4646
&49 SMD_RectX39.3701Y28.3465
&50 SMD_RectX23.6220Y25.5906
&51 SMD_RectX82.8740Y44.0945
&52 SMD_RectX35.4331Y27.5591

#
#Layer features
#
A 1.7712204 0.4310709 1.6275196 0.4310709 1.69937 0.4310709 0 P 0 N
L -0.0001175 0.177913 0.5908825 0.177913 1 P 0
L -0.0004331 0.1781182 0.5901181 0.1781182 0 P 0
L 0.5901181 0.1781182 0.5901181 0.5029213 0 P 0
L 0.5901181 0.5029213 1.312559 0.5029213 0 P 0
L 0.5908825 0.177913 0.5908825 0.502913 1 P 0
L 1.312559 0.313945 1.312559 0.5029213 0 P 0
L 1.312559 0.313945 1.6275197 0.313945 0 P 0
L 1.6275197 0.313945 1.6275197 0.4310709 0 P 0
P 0.5948031 0.906063 10 P 0 0 ;0=8,1=0
P 0.5948031 1.431063 10 P 0 0 ;0=8,1=0
P 0.5948031 1.956063 10 P 0 0 ;0=8,1=0
P 0.5948031 2.481063 10 P 0 0 ;0=8,1=0
P 0.6389685 4.0388976 51 P 0 0 ;0=49,1=0
P 0.6389685 4.0932283 51 P 0 0 ;0=49,1=0
P 0.6448425 4.1975197 37 P 0 0 ;0=35,1=0
P 0.6448425 4.2546063 37 P 0 0 ;0=35,1=0
P 0.6548425 0.8479921 11 P 0 0 ;0=9,1=0
P 0.6548425 0.9641339 11 P 0 0 ;0=9,1=0
P 0.6548425 1.3729921 11 P 0 0 ;0=9,1=0
P 0.6548425 1.4891339 11 P 0 0 ;0=9,1=0
P 0.6548425 1.8979921 11 P 0 0 ;0=9,1=0
P 0.6548425 2.0141339 11 P 0 0 ;0=9,1=0
P 0.6548425 2.4229921 11 P 0 0 ;0=9,1=0
P 0.6548425 2.5391339 11 P 0 0 ;0=9,1=0
P 0.8406351 4.0388976 51 P 0 0 ;0=49,1=0
P 0.8406351 4.0932283 51 P 0 0 ;0=49,1=0
P 0.8465091 4.1975197 37 P 0 0 ;0=35,1=0
P 0.8465091 4.2546063 37 P 0 0 ;0=35,1=0
P 0.9005905 1.7470472 32 P 0 0 ;0=30,1=0
P 0.9015747 0.7185038 32 P 0 0 ;0=30,1=0
P 0.9045275 1.2244094 32 P 0 0 ;0=30,1=0
P 0.9084645 2.2844487 32 P 0 0 ;0=30,1=0
P 0.9326378 0.906063 36 P 0 0 ;0=34,1=0
P 0.9326378 1.431063 36 P 0 0 ;0=34,1=0
P 0.9326378 1.956063 36 P 0 0 ;0=34,1=0
P 0.9326378 2.481063 36 P 0 0 ;0=34,1=0
P 0.9596456 1.7470472 32 P 0 0 ;0=30,1=0
P 0.9606298 0.7185038 32 P 0 0 ;0=30,1=0
P 0.9635826 1.2244094 32 P 0 0 ;0=30,1=0
P 0.9675196 2.2844487 32 P 0 0 ;0=30,1=0
P 1.0423017 4.0388976 51 P 0 0 ;0=49,1=0
P 1.0423017 4.0932283 51 P 0 0 ;0=49,1=0
P 1.0481757 4.1975197 37 P 0 0 ;0=35,1=0
P 1.0481757 4.2546063 37 P 0 0 ;0=35,1=0
P 1.1570472 0.906063 36 P 0 0 ;0=34,1=0
P 1.1570472 1.431063 36 P 0 0 ;0=34,1=0
P 1.1570472 1.956063 36 P 0 0 ;0=34,1=0
P 1.1570472 2.481063 36 P 0 0 ;0=34,1=0
P 1.2439683 4.0388976 51 P 0 0 ;0=49,1=0
P 1.2439683 4.0932283 51 P 0 0 ;0=49,1=0
P 1.2498423 4.1975197 37 P 0 0 ;0=35,1=0
P 1.2498423 4.2546063 37 P 0 0 ;0=35,1=0
P 1.3464567 3.9783465 54 P 0 0 ;0=52,1=0
P 1.3464567 4.0374016 54 P 0 0 ;0=52,1=0
P 1.3464567 4.0826772 54 P 0 0 ;0=52,1=0
P 1.3464567 4.1417323 54 P 0 0 ;0=52,1=0
P 1.6171125 1.319673 43 P 0 0 ;0=41,1=0
P 1.6171125 1.339363 43 P 0 0 ;0=41,1=0
P 1.6171125 1.359043 43 P 0 0 ;0=41,1=0
P 1.6171125 1.378733 43 P 0 0 ;0=41,1=0
P 1.6171125 1.398413 43 P 0 0 ;0=41,1=0
P 1.6171125 1.418103 43 P 0 0 ;0=41,1=0
P 1.6171125 1.437783 43 P 0 0 ;0=41,1=0
P 1.6171125 1.457473 43 P 0 0 ;0=41,1=0
P 1.6171125 1.477153 43 P 0 0 ;0=41,1=0
P 1.6171125 1.496843 43 P 0 0 ;0=41,1=0
P 1.6171125 1.516523 43 P 0 0 ;0=41,1=0
P 1.6171125 1.536213 43 P 0 0 ;0=41,1=0
P 1.6171125 1.555893 43 P 0 0 ;0=41,1=0
P 1.6171125 1.575583 43 P 0 0 ;0=41,1=0
P 1.6171125 1.595263 43 P 0 0 ;0=41,1=0
P 1.6171125 1.614953 43 P 0 0 ;0=41,1=0
P 1.6171125 1.634633 43 P 0 0 ;0=41,1=0
P 1.6171125 1.654323 43 P 0 0 ;0=41,1=0
P 1.6171125 1.674003 43 P 0 0 ;0=41,1=0
P 1.6171125 1.693693 43 P 0 0 ;0=41,1=0
P 1.6171125 1.713373 43 P 0 0 ;0=41,1=0
P 1.6171125 1.733063 43 P 0 0 ;0=41,1=0
P 1.6171125 1.752743 43 P 0 0 ;0=41,1=0
P 1.6171125 1.772433 43 P 0 0 ;0=41,1=0
P 1.6171125 1.792113 43 P 0 0 ;0=41,1=0
P 1.6171125 1.811803 43 P 0 0 ;0=41,1=0
P 1.6171125 1.831483 43 P 0 0 ;0=41,1=0
P 1.6171125 1.851173 43 P 0 0 ;0=41,1=0
P 1.6171125 1.870853 43 P 0 0 ;0=41,1=0
P 1.6171125 1.890543 43 P 0 0 ;0=41,1=0
P 1.6171125 1.910223 43 P 0 0 ;0=41,1=0
P 1.6171125 1.929913 43 P 0 0 ;0=41,1=0
P 1.6171125 1.949593 43 P 0 0 ;0=41,1=0
P 1.6171125 1.969283 43 P 0 0 ;0=41,1=0
P 1.6171125 1.988963 43 P 0 0 ;0=41,1=0
P 1.6171125 2.008653 43 P 0 0 ;0=41,1=0
P 1.6171125 2.028333 43 P 0 0 ;0=41,1=0
P 1.6171125 2.048023 43 P 0 0 ;0=41,1=0
P 1.6171125 2.067703 43 P 0 0 ;0=41,1=0
P 1.6171125 2.087393 43 P 0 0 ;0=41,1=0
P 1.631559 4.024563 13 P 0 0 ;0=11,1=0
P 1.631559 4.049563 13 P 0 0 ;0=11,1=0
P 1.631559 4.074563 13 P 0 0 ;0=11,1=0
P 1.631559 4.099563 13 P 0 0 ;0=11,1=0
P 1.631559 4.124563 13 P 0 0 ;0=11,1=0
P 1.631559 4.149563 13 P 0 0 ;0=11,1=0
P 1.631559 4.174563 13 P 0 0 ;0=11,1=0
P 1.631559 4.199563 13 P 0 0 ;0=11,1=0
P 1.6643465 4.273063 49 P 0 0 ;0=47,1=0
P 1.6968325 1.275383 44 P 0 0 ;0=42,1=0
P 1.6968325 2.131683 44 P 0 0 ;0=42,1=0
P 1.7273386 4.273063 49 P 0 0 ;0=47,1=0
P 1.7765525 1.319673 43 P 0 0 ;0=41,1=0
P 1.7765525 1.339363 43 P 0 0 ;0=41,1=0
P 1.7765525 1.359043 43 P 0 0 ;0=41,1=0
P 1.7765525 1.378733 43 P 0 0 ;0=41,1=0
P 1.7765525 1.398413 43 P 0 0 ;0=41,1=0
P 1.7765525 1.418103 43 P 0 0 ;0=41,1=0
P 1.7765525 1.437783 43 P 0 0 ;0=41,1=0
P 1.7765525 1.457473 43 P 0 0 ;0=41,1=0
P 1.7765525 1.477153 43 P 0 0 ;0=41,1=0
P 1.7765525 1.496843 43 P 0 0 ;0=41,1=0
P 1.7765525 1.516523 43 P 0 0 ;0=41,1=0
P 1.7765525 1.536213 43 P 0 0 ;0=41,1=0
P 1.7765525 1.555893 43 P 0 0 ;0=41,1=0
P 1.7765525 1.575583 43 P 0 0 ;0=41,1=0
P 1.7765525 1.595263 43 P 0 0 ;0=41,1=0
P 1.7765525 1.614953 43 P 0 0 ;0=41,1=0
P 1.7765525 1.634633 43 P 0 0 ;0=41,1=0
P 1.7765525 1.654323 43 P 0 0 ;0=41,1=0
P 1.7765525 1.674003 43 P 0 0 ;0=41,1=0
P 1.7765525 1.693693 43 P 0 0 ;0=41,1=0
P 1.7765525 1.713373 43 P 0 0 ;0=41,1=0
P 1.7765525 1.733063 43 P 0 0 ;0=41,1=0
P 1.7765525 1.752743 43 P 0 0 ;0=41,1=0
P 1.7765525 1.772433 43 P 0 0 ;0=41,1=0
P 1.7765525 1.792113 43 P 0 0 ;0=41,1=0
P 1.7765525 1.811803 43 P 0 0 ;0=41,1=0
P 1.7765525 1.831483 43 P 0 0 ;0=41,1=0
P 1.7765525 1.851173 43 P 0 0 ;0=41,1=0
P 1.7765525 1.870853 43 P 0 0 ;0=41,1=0
P 1.7765525 1.890543 43 P 0 0 ;0=41,1=0
P 1.7765525 1.910223 43 P 0 0 ;0=41,1=0
P 1.7765525 1.929913 43 P 0 0 ;0=41,1=0
P 1.7765525 1.949593 43 P 0 0 ;0=41,1=0
P 1.7765525 1.969283 43 P 0 0 ;0=41,1=0
P 1.7765525 1.988963 43 P 0 0 ;0=41,1=0
P 1.7765525 2.008653 43 P 0 0 ;0=41,1=0
P 1.7765525 2.028333 43 P 0 0 ;0=41,1=0
P 1.7765525 2.048023 43 P 0 0 ;0=41,1=0
P 1.7765525 2.067703 43 P 0 0 ;0=41,1=0
P 1.7765525 2.087393 43 P 0 0 ;0=41,1=0
P 1.7972451 0.1377953 26 P 0 0 ;0=24,1=0
P 1.8024094 4.276063 47 P 0 0 ;0=45,1=0
P 1.8366151 0.1377953 26 P 0 0 ;0=24,1=0
P 1.8461259 4.024563 13 P 0 0 ;0=11,1=0
P 1.8461259 4.049563 13 P 0 0 ;0=11,1=0
P 1.8461259 4.074563 13 P 0 0 ;0=11,1=0
P 1.8461259 4.099563 13 P 0 0 ;0=11,1=0
P 1.8461259 4.124563 13 P 0 0 ;0=11,1=0
P 1.8461259 4.149563 13 P 0 0 ;0=11,1=0
P 1.8461259 4.174563 13 P 0 0 ;0=11,1=0
P 1.8461259 4.199563 13 P 0 0 ;0=11,1=0
P 1.8732756 4.276063 47 P 0 0 ;0=45,1=0
P 1.8759851 0.1377953 26 P 0 0 ;0=24,1=0
P 1.9153551 0.1377953 26 P 0 0 ;0=24,1=0
P 1.9338425 4.0748977 51 P 0 0 ;0=49,1=0
P 1.9338425 4.1292284 51 P 0 0 ;0=49,1=0
P 1.9547251 0.1377953 26 P 0 0 ;0=24,1=0
P 1.9940951 0.1377953 26 P 0 0 ;0=24,1=0
P 2.0334651 0.1377953 26 P 0 0 ;0=24,1=0
P 2.0728351 0.1377953 26 P 0 0 ;0=24,1=0
P 2.1122051 0.1377953 26 P 0 0 ;0=24,1=0
P 2.1398425 3.6641339 40 P 0 0 ;0=38,1=0
P 2.1398425 3.6979922 40 P 0 0 ;0=38,1=0
P 2.1468425 2.6248976 51 P 0 0 ;0=49,1=0
P 2.1468425 2.6792283 51 P 0 0 ;0=49,1=0
P 2.1515748 4.0157481 54 P 0 0 ;0=52,1=0
P 2.1515748 4.0748032 54 P 0 0 ;0=52,1=0
P 2.1515751 0.1377953 26 P 0 0 ;0=24,1=0
P 2.1686825 2.438533 46 P 0 0 ;0=44,1=0
P 2.1686925 0.958593 46 P 0 0 ;0=44,1=0
P 2.1909451 0.1377953 26 P 0 0 ;0=24,1=0
P 2.1996929 4.275063 7 P 0 0 ;0=5,1=0
P 2.2098425 3.6456299 38 P 0 0 ;0=36,1=0
P 2.2098425 3.7164961 38 P 0 0 ;0=36,1=0
P 2.2125984 4.0157481 54 P 0 0 ;0=52,1=0
P 2.2125984 4.0748032 54 P 0 0 ;0=52,1=0
P 2.2129725 2.358813 45 P 0 0 ;0=43,1=0
P 2.2129725 2.518253 45 P 0 0 ;0=43,1=0
P 2.2129825 0.878873 45 P 0 0 ;0=43,1=0
P 2.2129825 1.038313 45 P 0 0 ;0=43,1=0
P 2.2326625 2.358813 45 P 0 0 ;0=43,1=0
P 2.2326625 2.518253 45 P 0 0 ;0=43,1=0
P 2.2326725 0.878873 45 P 0 0 ;0=43,1=0
P 2.2326725 1.038313 45 P 0 0 ;0=43,1=0
P 2.2341417 4.1736851 5 P 0 0 ;0=3,1=0
P 2.2523425 2.358813 45 P 0 0 ;0=43,1=0
P 2.2523425 2.518253 45 P 0 0 ;0=43,1=0
P 2.2523525 0.878873 45 P 0 0 ;0=43,1=0
P 2.2523525 1.038313 45 P 0 0 ;0=43,1=0
P 2.2715433 4.275063 3 P 0 0 ;0=1,1=0
P 2.2720325 2.358813 45 P 0 0 ;0=43,1=0
P 2.2720325 2.518253 45 P 0 0 ;0=43,1=0
P 2.2720425 0.878873 45 P 0 0 ;0=43,1=0
P 2.2720425 1.038313 45 P 0 0 ;0=43,1=0
P 2.2813858 4.1703386 6 P 0 0 ;0=4,1=0
P 2.2917125 2.358813 45 P 0 0 ;0=43,1=0
P 2.2917125 2.518253 45 P 0 0 ;0=43,1=0
P 2.2917225 0.878873 45 P 0 0 ;0=43,1=0
P 2.2917225 1.038313 45 P 0 0 ;0=43,1=0
P 2.3069763 4.1703386 6 P 0 0 ;0=4,1=0
P 2.3090551 0.1377953 26 P 0 0 ;0=24,1=0
P 2.3114025 2.358813 45 P 0 0 ;0=43,1=0
P 2.3114025 2.518253 45 P 0 0 ;0=43,1=0
P 2.3114125 0.878873 45 P 0 0 ;0=43,1=0
P 2.3114125 1.038313 45 P 0 0 ;0=43,1=0
P 2.3310825 2.358813 45 P 0 0 ;0=43,1=0
P 2.3310825 2.518253 45 P 0 0 ;0=43,1=0
P 2.3310925 0.878873 45 P 0 0 ;0=43,1=0
P 2.3310925 1.038313 45 P 0 0 ;0=43,1=0
P 2.3325669 4.1703386 6 P 0 0 ;0=4,1=0
P 2.3348425 3.4045276 53 P 0 0 ;0=51,1=0
P 2.3348425 3.4832677 53 P 0 0 ;0=51,1=0
P 2.3348425 3.5620079 53 P 0 0 ;0=51,1=0
P 2.3348425 3.640748 53 P 0 0 ;0=51,1=0
P 2.3484251 0.1377953 26 P 0 0 ;0=24,1=0
P 2.3507725 2.358813 45 P 0 0 ;0=43,1=0
P 2.3507725 2.518253 45 P 0 0 ;0=43,1=0
P 2.3507825 0.878873 45 P 0 0 ;0=43,1=0
P 2.3507825 1.038313 45 P 0 0 ;0=43,1=0
P 2.3581575 4.1703386 6 P 0 0 ;0=4,1=0
P 2.3704525 2.358813 45 P 0 0 ;0=43,1=0
P 2.3704525 2.518253 45 P 0 0 ;0=43,1=0
P 2.3704625 0.878873 45 P 0 0 ;0=43,1=0
P 2.3704625 1.038313 45 P 0 0 ;0=43,1=0
P 2.3778425 4.275063 4 P 0 0 ;0=2,1=0
P 2.383748 4.1703386 6 P 0 0 ;0=4,1=0
P 2.3877951 0.1377953 26 P 0 0 ;0=24,1=0
P 2.3877954 2.8996063 54 P 0 0 ;0=52,1=0
P 2.3877954 2.9586614 54 P 0 0 ;0=52,1=0
P 2.3901425 2.358813 45 P 0 0 ;0=43,1=0
P 2.3901425 2.518253 45 P 0 0 ;0=43,1=0
P 2.3901525 0.878873 45 P 0 0 ;0=43,1=0
P 2.3901525 1.038313 45 P 0 0 ;0=43,1=0
P 2.4098225 2.358813 45 P 0 0 ;0=43,1=0
P 2.4098225 2.518253 45 P 0 0 ;0=43,1=0
P 2.4098325 0.878873 45 P 0 0 ;0=43,1=0
P 2.4098325 1.038313 45 P 0 0 ;0=43,1=0
P 2.4271651 0.1377953 26 P 0 0 ;0=24,1=0
P 2.4295125 2.358813 45 P 0 0 ;0=43,1=0
P 2.4295125 2.518253 45 P 0 0 ;0=43,1=0
P 2.4295225 0.878873 45 P 0 0 ;0=43,1=0
P 2.4295225 1.038313 45 P 0 0 ;0=43,1=0
P 2.4309921 4.1736851 5 P 0 0 ;0=3,1=0
P 2.4491925 2.358813 45 P 0 0 ;0=43,1=0
P 2.4491925 2.518253 45 P 0 0 ;0=43,1=0
P 2.4492025 0.878873 45 P 0 0 ;0=43,1=0
P 2.4492025 1.038313 45 P 0 0 ;0=43,1=0
P 2.4654409 4.275063 7 P 0 0 ;0=5,1=0
P 2.4665351 0.1377953 26 P 0 0 ;0=24,1=0
P 2.4688825 2.358813 45 P 0 0 ;0=43,1=0
P 2.4688825 2.518253 45 P 0 0 ;0=43,1=0
P 2.4688925 0.878873 45 P 0 0 ;0=43,1=0
P 2.4688925 1.038313 45 P 0 0 ;0=43,1=0
P 2.4885625 2.358813 45 P 0 0 ;0=43,1=0
P 2.4885625 2.518253 45 P 0 0 ;0=43,1=0
P 2.4885725 0.878873 45 P 0 0 ;0=43,1=0
P 2.4885725 1.038313 45 P 0 0 ;0=43,1=0
P 2.503937 0.5738189 52 P 0 0 ;0=50,1=0
P 2.503937 0.6072835 52 P 0 0 ;0=50,1=0
P 2.5059051 0.1377953 26 P 0 0 ;0=24,1=0
P 2.5082525 2.358813 45 P 0 0 ;0=43,1=0
P 2.5082525 2.518253 45 P 0 0 ;0=43,1=0
P 2.5082625 0.878873 45 P 0 0 ;0=43,1=0
P 2.5082625 1.038313 45 P 0 0 ;0=43,1=0
P 2.5098425 3.4045276 53 P 0 0 ;0=51,1=0
P 2.5098425 3.4832677 53 P 0 0 ;0=51,1=0
P 2.5098425 3.5620079 53 P 0 0 ;0=51,1=0
P 2.5098425 3.640748 53 P 0 0 ;0=51,1=0
P 2.5279325 2.358813 45 P 0 0 ;0=43,1=0
P 2.5279325 2.518253 45 P 0 0 ;0=43,1=0
P 2.5279425 0.878873 45 P 0 0 ;0=43,1=0
P 2.5279425 1.038313 45 P 0 0 ;0=43,1=0
P 2.5452751 0.1377953 26 P 0 0 ;0=24,1=0
P 2.5476225 2.358813 45 P 0 0 ;0=43,1=0
P 2.5476225 2.518253 45 P 0 0 ;0=43,1=0
P 2.5476325 0.878873 45 P 0 0 ;0=43,1=0
P 2.5476325 1.038313 45 P 0 0 ;0=43,1=0
P 2.5673025 2.358813 45 P 0 0 ;0=43,1=0
P 2.5673025 2.518253 45 P 0 0 ;0=43,1=0
P 2.5673125 0.878873 45 P 0 0 ;0=43,1=0
P 2.5673125 1.038313 45 P 0 0 ;0=43,1=0
P 2.5846451 0.1377953 26 P 0 0 ;0=24,1=0
P 2.5869925 2.358813 45 P 0 0 ;0=43,1=0
P 2.5869925 2.518253 45 P 0 0 ;0=43,1=0
P 2.5870025 0.878873 45 P 0 0 ;0=43,1=0
P 2.5870025 1.038313 45 P 0 0 ;0=43,1=0
P 2.6066725 2.358813 45 P 0 0 ;0=43,1=0
P 2.6066725 2.518253 45 P 0 0 ;0=43,1=0
P 2.6066825 0.878873 45 P 0 0 ;0=43,1=0
P 2.6066825 1.038313 45 P 0 0 ;0=43,1=0
P 2.6240151 0.1377953 26 P 0 0 ;0=24,1=0
P 2.6263625 2.358813 45 P 0 0 ;0=43,1=0
P 2.6263625 2.518253 45 P 0 0 ;0=43,1=0
P 2.6263725 0.878873 45 P 0 0 ;0=43,1=0
P 2.6263725 1.038313 45 P 0 0 ;0=43,1=0
P 2.6398425 3.5356299 38 P 0 0 ;0=36,1=0
P 2.6398425 3.6064961 38 P 0 0 ;0=36,1=0
P 2.6460425 2.358813 45 P 0 0 ;0=43,1=0
P 2.6460425 2.518253 45 P 0 0 ;0=43,1=0
P 2.6460525 0.878873 45 P 0 0 ;0=43,1=0
P 2.6460525 1.038313 45 P 0 0 ;0=43,1=0
P 2.6633851 0.1377953 26 P 0 0 ;0=24,1=0
P 2.6657325 2.358813 45 P 0 0 ;0=43,1=0
P 2.6657325 2.518253 45 P 0 0 ;0=43,1=0
P 2.6657425 0.878873 45 P 0 0 ;0=43,1=0
P 2.6657425 1.038313 45 P 0 0 ;0=43,1=0
P 2.6854125 2.358813 45 P 0 0 ;0=43,1=0
P 2.6854125 2.518253 45 P 0 0 ;0=43,1=0
P 2.6854225 0.878873 45 P 0 0 ;0=43,1=0
P 2.6854225 1.038313 45 P 0 0 ;0=43,1=0
P 2.694252 3.7503543 12 P 0 0 ;0=10,1=0
P 2.7027551 0.1377953 26 P 0 0 ;0=24,1=0
P 2.7051025 2.358813 45 P 0 0 ;0=43,1=0
P 2.7051025 2.518253 45 P 0 0 ;0=43,1=0
P 2.7051125 0.878873 45 P 0 0 ;0=43,1=0
P 2.7051125 1.038313 45 P 0 0 ;0=43,1=0
P 2.7198425 3.6617716 12 P 0 0 ;0=10,1=0
P 2.7247825 2.358813 45 P 0 0 ;0=43,1=0
P 2.7247825 2.518253 45 P 0 0 ;0=43,1=0
P 2.7247925 0.878873 45 P 0 0 ;0=43,1=0
P 2.7247925 1.038313 45 P 0 0 ;0=43,1=0
P 2.7248425 3.5591338 40 P 0 0 ;0=38,1=0
P 2.7248425 3.5929921 40 P 0 0 ;0=38,1=0
P 2.7421251 0.1377953 26 P 0 0 ;0=24,1=0
P 2.7444725 2.358813 45 P 0 0 ;0=43,1=0
P 2.7444725 2.518253 45 P 0 0 ;0=43,1=0
P 2.7444825 0.878873 45 P 0 0 ;0=43,1=0
P 2.7444825 1.038313 45 P 0 0 ;0=43,1=0
P 2.7454331 3.7503543 12 P 0 0 ;0=10,1=0
P 2.7568898 2.9372047 2 P 0 0 ;0=0,1=0
P 2.7568898 2.9872047 2 P 0 0 ;0=0,1=0
P 2.7568898 3.0372047 2 P 0 0 ;0=0,1=0
P 2.7568898 3.0872047 2 P 0 0 ;0=0,1=0
P 2.7568898 3.1372047 2 P 0 0 ;0=0,1=0
P 2.7568898 3.1872047 2 P 0 0 ;0=0,1=0
P 2.7568898 3.2372047 2 P 0 0 ;0=0,1=0
P 2.7568898 3.2872047 2 P 0 0 ;0=0,1=0
P 2.7641525 2.358813 45 P 0 0 ;0=43,1=0
P 2.7641525 2.518253 45 P 0 0 ;0=43,1=0
P 2.7641625 0.878873 45 P 0 0 ;0=43,1=0
P 2.7641625 1.038313 45 P 0 0 ;0=43,1=0
P 2.7814951 0.1377953 26 P 0 0 ;0=24,1=0
P 2.7838425 2.358813 45 P 0 0 ;0=43,1=0
P 2.7838425 2.518253 45 P 0 0 ;0=43,1=0
P 2.7838525 0.878873 45 P 0 0 ;0=43,1=0
P 2.7838525 1.038313 45 P 0 0 ;0=43,1=0
P 2.8035225 2.358813 45 P 0 0 ;0=43,1=0
P 2.8035225 2.518253 45 P 0 0 ;0=43,1=0
P 2.8035325 0.878873 45 P 0 0 ;0=43,1=0
P 2.8035325 1.038313 45 P 0 0 ;0=43,1=0
P 2.809252 3.7503543 12 P 0 0 ;0=10,1=0
P 2.8208651 0.1377953 26 P 0 0 ;0=24,1=0
P 2.8232125 2.358813 45 P 0 0 ;0=43,1=0
P 2.8232125 2.518253 45 P 0 0 ;0=43,1=0
P 2.8232225 0.878873 45 P 0 0 ;0=43,1=0
P 2.8232225 1.038313 45 P 0 0 ;0=43,1=0
P 2.8348425 3.6617716 12 P 0 0 ;0=10,1=0
P 2.8428925 2.358813 45 P 0 0 ;0=43,1=0
P 2.8428925 2.518253 45 P 0 0 ;0=43,1=0
P 2.8429025 0.878873 45 P 0 0 ;0=43,1=0
P 2.8429025 1.038313 45 P 0 0 ;0=43,1=0
P 2.8602351 0.1377953 26 P 0 0 ;0=24,1=0
P 2.8604331 3.7503543 12 P 0 0 ;0=10,1=0
P 2.8625825 2.358813 45 P 0 0 ;0=43,1=0
P 2.8625825 2.518253 45 P 0 0 ;0=43,1=0
P 2.8625925 0.878873 45 P 0 0 ;0=43,1=0
P 2.8625925 1.038313 45 P 0 0 ;0=43,1=0
P 2.8822625 2.358813 45 P 0 0 ;0=43,1=0
P 2.8822625 2.518253 45 P 0 0 ;0=43,1=0
P 2.8822725 0.878873 45 P 0 0 ;0=43,1=0
P 2.8822725 1.038313 45 P 0 0 ;0=43,1=0
P 2.8996051 0.1377953 26 P 0 0 ;0=24,1=0
P 2.9019525 2.358813 45 P 0 0 ;0=43,1=0
P 2.9019525 2.518253 45 P 0 0 ;0=43,1=0
P 2.9019625 0.878873 45 P 0 0 ;0=43,1=0
P 2.9019625 1.038313 45 P 0 0 ;0=43,1=0
P 2.9216325 2.358813 45 P 0 0 ;0=43,1=0
P 2.9216325 2.518253 45 P 0 0 ;0=43,1=0
P 2.9216425 0.878873 45 P 0 0 ;0=43,1=0
P 2.9216425 1.038313 45 P 0 0 ;0=43,1=0
P 2.9389751 0.1377953 26 P 0 0 ;0=24,1=0
P 2.9413225 2.358813 45 P 0 0 ;0=43,1=0
P 2.9413225 2.518253 45 P 0 0 ;0=43,1=0
P 2.9413325 0.878873 45 P 0 0 ;0=43,1=0
P 2.9413325 1.038313 45 P 0 0 ;0=43,1=0
P 2.9448425 3.6666929 23 P 0 0 ;0=21,1=0
P 2.9448425 3.7454331 23 P 0 0 ;0=21,1=0
P 2.9448425 3.951063 22 P 0 0 ;0=20,1=0
P 2.9448425 4.2211417 22 P 0 0 ;0=20,1=0
P 2.9610025 2.358813 45 P 0 0 ;0=43,1=0
P 2.9610025 2.518253 45 P 0 0 ;0=43,1=0
P 2.9610125 0.878873 45 P 0 0 ;0=43,1=0
P 2.9610125 1.038313 45 P 0 0 ;0=43,1=0
P 2.9783451 0.1377953 26 P 0 0 ;0=24,1=0
P 2.9806925 2.358813 45 P 0 0 ;0=43,1=0
P 2.9806925 2.518253 45 P 0 0 ;0=43,1=0
P 2.9807025 0.878873 45 P 0 0 ;0=43,1=0
P 2.9807025 1.038313 45 P 0 0 ;0=43,1=0
P 3.0177151 0.1377953 26 P 0 0 ;0=24,1=0
P 3.0249825 2.438533 46 P 0 0 ;0=44,1=0
P 3.0249925 0.958593 46 P 0 0 ;0=44,1=0
P 3.0448425 3.6666929 23 P 0 0 ;0=21,1=0
P 3.0448425 3.7454331 23 P 0 0 ;0=21,1=0
P 3.0448425 3.951063 22 P 0 0 ;0=20,1=0
P 3.0448425 4.2211417 22 P 0 0 ;0=20,1=0
P 3.0551181 0.5738189 52 P 0 0 ;0=50,1=0
P 3.0551181 0.6072835 52 P 0 0 ;0=50,1=0
P 3.0570851 0.1572953 27 P 0 0 ;0=25,1=0
P 3.0964551 0.1377953 26 P 0 0 ;0=24,1=0
P 3.1112205 2.9372047 2 P 0 0 ;0=0,1=0
P 3.1112205 2.9872047 2 P 0 0 ;0=0,1=0
P 3.1112205 3.0372047 2 P 0 0 ;0=0,1=0
P 3.1112205 3.0872047 2 P 0 0 ;0=0,1=0
P 3.1112205 3.1372047 2 P 0 0 ;0=0,1=0
P 3.1112205 3.1872047 2 P 0 0 ;0=0,1=0
P 3.1112205 3.2372047 2 P 0 0 ;0=0,1=0
P 3.1112205 3.2872047 2 P 0 0 ;0=0,1=0
P 3.1448425 3.6666929 23 P 0 0 ;0=21,1=0
P 3.1448425 3.7454331 23 P 0 0 ;0=21,1=0
P 3.1448425 3.951063 22 P 0 0 ;0=20,1=0
P 3.1448425 4.2211417 22 P 0 0 ;0=20,1=0
P 3.2091732 2.7952756 41 P 0 0 ;0=39,1=0
P 3.2091732 2.8149606 41 P 0 0 ;0=39,1=0
P 3.2091732 2.8346456 41 P 0 0 ;0=39,1=0
P 3.219252 3.7503543 12 P 0 0 ;0=10,1=0
P 3.2293307 2.7849212 42 P 0 0 ;0=40,1=0
P 3.2293307 2.845 42 P 0 0 ;0=40,1=0
P 3.2448425 3.6617716 12 P 0 0 ;0=10,1=0
P 3.2448425 3.951063 22 P 0 0 ;0=20,1=0
P 3.2448425 4.2211417 22 P 0 0 ;0=20,1=0
P 3.2490157 2.7849212 42 P 0 0 ;0=40,1=0
P 3.2490157 2.845 42 P 0 0 ;0=40,1=0
P 3.2691732 2.7952756 41 P 0 0 ;0=39,1=0
P 3.2691732 2.8149606 41 P 0 0 ;0=39,1=0
P 3.2691732 2.8346456 41 P 0 0 ;0=39,1=0
P 3.2704331 3.7503543 12 P 0 0 ;0=10,1=0
P 3.3331103 3.2062205 17 P 0 0 ;0=15,1=0
P 3.3331103 3.3951969 17 P 0 0 ;0=15,1=0
P 3.3448425 3.951063 22 P 0 0 ;0=20,1=0
P 3.3448425 4.2211417 22 P 0 0 ;0=20,1=0
P 3.3498425 3.6666929 23 P 0 0 ;0=21,1=0
P 3.3498425 3.7454331 23 P 0 0 ;0=21,1=0
P 3.3921654 3.2062205 17 P 0 0 ;0=15,1=0
P 3.3921654 3.3951969 17 P 0 0 ;0=15,1=0
P 3.4385827 2.8923386 19 P 0 0 ;0=17,1=0
P 3.4385827 3.0517874 19 P 0 0 ;0=17,1=0
P 3.444252 3.7503543 12 P 0 0 ;0=10,1=0
P 3.4444882 2.948441 21 P 0 0 ;0=19,1=0
P 3.4444882 2.995685 21 P 0 0 ;0=19,1=0
P 3.4512205 3.2062205 17 P 0 0 ;0=15,1=0
P 3.4512205 3.3951969 17 P 0 0 ;0=15,1=0
P 3.4698425 3.6617716 12 P 0 0 ;0=10,1=0
P 3.4776771 2.797063 24 P 0 0 ;0=22,1=0
P 3.4848425 2.8923386 20 P 0 0 ;0=18,1=0
P 3.4848425 3.0517874 20 P 0 0 ;0=18,1=0
P 3.4920225 1.319633 43 P 0 0 ;0=41,1=0
P 3.4920225 1.339323 43 P 0 0 ;0=41,1=0
P 3.4920225 1.359003 43 P 0 0 ;0=41,1=0
P 3.4920225 1.378693 43 P 0 0 ;0=41,1=0
P 3.4920225 1.398373 43 P 0 0 ;0=41,1=0
P 3.4920225 1.418063 43 P 0 0 ;0=41,1=0
P 3.4920225 1.437743 43 P 0 0 ;0=41,1=0
P 3.4920225 1.457433 43 P 0 0 ;0=41,1=0
P 3.4920225 1.477113 43 P 0 0 ;0=41,1=0
P 3.4920225 1.496803 43 P 0 0 ;0=41,1=0
P 3.4920225 1.516483 43 P 0 0 ;0=41,1=0
P 3.4920225 1.536173 43 P 0 0 ;0=41,1=0
P 3.4920225 1.555853 43 P 0 0 ;0=41,1=0
P 3.4920225 1.575543 43 P 0 0 ;0=41,1=0
P 3.4920225 1.595223 43 P 0 0 ;0=41,1=0
P 3.4920225 1.614913 43 P 0 0 ;0=41,1=0
P 3.4920225 1.634593 43 P 0 0 ;0=41,1=0
P 3.4920225 1.654283 43 P 0 0 ;0=41,1=0
P 3.4920225 1.673963 43 P 0 0 ;0=41,1=0
P 3.4920225 1.693653 43 P 0 0 ;0=41,1=0
P 3.4920225 1.713333 43 P 0 0 ;0=41,1=0
P 3.4920225 1.733023 43 P 0 0 ;0=41,1=0
P 3.4920225 1.752703 43 P 0 0 ;0=41,1=0
P 3.4920225 1.772393 43 P 0 0 ;0=41,1=0
P 3.4920225 1.792073 43 P 0 0 ;0=41,1=0
P 3.4920225 1.811763 43 P 0 0 ;0=41,1=0
P 3.4920225 1.831443 43 P 0 0 ;0=41,1=0
P 3.4920225 1.851133 43 P 0 0 ;0=41,1=0
P 3.4920225 1.870813 43 P 0 0 ;0=41,1=0
P 3.4920225 1.890503 43 P 0 0 ;0=41,1=0
P 3.4920225 1.910183 43 P 0 0 ;0=41,1=0
P 3.4920225 1.929873 43 P 0 0 ;0=41,1=0
P 3.4920225 1.949553 43 P 0 0 ;0=41,1=0
P 3.4920225 1.969243 43 P 0 0 ;0=41,1=0
P 3.4920225 1.988923 43 P 0 0 ;0=41,1=0
P 3.4920225 2.008613 43 P 0 0 ;0=41,1=0
P 3.4920225 2.028293 43 P 0 0 ;0=41,1=0
P 3.4920225 2.047983 43 P 0 0 ;0=41,1=0
P 3.4920225 2.067663 43 P 0 0 ;0=41,1=0
P 3.4920225 2.087353 43 P 0 0 ;0=41,1=0
P 3.4954331 3.7503543 12 P 0 0 ;0=10,1=0
P 3.5102756 3.2062205 17 P 0 0 ;0=15,1=0
P 3.5102756 3.3951969 17 P 0 0 ;0=15,1=0
P 3.5251968 2.948441 21 P 0 0 ;0=19,1=0
P 3.5251968 2.995685 21 P 0 0 ;0=19,1=0
P 3.5311023 2.8923386 19 P 0 0 ;0=17,1=0
P 3.5311023 3.0517874 19 P 0 0 ;0=17,1=0
P 3.5320078 2.797063 24 P 0 0 ;0=22,1=0
P 3.5693307 3.2062205 17 P 0 0 ;0=15,1=0
P 3.5693307 3.3853543 18 P 0 0 ;0=16,1=0
P 3.5717425 1.275343 44 P 0 0 ;0=42,1=0
P 3.5717425 2.131643 44 P 0 0 ;0=42,1=0
P 3.5898425 3.7275197 37 P 0 0 ;0=35,1=0
P 3.5898425 3.7846063 37 P 0 0 ;0=35,1=0
P 3.5898425 3.8525197 37 P 0 0 ;0=35,1=0
P 3.5898425 3.9096063 37 P 0 0 ;0=35,1=0
P 3.6514625 1.319633 43 P 0 0 ;0=41,1=0
P 3.6514625 1.339323 43 P 0 0 ;0=41,1=0
P 3.6514625 1.359003 43 P 0 0 ;0=41,1=0
P 3.6514625 1.378693 43 P 0 0 ;0=41,1=0
P 3.6514625 1.398373 43 P 0 0 ;0=41,1=0
P 3.6514625 1.418063 43 P 0 0 ;0=41,1=0
P 3.6514625 1.437743 43 P 0 0 ;0=41,1=0
P 3.6514625 1.457433 43 P 0 0 ;0=41,1=0
P 3.6514625 1.477113 43 P 0 0 ;0=41,1=0
P 3.6514625 1.496803 43 P 0 0 ;0=41,1=0
P 3.6514625 1.516483 43 P 0 0 ;0=41,1=0
P 3.6514625 1.536173 43 P 0 0 ;0=41,1=0
P 3.6514625 1.555853 43 P 0 0 ;0=41,1=0
P 3.6514625 1.575543 43 P 0 0 ;0=41,1=0
P 3.6514625 1.595223 43 P 0 0 ;0=41,1=0
P 3.6514625 1.614913 43 P 0 0 ;0=41,1=0
P 3.6514625 1.634593 43 P 0 0 ;0=41,1=0
P 3.6514625 1.654283 43 P 0 0 ;0=41,1=0
P 3.6514625 1.673963 43 P 0 0 ;0=41,1=0
P 3.6514625 1.693653 43 P 0 0 ;0=41,1=0
P 3.6514625 1.713333 43 P 0 0 ;0=41,1=0
P 3.6514625 1.733023 43 P 0 0 ;0=41,1=0
P 3.6514625 1.752703 43 P 0 0 ;0=41,1=0
P 3.6514625 1.772393 43 P 0 0 ;0=41,1=0
P 3.6514625 1.792073 43 P 0 0 ;0=41,1=0
P 3.6514625 1.811763 43 P 0 0 ;0=41,1=0
P 3.6514625 1.831443 43 P 0 0 ;0=41,1=0
P 3.6514625 1.851133 43 P 0 0 ;0=41,1=0
P 3.6514625 1.870813 43 P 0 0 ;0=41,1=0
P 3.6514625 1.890503 43 P 0 0 ;0=41,1=0
P 3.6514625 1.910183 43 P 0 0 ;0=41,1=0
P 3.6514625 1.929873 43 P 0 0 ;0=41,1=0
P 3.6514625 1.949553 43 P 0 0 ;0=41,1=0
P 3.6514625 1.969243 43 P 0 0 ;0=41,1=0
P 3.6514625 1.988923 43 P 0 0 ;0=41,1=0
P 3.6514625 2.008613 43 P 0 0 ;0=41,1=0
P 3.6514625 2.028293 43 P 0 0 ;0=41,1=0
P 3.6514625 2.047983 43 P 0 0 ;0=41,1=0
P 3.6514625 2.067663 43 P 0 0 ;0=41,1=0
P 3.6514625 2.087353 43 P 0 0 ;0=41,1=0
P 3.6594094 0.726063 47 P 0 0 ;0=45,1=0
P 3.6681102 3.786063 25 P 0 0 ;0=23,1=0
P 3.6681102 3.861063 25 P 0 0 ;0=23,1=0
P 3.6829133 0.636063 48 P 0 0 ;0=46,1=0
P 3.6888425 3.266567 39 P 0 0 ;0=37,1=0
P 3.6888425 3.3295591 39 P 0 0 ;0=37,1=0
P 3.6938425 3.1176299 38 P 0 0 ;0=36,1=0
P 3.6938425 3.1884961 38 P 0 0 ;0=36,1=0
P 3.6962598 4.0276378 8 P 0 0 ;0=6,1=0
P 3.6962598 4.2441732 8 P 0 0 ;0=6,1=0
P 3.7015748 3.786063 25 P 0 0 ;0=23,1=0
P 3.7015748 3.861063 25 P 0 0 ;0=23,1=0
P 3.7167716 0.636063 48 P 0 0 ;0=46,1=0
P 3.7302756 0.726063 47 P 0 0 ;0=45,1=0
P 3.7698425 3.2011339 40 P 0 0 ;0=38,1=0
P 3.7698425 3.2349922 40 P 0 0 ;0=38,1=0
P 3.772559 3.683563 13 P 0 0 ;0=11,1=0
P 3.772559 3.708563 13 P 0 0 ;0=11,1=0
P 3.772559 3.733563 13 P 0 0 ;0=11,1=0
P 3.772559 3.758563 13 P 0 0 ;0=11,1=0
P 3.772559 3.783563 13 P 0 0 ;0=11,1=0
P 3.772559 3.808563 13 P 0 0 ;0=11,1=0
P 3.772559 3.833563 13 P 0 0 ;0=11,1=0
P 3.772559 3.858563 13 P 0 0 ;0=11,1=0
P 3.8084646 4.0237008 9 P 0 0 ;0=7,1=0
P 3.8399606 4.0237008 9 P 0 0 ;0=7,1=0
P 3.8714567 4.0237008 9 P 0 0 ;0=7,1=0
P 3.9029528 4.0237008 9 P 0 0 ;0=7,1=0
P 3.9114214 1.5996232 29 P 0 0 ;0=27,1=0
P 3.9114214 1.6196232 29 P 0 0 ;0=27,1=0
P 3.9114214 1.6396232 29 P 0 0 ;0=27,1=0
P 3.9114214 1.6596232 29 P 0 0 ;0=27,1=0
P 3.9114214 1.6796232 29 P 0 0 ;0=27,1=0
P 3.9114214 1.6996232 29 P 0 0 ;0=27,1=0
P 3.9114214 1.7196232 29 P 0 0 ;0=27,1=0
P 3.9114214 1.7396232 29 P 0 0 ;0=27,1=0
P 3.9114214 1.7596232 29 P 0 0 ;0=27,1=0
P 3.9114214 1.7796232 29 P 0 0 ;0=27,1=0
P 3.9344488 4.0237008 9 P 0 0 ;0=7,1=0
P 3.9598425 2.7806299 38 P 0 0 ;0=36,1=0
P 3.9598425 2.8514961 38 P 0 0 ;0=36,1=0
P 3.9871259 3.683563 13 P 0 0 ;0=11,1=0
P 3.9871259 3.708563 13 P 0 0 ;0=11,1=0
P 3.9871259 3.733563 13 P 0 0 ;0=11,1=0
P 3.9871259 3.758563 13 P 0 0 ;0=11,1=0
P 3.9871259 3.783563 13 P 0 0 ;0=11,1=0
P 3.9871259 3.808563 13 P 0 0 ;0=11,1=0
P 3.9871259 3.833563 13 P 0 0 ;0=11,1=0
P 3.9871259 3.858563 13 P 0 0 ;0=11,1=0
P 4.0398425 3.029567 39 P 0 0 ;0=37,1=0
P 4.0398425 3.0925591 39 P 0 0 ;0=37,1=0
P 4.0466536 4.0276378 8 P 0 0 ;0=6,1=0
P 4.0466536 4.2441732 8 P 0 0 ;0=6,1=0
P 4.0648425 2.7806299 38 P 0 0 ;0=36,1=0
P 4.0648425 2.8514961 38 P 0 0 ;0=36,1=0
P 4.0689017 1.5996232 29 P 0 0 ;0=27,1=0
P 4.0689017 1.6196232 29 P 0 0 ;0=27,1=0
P 4.0689017 1.6396232 29 P 0 0 ;0=27,1=0
P 4.0689017 1.6596232 29 P 0 0 ;0=27,1=0
P 4.0689017 1.6796232 29 P 0 0 ;0=27,1=0
P 4.0689017 1.6996232 29 P 0 0 ;0=27,1=0
P 4.0689017 1.7196232 29 P 0 0 ;0=27,1=0
P 4.0689017 1.7396232 29 P 0 0 ;0=27,1=0
P 4.0689017 1.7596232 29 P 0 0 ;0=27,1=0
P 4.0689017 1.7796232 29 P 0 0 ;0=27,1=0
P 4.1048425 3.7706299 38 P 0 0 ;0=36,1=0
P 4.1048425 3.8414961 38 P 0 0 ;0=36,1=0
P 4.1098425 3.0441338 40 P 0 0 ;0=38,1=0
P 4.1098425 3.0779921 40 P 0 0 ;0=38,1=0
P 4.1126772 3.701063 24 P 0 0 ;0=22,1=0
P 4.1498425 2.7898819 33 P 0 0 ;0=31,1=0
P 4.1498425 2.8422441 33 P 0 0 ;0=31,1=0
P 4.1505905 3.6033465 24 P 0 0 ;0=22,1=0
P 4.1648425 3.0441338 40 P 0 0 ;0=38,1=0
P 4.1648425 3.0779921 40 P 0 0 ;0=38,1=0
P 4.1670079 3.701063 24 P 0 0 ;0=22,1=0
P 4.1948425 3.774567 39 P 0 0 ;0=37,1=0
P 4.1948425 3.8375591 39 P 0 0 ;0=37,1=0
P 4.2049212 3.6033465 24 P 0 0 ;0=22,1=0
P 4.2094094 3.246063 47 P 0 0 ;0=45,1=0
P 4.2198425 3.0441338 40 P 0 0 ;0=38,1=0
P 4.2198425 3.0779921 40 P 0 0 ;0=38,1=0
P 4.2348425 2.7806299 38 P 0 0 ;0=36,1=0
P 4.2348425 2.8514961 38 P 0 0 ;0=36,1=0
P 4.2748425 3.0441338 40 P 0 0 ;0=38,1=0
P 4.2748425 3.0779921 40 P 0 0 ;0=38,1=0
P 4.2755905 3.6033465 50 P 0 0 ;0=48,1=0
P 4.2802756 3.246063 47 P 0 0 ;0=45,1=0
P 4.3326771 3.6033465 50 P 0 0 ;0=48,1=0
P 4.3348425 3.0441338 40 P 0 0 ;0=38,1=0
P 4.3348425 3.0779921 40 P 0 0 ;0=38,1=0
P 4.3398425 2.7806299 38 P 0 0 ;0=36,1=0
P 4.3398425 2.8514961 38 P 0 0 ;0=36,1=0
P 4.3948425 3.0441338 40 P 0 0 ;0=38,1=0
P 4.3948425 3.0779921 40 P 0 0 ;0=38,1=0
P 4.4329134 4.206063 28 P 0 0 ;0=26,1=0
P 4.4348425 2.7898819 33 P 0 0 ;0=31,1=0
P 4.4348425 2.8422441 33 P 0 0 ;0=31,1=0
P 4.4548425 3.0441338 40 P 0 0 ;0=38,1=0
P 4.4548425 3.0779921 40 P 0 0 ;0=38,1=0
P 4.5667716 4.206063 28 P 0 0 ;0=26,1=0
P 4.6526771 4.206063 24 P 0 0 ;0=22,1=0
P 4.6526772 4.121063 24 P 0 0 ;0=22,1=0
P 4.7070078 4.206063 24 P 0 0 ;0=22,1=0
P 4.7070079 4.121063 24 P 0 0 ;0=22,1=0
P 4.9094488 2.8080708 35 P 0 0 ;0=33,1=0
P 4.9094488 3.9616142 35 P 0 0 ;0=33,1=0
P 4.9579134 4.206063 28 P 0 0 ;0=26,1=0
P 5.0917716 4.206063 28 P 0 0 ;0=26,1=0
P 5.2126771 4.206063 24 P 0 0 ;0=22,1=0
P 5.2126772 4.126063 24 P 0 0 ;0=22,1=0
P 5.2670078 4.206063 24 P 0 0 ;0=22,1=0
P 5.2670079 4.126063 24 P 0 0 ;0=22,1=0
P 5.6344488 3.359252 48 P 0 0 ;0=46,1=0
P 5.6683071 3.359252 48 P 0 0 ;0=46,1=0
P 5.7411417 3.3612205 47 P 0 0 ;0=45,1=0
P 5.8120079 3.3612205 47 P 0 0 ;0=45,1=0
P 5.8879921 3.701063 15 P 0 0 ;0=13,1=0
P 6.0048425 2.3388977 51 P 0 0 ;0=49,1=0
P 6.0048425 2.3932284 51 P 0 0 ;0=49,1=0
P 6.0316929 3.701063 15 P 0 0 ;0=13,1=0
P 6.0356772 3.556063 24 P 0 0 ;0=22,1=0
P 6.0648425 2.3441339 40 P 0 0 ;0=38,1=0
P 6.0648425 2.3779922 40 P 0 0 ;0=38,1=0
P 6.0900079 3.556063 24 P 0 0 ;0=22,1=0
P 6.0933464 2.171063 49 P 0 0 ;0=47,1=0
P 6.1228425 2.4338976 51 P 0 0 ;0=49,1=0
P 6.1228425 2.4882283 51 P 0 0 ;0=49,1=0
P 6.1563385 2.171063 49 P 0 0 ;0=47,1=0
P 6.1574016 2.241063 14 P 0 0 ;0=12,1=0
P 6.1574016 2.291063 14 P 0 0 ;0=12,1=0
P 6.1574016 2.341063 14 P 0 0 ;0=12,1=0
P 6.1574016 2.391063 14 P 0 0 ;0=12,1=0
P 6.1979921 3.701063 15 P 0 0 ;0=13,1=0
P 6.2029921 3.566063 15 P 0 0 ;0=13,1=0
P 6.2348425 2.1288977 51 P 0 0 ;0=49,1=0
P 6.2348425 2.1832284 51 P 0 0 ;0=49,1=0
P 6.253937 2.7559055 38 P 0 0 ;0=36,1=0
P 6.253937 2.8267717 38 P 0 0 ;0=36,1=0
P 6.3126772 2.451063 24 P 0 0 ;0=22,1=0
P 6.3198425 1.4601181 34 P 0 0 ;0=32,1=0
P 6.3198425 1.8420079 34 P 0 0 ;0=32,1=0
P 6.3279134 2.501063 48 P 0 0 ;0=46,1=0
P 6.3279134 2.556063 48 P 0 0 ;0=46,1=0
P 6.3279134 2.611063 48 P 0 0 ;0=46,1=0
P 6.3279134 2.656063 48 P 0 0 ;0=46,1=0
P 6.3348425 2.1106299 38 P 0 0 ;0=36,1=0
P 6.3348425 2.1814961 38 P 0 0 ;0=36,1=0
P 6.3416929 3.701063 15 P 0 0 ;0=13,1=0
P 6.3466929 3.566063 15 P 0 0 ;0=13,1=0
P 6.3522834 2.241063 14 P 0 0 ;0=12,1=0
P 6.3522834 2.291063 14 P 0 0 ;0=12,1=0
P 6.3522834 2.341063 14 P 0 0 ;0=12,1=0
P 6.3522834 2.391063 14 P 0 0 ;0=12,1=0
P 6.3617717 2.501063 48 P 0 0 ;0=46,1=0
P 6.3617717 2.556063 48 P 0 0 ;0=46,1=0
P 6.3617717 2.611063 48 P 0 0 ;0=46,1=0
P 6.3617717 2.656063 48 P 0 0 ;0=46,1=0
P 6.3670079 2.451063 24 P 0 0 ;0=22,1=0
P 6.3720472 2.7559055 38 P 0 0 ;0=36,1=0
P 6.3720472 2.8267717 38 P 0 0 ;0=36,1=0
P 6.3883268 3.1524803 30 P 0 0 ;0=28,1=0
P 6.3883268 3.1721654 30 P 0 0 ;0=28,1=0
P 6.3883268 3.1918504 30 P 0 0 ;0=28,1=0
P 6.3883268 3.2115354 30 P 0 0 ;0=28,1=0
P 6.3883268 3.2312205 30 P 0 0 ;0=28,1=0
P 6.3883268 3.2509055 30 P 0 0 ;0=28,1=0
P 6.3883268 3.2705906 30 P 0 0 ;0=28,1=0
P 6.3883268 3.2902756 30 P 0 0 ;0=28,1=0
P 6.3883268 3.3099606 30 P 0 0 ;0=28,1=0
P 6.3883268 3.3296457 30 P 0 0 ;0=28,1=0
P 6.4203149 3.1500197 31 P 0 0 ;0=29,1=0
P 6.4203149 3.3321063 31 P 0 0 ;0=29,1=0
P 6.4394094 3.071063 47 P 0 0 ;0=45,1=0
P 6.44 3.1500197 31 P 0 0 ;0=29,1=0
P 6.44 3.3321063 31 P 0 0 ;0=29,1=0
P 6.459685 3.3321063 31 P 0 0 ;0=29,1=0
P 6.4598425 3.1500197 31 P 0 0 ;0=29,1=0
P 6.4698425 2.2395669 39 P 0 0 ;0=37,1=0
P 6.4698425 2.302559 39 P 0 0 ;0=37,1=0
P 6.4793701 3.1500197 31 P 0 0 ;0=29,1=0
P 6.4793701 3.3321063 31 P 0 0 ;0=29,1=0
P 6.5102756 3.071063 47 P 0 0 ;0=45,1=0
P 6.5113582 3.1524803 30 P 0 0 ;0=28,1=0
P 6.5113582 3.1721654 30 P 0 0 ;0=28,1=0
P 6.5113582 3.1918504 30 P 0 0 ;0=28,1=0
P 6.5113582 3.2115354 30 P 0 0 ;0=28,1=0
P 6.5113582 3.2312205 30 P 0 0 ;0=28,1=0
P 6.5113582 3.2509055 30 P 0 0 ;0=28,1=0
P 6.5113582 3.2705906 30 P 0 0 ;0=28,1=0
P 6.5113582 3.2902756 30 P 0 0 ;0=28,1=0
P 6.5113582 3.3099606 30 P 0 0 ;0=28,1=0
P 6.5113582 3.3296457 30 P 0 0 ;0=28,1=0
P 6.5198425 1.954567 39 P 0 0 ;0=37,1=0
P 6.5198425 2.0175591 39 P 0 0 ;0=37,1=0
P 6.5848425 3.0391338 40 P 0 0 ;0=38,1=0
P 6.5848425 3.0729921 40 P 0 0 ;0=38,1=0
P 6.6048425 3.1295669 39 P 0 0 ;0=37,1=0
P 6.6048425 3.192559 39 P 0 0 ;0=37,1=0
P 6.6048425 3.264567 39 P 0 0 ;0=37,1=0
P 6.6048425 3.3275591 39 P 0 0 ;0=37,1=0
P 6.6294094 1.421063 47 P 0 0 ;0=45,1=0
P 6.6294094 1.531063 47 P 0 0 ;0=45,1=0
P 6.6374016 1.881063 14 P 0 0 ;0=12,1=0
P 6.6374016 1.931063 14 P 0 0 ;0=12,1=0
P 6.6374016 1.981063 14 P 0 0 ;0=12,1=0
P 6.6374016 2.031063 14 P 0 0 ;0=12,1=0
P 6.6429133 1.611063 48 P 0 0 ;0=46,1=0
P 6.6429133 1.671063 48 P 0 0 ;0=46,1=0
P 6.6429133 1.721063 48 P 0 0 ;0=46,1=0
P 6.6429133 1.776063 48 P 0 0 ;0=46,1=0
P 6.6598425 2.0956299 38 P 0 0 ;0=36,1=0
P 6.6598425 2.1664961 38 P 0 0 ;0=36,1=0
P 6.6767716 1.611063 48 P 0 0 ;0=46,1=0
P 6.6767716 1.671063 48 P 0 0 ;0=46,1=0
P 6.6767716 1.721063 48 P 0 0 ;0=46,1=0
P 6.6767716 1.776063 48 P 0 0 ;0=46,1=0
P 6.6798425 2.4201181 34 P 0 0 ;0=32,1=0
P 6.6798425 2.8020079 34 P 0 0 ;0=32,1=0
P 6.7002756 1.421063 47 P 0 0 ;0=45,1=0
P 6.7002756 1.531063 47 P 0 0 ;0=45,1=0
P 6.7265748 3.1680709 16 P 0 0 ;0=14,1=0
P 6.7265748 3.2940551 16 P 0 0 ;0=14,1=0
P 6.7276771 1.816063 24 P 0 0 ;0=22,1=0
P 6.7498425 2.0888976 51 P 0 0 ;0=49,1=0
P 6.7498425 2.1432283 51 P 0 0 ;0=49,1=0
P 6.7820078 1.816063 24 P 0 0 ;0=22,1=0
P 6.8322834 1.881063 14 P 0 0 ;0=12,1=0
P 6.8322834 1.931063 14 P 0 0 ;0=12,1=0
P 6.8322834 1.981063 14 P 0 0 ;0=12,1=0
P 6.8322834 2.031063 14 P 0 0 ;0=12,1=0
P 6.8426771 1.816063 24 P 0 0 ;0=22,1=0
P 6.8433465 2.096063 49 P 0 0 ;0=47,1=0
P 6.8970078 1.816063 24 P 0 0 ;0=22,1=0
P 6.9063386 2.096063 49 P 0 0 ;0=47,1=0
P 6.9398425 1.8891338 40 P 0 0 ;0=38,1=0
P 6.9398425 1.9229921 40 P 0 0 ;0=38,1=0
P 6.9431102 3.1680709 16 P 0 0 ;0=14,1=0
P 6.9431102 3.2940551 16 P 0 0 ;0=14,1=0
P 7.0098425 1.8838977 51 P 0 0 ;0=49,1=0
P 7.0098425 1.9382284 51 P 0 0 ;0=49,1=0

### steps/pcb/layers/top_solder/features
#Layer_Color=8388736
#
#Feature symbol names
#
$0 r3.937
$1 r1
$2 rect314.9607x135.8267
$3 rect1354.3307x230.315
$4 oval86.7402x31.622
$5 rect47.3701x82.8031
$6 rect78.8661x82.8031
$7 rect63.9055x69.0236
$8 rect25.7165x62.3307
$9 rect72.9606x59.1811
$10 rect86.7402x106.4252
$11 rect27.685x98.5512
$12 rect49.3386x47.3701
$13 rect94.6142x49.3386
$14 rect27.685x43.4331
$15 oval65.0866x25.7165
$16 rect85.5591x30.4409
$17 rect33.5906x49.3386
$18 rect59.1811x82.8031
$19 rect47.3701x78.8661
$20 rect47.3701x98.5512
$21 rect49.3386x53.2756
$22 rect35.5591x53.2756
$23 rect61.1496x35.5591
$24 rect58x208
$25 rect65.0866x45.4016
$26 rect36.3465x47.3701
$27 rect33.5906x31.622
$28 rect36x173
$29 rect36x134
$30 rect39.4961x74.9291
$31 rect78.8661x17.8425
$32 rect34.5748x17.8425
$33 rect17.8425x30.6378
$34 rect35.5591x43.4331
$35 rect46.5827x42.252
$36 rect220.5984x122.1732
$37 rect165.3543x125.9843
$38 rect104.4567x132.0157
$39 rect41.4646x47.3701
$40 rect65.0866x53.2756
$41 rect45.4016x47.3701
$42 rect33.1969x34.7717
$43 rect18.8268x17.8425
$44 rect17.8425x18.8268
$45 rect69.02x17.84
$46 rect74.93x61.15
$47 rect17.84x69.02
$48 rect61.15x74.93
$49 rect53.2756x65.0866
$50 rect34.7717x33.1969
$51 rect47.3701x45.4016
$52 rect47.3701x41.4646
$53 rect47.3701x36.3465
$54 rect31.622x33.5906
$55 rect90.874x52.0945
$56 rect43.4331x35.5591
$57 r39.4961
$58 r73.9843
$59 r8
$60 r69.0236
$61 s69.0236
$62 r83
$63 r106.4252
$64 oval96.5827x185.1654
$65 oval185.1654x96.5827
$66 oval204.8504x106.4252
$67 r120
$68 r128
$69 s8
$70 r29.66
$71 r63
$72 s63
$73 r58
$74 r258
$75 r24
$76 r208

#
#Feature attribute names
#
@0 .geometry
@1 .pad_usage

#
#Feature attribute text strings
#
&0 SMD_OvalX78.7402Y23.6220
&1 SMD_RectX39.3701Y74.8031
&2 SMD_RectX70.8661Y74.8031
&3 SMD_RectX55.9055Y61.0236
&4 SMD_RectX17.7165Y54.3307
&5 SMD_RectX64.9606Y51.1811
&6 SMD_RectX78.7402Y98.4252
&7 SMD_RectX19.6850Y90.5512
&8 SMD_RectX41.3386Y39.3701
&9 SMD_RectX86.6142Y41.3386
&10 SMD_RectX19.6850Y35.4331
&11 SMD_OvalX57.0866Y17.7165
&12 SMD_RectX77.5591Y22.4409
&13 SMD_RectX25.5906Y41.3386
&14 SMD_RectX51.1811Y74.8031
&15 SMD_RectX39.3701Y70.8661
&16 SMD_RectX39.3701Y90.5512
&17 SMD_RectX41.3386Y45.2756
&18 SMD_RectX27.5591Y45.2756
&19 SMD_RectX53.1496Y27.5591
&20 SMD_RectX50.0000Y200.0000
&21 SMD_RectX57.0866Y37.4016
&22 SMD_RectX28.3465Y39.3701
&23 SMD_RectX25.5906Y23.6220
&24 SMD_RectX28.0000Y165.0000
&25 SMD_RectX28.0000Y126.0000
&26 SMD_RectX31.4961Y66.9291
&27 SMD_RectX70.8661Y9.8425
&28 SMD_RectX26.5748Y9.8425
&29 SMD_RectX9.8425Y22.6378
&30 SMD_RectX27.5591Y35.4331
&31 SMD_RectX38.5827Y34.2520
&32 SMD_RectX212.5984Y114.1732
&33 SMD_RectX165.3543Y125.9843
&34 SMD_RectX96.4567Y124.0157
&35 SMD_RectX33.4646Y39.3701
&36 SMD_RectX57.0866Y45.2756
&37 SMD_RectX37.4016Y39.3701
&38 SMD_RectX25.1969Y26.7717
&39 SMD_RectX10.8268Y9.8425
&40 SMD_RectX9.8425Y10.8268
&41 SMD_RectX61.0200Y9.8400
&42 SMD_RectX66.9300Y53.1500
&43 SMD_RectX9.8400Y61.0200
&44 SMD_RectX53.1500Y66.9300
&45 SMD_RectX45.2756Y57.0866
&46 SMD_RectX26.7717Y25.1969
&47 SMD_RectX39.3701Y37.4016
&48 SMD_RectX39.3701Y33.4646
&49 SMD_RectX39.3701Y28.3465
&50 SMD_RectX23.6220Y25.5906
&51 SMD_RectX82.8740Y44.0945
&52 SMD_RectX35.4331Y27.5591
&53 Pad_Simple_X31.4961Y31.4961H35.4331C75.4331
&54 Pad_Simple_X65.9843Y65.9843H65.9843C105.9843
&55 Pad_Simple_X0.0000Y0.0000H29.9213C69.9213
&56 Pad_Simple_X61.0236Y61.0236H41.3386C81.3386
&57 Pad_Simple_X75.0000Y75.0000H50.0000C90.0000
&58 Pad_Simple_X98.4252Y98.4252H64.9606C104.9606
&59 Pad_Simple_X88.5827Y177.1654H39.3701C79.3701
&60 Pad_Simple_X177.1654Y88.5827H39.3701C79.3701
&61 Pad_Simple_X196.8504Y98.4252H39.3701C79.3701
&62 Pad_Simple_X112.0000Y112.0000H60.0000C100.0000
&63 Pad_Simple_X120.0000Y120.0000H68.0000C108.0000
&64 Pad_Simple_X0.0000Y0.0000H118.1100C158.1100
&65 Pad_Simple_X21.6600Y21.6600H21.6600C61.6600
&66 Pad_Simple_X55.0000Y55.0000H30.0000C70.0000
&67 Pad_Simple_X50.0000Y50.0000H118.1102C158.1102
&68 Pad_Simple_X98.4252Y98.4252H70.8661C110.8661
&69 Pad_Complex_X50.0000Y50.0000H118.1102C158.1102
&70 Pad_Simple_X250.0000Y250.0000H125.1969C165.1969
&71 VIA_RoundD16.0000H8.0000C48.0000
&72 VIA_RoundD200.0000H125.9843C165.9843

#
#Layer features
#
A 1.7712204 0.4310709 1.6275196 0.4310709 1.69937 0.4310709 0 P 0 N
L -0.0001175 0.177913 0.5908825 0.177913 1 P 0
L -0.0004331 0.1781182 0.5901181 0.1781182 0 P 0
L 0.5901181 0.1781182 0.5901181 0.5029213 0 P 0
L 0.5901181 0.5029213 1.312559 0.5029213 0 P 0
L 0.5908825 0.177913 0.5908825 0.502913 1 P 0
L 1.312559 0.313945 1.312559 0.5029213 0 P 0
L 1.312559 0.313945 1.6275197 0.313945 0 P 0
L 1.6275197 0.313945 1.6275197 0.4310709 0 P 0
P 0.0998425 0.806063 68 P 0 0 ;0=63,1=0
P 0.0998425 1.006063 68 P 0 0 ;0=63,1=0
P 0.0998425 1.331063 68 P 0 0 ;0=63,1=0
P 0.0998425 1.531063 68 P 0 0 ;0=63,1=0
P 0.0998425 1.856063 68 P 0 0 ;0=63,1=0
P 0.0998425 2.056063 68 P 0 0 ;0=63,1=0
P 0.0998425 2.381063 68 P 0 0 ;0=63,1=0
P 0.0998425 2.581063 68 P 0 0 ;0=63,1=0
P 0.1998425 0.906063 67 P 0 0 ;0=62,1=0
P 0.1998425 1.431063 67 P 0 0 ;0=62,1=0
P 0.1998425 1.956063 67 P 0 0 ;0=62,1=0
P 0.1998425 2.481063 67 P 0 0 ;0=62,1=0
P 0.285433 4.152063 74 P 0 0 ;0=70,1=0
P 0.2854331 0.3681102 74 P 0 0 ;0=70,1=0
P 0.2998425 0.806063 68 P 0 0 ;0=63,1=0
P 0.2998425 1.006063 68 P 0 0 ;0=63,1=0
P 0.2998425 1.331063 68 P 0 0 ;0=63,1=0
P 0.2998425 1.531063 68 P 0 0 ;0=63,1=0
P 0.2998425 1.856063 68 P 0 0 ;0=63,1=0
P 0.2998425 2.056063 68 P 0 0 ;0=63,1=0
P 0.2998425 2.381063 68 P 0 0 ;0=63,1=0
P 0.2998425 2.581063 68 P 0 0 ;0=63,1=0
P 0.5948031 0.906063 12 P 0 0 ;0=8,1=0
P 0.5948031 1.431063 12 P 0 0 ;0=8,1=0
P 0.5948031 1.956063 12 P 0 0 ;0=8,1=0
P 0.5948031 2.481063 12 P 0 0 ;0=8,1=0
P 0.6389685 4.0388976 53 P 0 0 ;0=49,1=0
P 0.6389685 4.0932283 53 P 0 0 ;0=49,1=0
P 0.6448425 4.1975197 39 P 0 0 ;0=35,1=0
P 0.6448425 4.2546063 39 P 0 0 ;0=35,1=0
P 0.6548425 0.8479921 13 P 0 0 ;0=9,1=0
P 0.6548425 0.9641339 13 P 0 0 ;0=9,1=0
P 0.6548425 1.3729921 13 P 0 0 ;0=9,1=0
P 0.6548425 1.4891339 13 P 0 0 ;0=9,1=0
P 0.6548425 1.8979921 13 P 0 0 ;0=9,1=0
P 0.6548425 2.0141339 13 P 0 0 ;0=9,1=0
P 0.6548425 2.4229921 13 P 0 0 ;0=9,1=0
P 0.6548425 2.5391339 13 P 0 0 ;0=9,1=0
P 0.8406351 4.0388976 53 P 0 0 ;0=49,1=0
P 0.8406351 4.0932283 53 P 0 0 ;0=49,1=0
P 0.8465091 4.1975197 39 P 0 0 ;0=35,1=0
P 0.8465091 4.2546063 39 P 0 0 ;0=35,1=0
P 0.9005905 1.7470472 34 P 0 0 ;0=30,1=0
P 0.9015747 0.7185038 34 P 0 0 ;0=30,1=0
P 0.9045275 1.2244094 34 P 0 0 ;0=30,1=0
P 0.9084645 2.2844487 34 P 0 0 ;0=30,1=0
P 0.9326378 0.906063 38 P 0 0 ;0=34,1=0
P 0.9326378 1.431063 38 P 0 0 ;0=34,1=0
P 0.9326378 1.956063 38 P 0 0 ;0=34,1=0
P 0.9326378 2.481063 38 P 0 0 ;0=34,1=0
P 0.9596456 1.7470472 34 P 0 0 ;0=30,1=0
P 0.9606298 0.7185038 34 P 0 0 ;0=30,1=0
P 0.9635826 1.2244094 34 P 0 0 ;0=30,1=0
P 0.9675196 2.2844487 34 P 0 0 ;0=30,1=0
P 1.0423017 4.0388976 53 P 0 0 ;0=49,1=0
P 1.0423017 4.0932283 53 P 0 0 ;0=49,1=0
P 1.0481757 4.1975197 39 P 0 0 ;0=35,1=0
P 1.0481757 4.2546063 39 P 0 0 ;0=35,1=0
P 1.1570472 0.906063 38 P 0 0 ;0=34,1=0
P 1.1570472 1.431063 38 P 0 0 ;0=34,1=0
P 1.1570472 1.956063 38 P 0 0 ;0=34,1=0
P 1.1570472 2.481063 38 P 0 0 ;0=34,1=0
P 1.2439683 4.0388976 53 P 0 0 ;0=49,1=0
P 1.2439683 4.0932283 53 P 0 0 ;0=49,1=0
P 1.2498423 4.1975197 39 P 0 0 ;0=35,1=0
P 1.2498423 4.2546063 39 P 0 0 ;0=35,1=0
P 1.3464567 3.9783465 56 P 0 0 ;0=52,1=0
P 1.3464567 4.0374016 56 P 0 0 ;0=52,1=0
P 1.3464567 4.0826772 56 P 0 0 ;0=52,1=0
P 1.3464567 4.1417323 56 P 0 0 ;0=52,1=0
P 1.4576771 4.053937 71 P 0 0 ;0=66,1=0
P 1.4576771 4.153937 71 P 0 0 ;0=66,1=0
P 1.4576771 4.253937 72 P 0 0 ;0=66,1=0
P 1.4704724 0.2450787 2 P 0 0
P 1.6171125 1.319673 45 P 0 0 ;0=41,1=0
P 1.6171125 1.339363 45 P 0 0 ;0=41,1=0
P 1.6171125 1.359043 45 P 0 0 ;0=41,1=0
P 1.6171125 1.378733 45 P 0 0 ;0=41,1=0
P 1.6171125 1.398413 45 P 0 0 ;0=41,1=0
P 1.6171125 1.418103 45 P 0 0 ;0=41,1=0
P 1.6171125 1.437783 45 P 0 0 ;0=41,1=0
P 1.6171125 1.457473 45 P 0 0 ;0=41,1=0
P 1.6171125 1.477153 45 P 0 0 ;0=41,1=0
P 1.6171125 1.496843 45 P 0 0 ;0=41,1=0
P 1.6171125 1.516523 45 P 0 0 ;0=41,1=0
P 1.6171125 1.536213 45 P 0 0 ;0=41,1=0
P 1.6171125 1.555893 45 P 0 0 ;0=41,1=0
P 1.6171125 1.575583 45 P 0 0 ;0=41,1=0
P 1.6171125 1.595263 45 P 0 0 ;0=41,1=0
P 1.6171125 1.614953 45 P 0 0 ;0=41,1=0
P 1.6171125 1.634633 45 P 0 0 ;0=41,1=0
P 1.6171125 1.654323 45 P 0 0 ;0=41,1=0
P 1.6171125 1.674003 45 P 0 0 ;0=41,1=0
P 1.6171125 1.693693 45 P 0 0 ;0=41,1=0
P 1.6171125 1.713373 45 P 0 0 ;0=41,1=0
P 1.6171125 1.733063 45 P 0 0 ;0=41,1=0
P 1.6171125 1.752743 45 P 0 0 ;0=41,1=0
P 1.6171125 1.772433 45 P 0 0 ;0=41,1=0
P 1.6171125 1.792113 45 P 0 0 ;0=41,1=0
P 1.6171125 1.811803 45 P 0 0 ;0=41,1=0
P 1.6171125 1.831483 45 P 0 0 ;0=41,1=0
P 1.6171125 1.851173 45 P 0 0 ;0=41,1=0
P 1.6171125 1.870853 45 P 0 0 ;0=41,1=0
P 1.6171125 1.890543 45 P 0 0 ;0=41,1=0
P 1.6171125 1.910223 45 P 0 0 ;0=41,1=0
P 1.6171125 1.929913 45 P 0 0 ;0=41,1=0
P 1.6171125 1.949593 45 P 0 0 ;0=41,1=0
P 1.6171125 1.969283 45 P 0 0 ;0=41,1=0
P 1.6171125 1.988963 45 P 0 0 ;0=41,1=0
P 1.6171125 2.008653 45 P 0 0 ;0=41,1=0
P 1.6171125 2.028333 45 P 0 0 ;0=41,1=0
P 1.6171125 2.048023 45 P 0 0 ;0=41,1=0
P 1.6171125 2.067703 45 P 0 0 ;0=41,1=0
P 1.6171125 2.087393 45 P 0 0 ;0=41,1=0
P 1.631559 4.024563 15 P 0 0 ;0=11,1=0
P 1.631559 4.049563 15 P 0 0 ;0=11,1=0
P 1.631559 4.074563 15 P 0 0 ;0=11,1=0
P 1.631559 4.099563 15 P 0 0 ;0=11,1=0
P 1.631559 4.124563 15 P 0 0 ;0=11,1=0
P 1.631559 4.149563 15 P 0 0 ;0=11,1=0
P 1.631559 4.174563 15 P 0 0 ;0=11,1=0
P 1.631559 4.199563 15 P 0 0 ;0=11,1=0
P 1.6519425 2.486293 69 P 0 0 ;0=64,1=0
P 1.6529425 0.916293 69 P 0 0 ;0=64,1=0
P 1.6643465 4.273063 51 P 0 0 ;0=47,1=0
P 1.6968325 1.275383 46 P 0 0 ;0=42,1=0
P 1.6968325 1.309833 70 P 0 0 ;0=65,1=0
P 1.6968325 2.097233 70 P 0 0 ;0=65,1=0
P 1.6968325 2.131683 46 P 0 0 ;0=42,1=0
P 1.7273386 4.273063 51 P 0 0 ;0=47,1=0
P 1.7765525 1.319673 45 P 0 0 ;0=41,1=0
P 1.7765525 1.339363 45 P 0 0 ;0=41,1=0
P 1.7765525 1.359043 45 P 0 0 ;0=41,1=0
P 1.7765525 1.378733 45 P 0 0 ;0=41,1=0
P 1.7765525 1.398413 45 P 0 0 ;0=41,1=0
P 1.7765525 1.418103 45 P 0 0 ;0=41,1=0
P 1.7765525 1.437783 45 P 0 0 ;0=41,1=0
P 1.7765525 1.457473 45 P 0 0 ;0=41,1=0
P 1.7765525 1.477153 45 P 0 0 ;0=41,1=0
P 1.7765525 1.496843 45 P 0 0 ;0=41,1=0
P 1.7765525 1.516523 45 P 0 0 ;0=41,1=0
P 1.7765525 1.536213 45 P 0 0 ;0=41,1=0
P 1.7765525 1.555893 45 P 0 0 ;0=41,1=0
P 1.7765525 1.575583 45 P 0 0 ;0=41,1=0
P 1.7765525 1.595263 45 P 0 0 ;0=41,1=0
P 1.7765525 1.614953 45 P 0 0 ;0=41,1=0
P 1.7765525 1.634633 45 P 0 0 ;0=41,1=0
P 1.7765525 1.654323 45 P 0 0 ;0=41,1=0
P 1.7765525 1.674003 45 P 0 0 ;0=41,1=0
P 1.7765525 1.693693 45 P 0 0 ;0=41,1=0
P 1.7765525 1.713373 45 P 0 0 ;0=41,1=0
P 1.7765525 1.733063 45 P 0 0 ;0=41,1=0
P 1.7765525 1.752743 45 P 0 0 ;0=41,1=0
P 1.7765525 1.772433 45 P 0 0 ;0=41,1=0
P 1.7765525 1.792113 45 P 0 0 ;0=41,1=0
P 1.7765525 1.811803 45 P 0 0 ;0=41,1=0
P 1.7765525 1.831483 45 P 0 0 ;0=41,1=0
P 1.7765525 1.851173 45 P 0 0 ;0=41,1=0
P 1.7765525 1.870853 45 P 0 0 ;0=41,1=0
P 1.7765525 1.890543 45 P 0 0 ;0=41,1=0
P 1.7765525 1.910223 45 P 0 0 ;0=41,1=0
P 1.7765525 1.929913 45 P 0 0 ;0=41,1=0
P 1.7765525 1.949593 45 P 0 0 ;0=41,1=0
P 1.7765525 1.969283 45 P 0 0 ;0=41,1=0
P 1.7765525 1.988963 45 P 0 0 ;0=41,1=0
P 1.7765525 2.008653 45 P 0 0 ;0=41,1=0
P 1.7765525 2.028333 45 P 0 0 ;0=41,1=0
P 1.7765525 2.048023 45 P 0 0 ;0=41,1=0
P 1.7765525 2.067703 45 P 0 0 ;0=41,1=0
P 1.7765525 2.087393 45 P 0 0 ;0=41,1=0
P 1.7972451 0.1377953 28 P 0 0 ;0=24,1=0
P 1.8024094 4.276063 49 P 0 0 ;0=45,1=0
P 1.8366151 0.1377953 28 P 0 0 ;0=24,1=0
P 1.8461259 4.024563 15 P 0 0 ;0=11,1=0
P 1.8461259 4.049563 15 P 0 0 ;0=11,1=0
P 1.8461259 4.074563 15 P 0 0 ;0=11,1=0
P 1.8461259 4.099563 15 P 0 0 ;0=11,1=0
P 1.8461259 4.124563 15 P 0 0 ;0=11,1=0
P 1.8461259 4.149563 15 P 0 0 ;0=11,1=0
P 1.8461259 4.174563 15 P 0 0 ;0=11,1=0
P 1.8461259 4.199563 15 P 0 0 ;0=11,1=0
P 1.8732756 4.276063 49 P 0 0 ;0=45,1=0
P 1.8759851 0.1377953 28 P 0 0 ;0=24,1=0
P 1.9153551 0.1377953 28 P 0 0 ;0=24,1=0
P 1.9338425 4.0748977 53 P 0 0 ;0=49,1=0
P 1.9338425 4.1292284 53 P 0 0 ;0=49,1=0
P 1.9547251 0.1377953 28 P 0 0 ;0=24,1=0
P 1.9940951 0.1377953 28 P 0 0 ;0=24,1=0
P 2.0334651 0.1377953 28 P 0 0 ;0=24,1=0
P 2.0433071 4.057874 71 P 0 0 ;0=66,1=0
P 2.0433071 4.157874 71 P 0 0 ;0=66,1=0
P 2.0433071 4.257874 72 P 0 0 ;0=66,1=0
P 2.0728351 0.1377953 28 P 0 0 ;0=24,1=0
P 2.1122051 0.1377953 28 P 0 0 ;0=24,1=0
P 2.1398425 3.6641339 42 P 0 0 ;0=38,1=0
P 2.1398425 3.6979922 42 P 0 0 ;0=38,1=0
P 2.1468425 2.6248976 53 P 0 0 ;0=49,1=0
P 2.1468425 2.6792283 53 P 0 0 ;0=49,1=0
P 2.1515748 4.0157481 56 P 0 0 ;0=52,1=0
P 2.1515748 4.0748032 56 P 0 0 ;0=52,1=0
P 2.1515751 0.1377953 28 P 0 0 ;0=24,1=0
P 2.1686825 2.438533 48 P 0 0 ;0=44,1=0
P 2.1686925 0.958593 48 P 0 0 ;0=44,1=0
P 2.1909451 0.1377953 28 P 0 0 ;0=24,1=0
P 2.1996929 4.275063 9 P 0 0 ;0=5,1=0
P 2.2031325 2.438533 70 P 0 0 ;0=65,1=0
P 2.2031425 0.958593 70 P 0 0 ;0=65,1=0
P 2.2098425 3.6456299 40 P 0 0 ;0=36,1=0
P 2.2098425 3.7164961 40 P 0 0 ;0=36,1=0
P 2.2125984 4.0157481 56 P 0 0 ;0=52,1=0
P 2.2125984 4.0748032 56 P 0 0 ;0=52,1=0
P 2.2129725 2.358813 47 P 0 0 ;0=43,1=0
P 2.2129725 2.518253 47 P 0 0 ;0=43,1=0
P 2.2129825 0.878873 47 P 0 0 ;0=43,1=0
P 2.2129825 1.038313 47 P 0 0 ;0=43,1=0
P 2.2326625 2.358813 47 P 0 0 ;0=43,1=0
P 2.2326625 2.518253 47 P 0 0 ;0=43,1=0
P 2.2326725 0.878873 47 P 0 0 ;0=43,1=0
P 2.2326725 1.038313 47 P 0 0 ;0=43,1=0
P 2.2341417 4.1736851 7 P 0 0 ;0=3,1=0
P 2.2523425 2.358813 47 P 0 0 ;0=43,1=0
P 2.2523425 2.518253 47 P 0 0 ;0=43,1=0
P 2.2523525 0.878873 47 P 0 0 ;0=43,1=0
P 2.2523525 1.038313 47 P 0 0 ;0=43,1=0
P 2.2715433 4.275063 5 P 0 0 ;0=1,1=0
P 2.2720325 2.358813 47 P 0 0 ;0=43,1=0
P 2.2720325 2.518253 47 P 0 0 ;0=43,1=0
P 2.2720425 0.878873 47 P 0 0 ;0=43,1=0
P 2.2720425 1.038313 47 P 0 0 ;0=43,1=0
P 2.2813858 4.1703386 8 P 0 0 ;0=4,1=0
P 2.2917125 2.358813 47 P 0 0 ;0=43,1=0
P 2.2917125 2.518253 47 P 0 0 ;0=43,1=0
P 2.2917225 0.878873 47 P 0 0 ;0=43,1=0
P 2.2917225 1.038313 47 P 0 0 ;0=43,1=0
P 2.3069763 4.1703386 8 P 0 0 ;0=4,1=0
P 2.3090551 0.1377953 28 P 0 0 ;0=24,1=0
P 2.3114025 2.358813 47 P 0 0 ;0=43,1=0
P 2.3114025 2.518253 47 P 0 0 ;0=43,1=0
P 2.3114125 0.878873 47 P 0 0 ;0=43,1=0
P 2.3114125 1.038313 47 P 0 0 ;0=43,1=0
P 2.3310825 2.358813 47 P 0 0 ;0=43,1=0
P 2.3310825 2.518253 47 P 0 0 ;0=43,1=0
P 2.3310925 0.878873 47 P 0 0 ;0=43,1=0
P 2.3310925 1.038313 47 P 0 0 ;0=43,1=0
P 2.3325669 4.1703386 8 P 0 0 ;0=4,1=0
P 2.3348425 3.4045276 55 P 0 0 ;0=51,1=0
P 2.3348425 3.4832677 55 P 0 0 ;0=51,1=0
P 2.3348425 3.5620079 55 P 0 0 ;0=51,1=0
P 2.3348425 3.640748 55 P 0 0 ;0=51,1=0
P 2.3484251 0.1377953 28 P 0 0 ;0=24,1=0
P 2.3507725 2.358813 47 P 0 0 ;0=43,1=0
P 2.3507725 2.518253 47 P 0 0 ;0=43,1=0
P 2.3507825 0.878873 47 P 0 0 ;0=43,1=0
P 2.3507825 1.038313 47 P 0 0 ;0=43,1=0
P 2.3581575 4.1703386 8 P 0 0 ;0=4,1=0
P 2.3704525 2.358813 47 P 0 0 ;0=43,1=0
P 2.3704525 2.518253 47 P 0 0 ;0=43,1=0
P 2.3704625 0.878873 47 P 0 0 ;0=43,1=0
P 2.3704625 1.038313 47 P 0 0 ;0=43,1=0
P 2.3778425 4.275063 6 P 0 0 ;0=2,1=0
P 2.383748 4.1703386 8 P 0 0 ;0=4,1=0
P 2.3877951 0.1377953 28 P 0 0 ;0=24,1=0
P 2.3877954 2.8996063 56 P 0 0 ;0=52,1=0
P 2.3877954 2.9586614 56 P 0 0 ;0=52,1=0
P 2.3901425 2.358813 47 P 0 0 ;0=43,1=0
P 2.3901425 2.518253 47 P 0 0 ;0=43,1=0
P 2.3901525 0.878873 47 P 0 0 ;0=43,1=0
P 2.3901525 1.038313 47 P 0 0 ;0=43,1=0
P 2.4098225 2.358813 47 P 0 0 ;0=43,1=0
P 2.4098225 2.518253 47 P 0 0 ;0=43,1=0
P 2.4098325 0.878873 47 P 0 0 ;0=43,1=0
P 2.4098325 1.038313 47 P 0 0 ;0=43,1=0
P 2.4223425 3.0822126 59 P 0 0 ;0=55,1=0
P 2.4223425 3.2396929 59 P 0 0 ;0=55,1=0
P 2.4223425 3.4438977 59 P 0 0 ;0=55,1=0
P 2.4223425 3.601378 59 P 0 0 ;0=55,1=0
P 2.4271651 0.1377953 28 P 0 0 ;0=24,1=0
P 2.4295125 2.358813 47 P 0 0 ;0=43,1=0
P 2.4295125 2.518253 47 P 0 0 ;0=43,1=0
P 2.4295225 0.878873 47 P 0 0 ;0=43,1=0
P 2.4295225 1.038313 47 P 0 0 ;0=43,1=0
P 2.4309921 4.1736851 7 P 0 0 ;0=3,1=0
P 2.4468503 0.1112205 3 P 0 0
P 2.4491925 2.358813 47 P 0 0 ;0=43,1=0
P 2.4491925 2.518253 47 P 0 0 ;0=43,1=0
P 2.4492025 0.878873 47 P 0 0 ;0=43,1=0
P 2.4492025 1.038313 47 P 0 0 ;0=43,1=0
P 2.4654409 4.275063 9 P 0 0 ;0=5,1=0
P 2.4665351 0.1377953 28 P 0 0 ;0=24,1=0
P 2.4688825 2.358813 47 P 0 0 ;0=43,1=0
P 2.4688825 2.518253 47 P 0 0 ;0=43,1=0
P 2.4688925 0.878873 47 P 0 0 ;0=43,1=0
P 2.4688925 1.038313 47 P 0 0 ;0=43,1=0
P 2.4885625 2.358813 47 P 0 0 ;0=43,1=0
P 2.4885625 2.518253 47 P 0 0 ;0=43,1=0
P 2.4885725 0.878873 47 P 0 0 ;0=43,1=0
P 2.4885725 1.038313 47 P 0 0 ;0=43,1=0
P 2.503937 0.5738189 54 P 0 0 ;0=50,1=0
P 2.503937 0.6072835 54 P 0 0 ;0=50,1=0
P 2.5059051 0.1377953 28 P 0 0 ;0=24,1=0
P 2.5082525 2.358813 47 P 0 0 ;0=43,1=0
P 2.5082525 2.518253 47 P 0 0 ;0=43,1=0
P 2.5082625 0.878873 47 P 0 0 ;0=43,1=0
P 2.5082625 1.038313 47 P 0 0 ;0=43,1=0
P 2.5098425 3.4045276 55 P 0 0 ;0=51,1=0
P 2.5098425 3.4832677 55 P 0 0 ;0=51,1=0
P 2.5098425 3.5620079 55 P 0 0 ;0=51,1=0
P 2.5098425 3.640748 55 P 0 0 ;0=51,1=0
P 2.5279325 2.358813 47 P 0 0 ;0=43,1=0
P 2.5279325 2.518253 47 P 0 0 ;0=43,1=0
P 2.5279425 0.878873 47 P 0 0 ;0=43,1=0
P 2.5279425 1.038313 47 P 0 0 ;0=43,1=0
P 2.5452751 0.1377953 28 P 0 0 ;0=24,1=0
P 2.5476225 2.358813 47 P 0 0 ;0=43,1=0
P 2.5476225 2.518253 47 P 0 0 ;0=43,1=0
P 2.5476325 0.878873 47 P 0 0 ;0=43,1=0
P 2.5476325 1.038313 47 P 0 0 ;0=43,1=0
P 2.5673025 2.358813 47 P 0 0 ;0=43,1=0
P 2.5673025 2.518253 47 P 0 0 ;0=43,1=0
P 2.5673125 0.878873 47 P 0 0 ;0=43,1=0
P 2.5673125 1.038313 47 P 0 0 ;0=43,1=0
P 2.5846451 0.1377953 28 P 0 0 ;0=24,1=0
P 2.5869925 2.358813 47 P 0 0 ;0=43,1=0
P 2.5869925 2.518253 47 P 0 0 ;0=43,1=0
P 2.5870025 0.878873 47 P 0 0 ;0=43,1=0
P 2.5870025 1.038313 47 P 0 0 ;0=43,1=0
P 2.6066725 2.358813 47 P 0 0 ;0=43,1=0
P 2.6066725 2.518253 47 P 0 0 ;0=43,1=0
P 2.6066825 0.878873 47 P 0 0 ;0=43,1=0
P 2.6066825 1.038313 47 P 0 0 ;0=43,1=0
P 2.6240151 0.1377953 28 P 0 0 ;0=24,1=0
P 2.6263625 2.358813 47 P 0 0 ;0=43,1=0
P 2.6263625 2.518253 47 P 0 0 ;0=43,1=0
P 2.6263725 0.878873 47 P 0 0 ;0=43,1=0
P 2.6263725 1.038313 47 P 0 0 ;0=43,1=0
P 2.6398425 3.5356299 40 P 0 0 ;0=36,1=0
P 2.6398425 3.6064961 40 P 0 0 ;0=36,1=0
P 2.6460425 2.358813 47 P 0 0 ;0=43,1=0
P 2.6460425 2.518253 47 P 0 0 ;0=43,1=0
P 2.6460525 0.878873 47 P 0 0 ;0=43,1=0
P 2.6460525 1.038313 47 P 0 0 ;0=43,1=0
P 2.6633851 0.1377953 28 P 0 0 ;0=24,1=0
P 2.6657325 2.358813 47 P 0 0 ;0=43,1=0
P 2.6657325 2.518253 47 P 0 0 ;0=43,1=0
P 2.6657425 0.878873 47 P 0 0 ;0=43,1=0
P 2.6657425 1.038313 47 P 0 0 ;0=43,1=0
P 2.6854125 2.358813 47 P 0 0 ;0=43,1=0
P 2.6854125 2.518253 47 P 0 0 ;0=43,1=0
P 2.6854225 0.878873 47 P 0 0 ;0=43,1=0
P 2.6854225 1.038313 47 P 0 0 ;0=43,1=0
P 2.694252 3.7503543 14 P 0 0 ;0=10,1=0
P 2.7027551 0.1377953 28 P 0 0 ;0=24,1=0
P 2.7051025 2.358813 47 P 0 0 ;0=43,1=0
P 2.7051025 2.518253 47 P 0 0 ;0=43,1=0
P 2.7051125 0.878873 47 P 0 0 ;0=43,1=0
P 2.7051125 1.038313 47 P 0 0 ;0=43,1=0
P 2.7198425 3.6617716 14 P 0 0 ;0=10,1=0
P 2.7247825 2.358813 47 P 0 0 ;0=43,1=0
P 2.7247825 2.518253 47 P 0 0 ;0=43,1=0
P 2.7247925 0.878873 47 P 0 0 ;0=43,1=0
P 2.7247925 1.038313 47 P 0 0 ;0=43,1=0
P 2.7248425 3.5591338 42 P 0 0 ;0=38,1=0
P 2.7248425 3.5929921 42 P 0 0 ;0=38,1=0
P 2.7421251 0.1377953 28 P 0 0 ;0=24,1=0
P 2.7444725 2.358813 47 P 0 0 ;0=43,1=0
P 2.7444725 2.518253 47 P 0 0 ;0=43,1=0
P 2.7444825 0.878873 47 P 0 0 ;0=43,1=0
P 2.7444825 1.038313 47 P 0 0 ;0=43,1=0
P 2.7454331 3.7503543 14 P 0 0 ;0=10,1=0
P 2.7568898 2.9372047 4 P 0 0 ;0=0,1=0
P 2.7568898 2.9872047 4 P 0 0 ;0=0,1=0
P 2.7568898 3.0372047 4 P 0 0 ;0=0,1=0
P 2.7568898 3.0872047 4 P 0 0 ;0=0,1=0
P 2.7568898 3.1372047 4 P 0 0 ;0=0,1=0
P 2.7568898 3.1872047 4 P 0 0 ;0=0,1=0
P 2.7568898 3.2372047 4 P 0 0 ;0=0,1=0
P 2.7568898 3.2872047 4 P 0 0 ;0=0,1=0
P 2.7641525 2.358813 47 P 0 0 ;0=43,1=0
P 2.7641525 2.518253 47 P 0 0 ;0=43,1=0
P 2.7641625 0.878873 47 P 0 0 ;0=43,1=0
P 2.7641625 1.038313 47 P 0 0 ;0=43,1=0
P 2.7814951 0.1377953 28 P 0 0 ;0=24,1=0
P 2.7838425 2.358813 47 P 0 0 ;0=43,1=0
P 2.7838425 2.518253 47 P 0 0 ;0=43,1=0
P 2.7838525 0.878873 47 P 0 0 ;0=43,1=0
P 2.7838525 1.038313 47 P 0 0 ;0=43,1=0
P 2.8035225 2.358813 47 P 0 0 ;0=43,1=0
P 2.8035225 2.518253 47 P 0 0 ;0=43,1=0
P 2.8035325 0.878873 47 P 0 0 ;0=43,1=0
P 2.8035325 1.038313 47 P 0 0 ;0=43,1=0
P 2.809252 3.7503543 14 P 0 0 ;0=10,1=0
P 2.8208651 0.1377953 28 P 0 0 ;0=24,1=0
P 2.8232125 2.358813 47 P 0 0 ;0=43,1=0
P 2.8232125 2.518253 47 P 0 0 ;0=43,1=0
P 2.8232225 0.878873 47 P 0 0 ;0=43,1=0
P 2.8232225 1.038313 47 P 0 0 ;0=43,1=0
P 2.8348425 3.6617716 14 P 0 0 ;0=10,1=0
P 2.8428925 2.358813 47 P 0 0 ;0=43,1=0
P 2.8428925 2.518253 47 P 0 0 ;0=43,1=0
P 2.8429025 0.878873 47 P 0 0 ;0=43,1=0
P 2.8429025 1.038313 47 P 0 0 ;0=43,1=0
P 2.8602351 0.1377953 28 P 0 0 ;0=24,1=0
P 2.8604331 3.7503543 14 P 0 0 ;0=10,1=0
P 2.8625825 2.358813 47 P 0 0 ;0=43,1=0
P 2.8625825 2.518253 47 P 0 0 ;0=43,1=0
P 2.8625925 0.878873 47 P 0 0 ;0=43,1=0
P 2.8625925 1.038313 47 P 0 0 ;0=43,1=0
P 2.8822625 2.358813 47 P 0 0 ;0=43,1=0
P 2.8822625 2.518253 47 P 0 0 ;0=43,1=0
P 2.8822725 0.878873 47 P 0 0 ;0=43,1=0
P 2.8822725 1.038313 47 P 0 0 ;0=43,1=0
P 2.8996051 0.1377953 28 P 0 0 ;0=24,1=0
P 2.9019525 2.358813 47 P 0 0 ;0=43,1=0
P 2.9019525 2.518253 47 P 0 0 ;0=43,1=0
P 2.9019625 0.878873 47 P 0 0 ;0=43,1=0
P 2.9019625 1.038313 47 P 0 0 ;0=43,1=0
P 2.9216325 2.358813 47 P 0 0 ;0=43,1=0
P 2.9216325 2.518253 47 P 0 0 ;0=43,1=0
P 2.9216425 0.878873 47 P 0 0 ;0=43,1=0
P 2.9216425 1.038313 47 P 0 0 ;0=43,1=0
P 2.9389751 0.1377953 28 P 0 0 ;0=24,1=0
P 2.9413225 2.358813 47 P 0 0 ;0=43,1=0
P 2.9413225 2.518253 47 P 0 0 ;0=43,1=0
P 2.9413325 0.878873 47 P 0 0 ;0=43,1=0
P 2.9413325 1.038313 47 P 0 0 ;0=43,1=0
P 2.9448425 3.6666929 25 P 0 0 ;0=21,1=0
P 2.9448425 3.7454331 25 P 0 0 ;0=21,1=0
P 2.9448425 3.951063 24 P 0 0 ;0=20,1=0
P 2.9448425 4.2211417 24 P 0 0 ;0=20,1=0
P 2.9610025 2.358813 47 P 0 0 ;0=43,1=0
P 2.9610025 2.518253 47 P 0 0 ;0=43,1=0
P 2.9610125 0.878873 47 P 0 0 ;0=43,1=0
P 2.9610125 1.038313 47 P 0 0 ;0=43,1=0
P 2.9783451 0.1377953 28 P 0 0 ;0=24,1=0
P 2.9806925 2.358813 47 P 0 0 ;0=43,1=0
P 2.9806925 2.518253 47 P 0 0 ;0=43,1=0
P 2.9807025 0.878873 47 P 0 0 ;0=43,1=0
P 2.9807025 1.038313 47 P 0 0 ;0=43,1=0
P 2.9905325 2.438533 70 P 0 0 ;0=65,1=0
P 2.9905425 0.958593 70 P 0 0 ;0=65,1=0
P 2.9948425 4.0861024 58 P 0 0 ;0=54,1=0
P 3.0177151 0.1377953 28 P 0 0 ;0=24,1=0
P 3.0249825 2.438533 48 P 0 0 ;0=44,1=0
P 3.0249925 0.958593 48 P 0 0 ;0=44,1=0
P 3.0448425 3.6666929 25 P 0 0 ;0=21,1=0
P 3.0448425 3.7454331 25 P 0 0 ;0=21,1=0
P 3.0448425 3.951063 24 P 0 0 ;0=20,1=0
P 3.0448425 4.2211417 24 P 0 0 ;0=20,1=0
P 3.0551181 0.5738189 54 P 0 0 ;0=50,1=0
P 3.0551181 0.6072835 54 P 0 0 ;0=50,1=0
P 3.0570851 0.1572953 29 P 0 0 ;0=25,1=0
P 3.0964551 0.1377953 28 P 0 0 ;0=24,1=0
P 3.1112205 2.9372047 4 P 0 0 ;0=0,1=0
P 3.1112205 2.9872047 4 P 0 0 ;0=0,1=0
P 3.1112205 3.0372047 4 P 0 0 ;0=0,1=0
P 3.1112205 3.0872047 4 P 0 0 ;0=0,1=0
P 3.1112205 3.1372047 4 P 0 0 ;0=0,1=0
P 3.1112205 3.1872047 4 P 0 0 ;0=0,1=0
P 3.1112205 3.2372047 4 P 0 0 ;0=0,1=0
P 3.1112205 3.2872047 4 P 0 0 ;0=0,1=0
P 3.1448425 3.6666929 25 P 0 0 ;0=21,1=0
P 3.1448425 3.7454331 25 P 0 0 ;0=21,1=0
P 3.1448425 3.951063 24 P 0 0 ;0=20,1=0
P 3.1448425 4.2211417 24 P 0 0 ;0=20,1=0
P 3.2091732 2.7952756 43 P 0 0 ;0=39,1=0
P 3.2091732 2.8149606 43 P 0 0 ;0=39,1=0
P 3.2091732 2.8346456 43 P 0 0 ;0=39,1=0
P 3.219252 3.7503543 14 P 0 0 ;0=10,1=0
P 3.2293307 2.7849212 44 P 0 0 ;0=40,1=0
P 3.2293307 2.845 44 P 0 0 ;0=40,1=0
P 3.2448425 3.6617716 14 P 0 0 ;0=10,1=0
P 3.2448425 3.951063 24 P 0 0 ;0=20,1=0
P 3.2448425 4.2211417 24 P 0 0 ;0=20,1=0
P 3.2490157 2.7849212 44 P 0 0 ;0=40,1=0
P 3.2490157 2.845 44 P 0 0 ;0=40,1=0
P 3.2691732 2.7952756 43 P 0 0 ;0=39,1=0
P 3.2691732 2.8149606 43 P 0 0 ;0=39,1=0
P 3.2691732 2.8346456 43 P 0 0 ;0=39,1=0
P 3.2704331 3.7503543 14 P 0 0 ;0=10,1=0
P 3.2948425 4.0861024 58 P 0 0 ;0=54,1=0
P 3.3331103 3.2062205 19 P 0 0 ;0=15,1=0
P 3.3331103 3.3951969 19 P 0 0 ;0=15,1=0
P 3.3448425 3.951063 24 P 0 0 ;0=20,1=0
P 3.3448425 4.2211417 24 P 0 0 ;0=20,1=0
P 3.3498425 3.6666929 25 P 0 0 ;0=21,1=0
P 3.3498425 3.7454331 25 P 0 0 ;0=21,1=0
P 3.3921654 3.2062205 19 P 0 0 ;0=15,1=0
P 3.3921654 3.3951969 19 P 0 0 ;0=15,1=0
P 3.4385827 2.8923386 21 P 0 0 ;0=17,1=0
P 3.4385827 3.0517874 21 P 0 0 ;0=17,1=0
P 3.444252 3.7503543 14 P 0 0 ;0=10,1=0
P 3.4444882 2.948441 23 P 0 0 ;0=19,1=0
P 3.4444882 2.995685 23 P 0 0 ;0=19,1=0
P 3.4512205 3.2062205 19 P 0 0 ;0=15,1=0
P 3.4512205 3.3951969 19 P 0 0 ;0=15,1=0
P 3.4698425 3.6617716 14 P 0 0 ;0=10,1=0
P 3.4776771 2.797063 26 P 0 0 ;0=22,1=0
P 3.4848425 2.8923386 22 P 0 0 ;0=18,1=0
P 3.4848425 3.0517874 22 P 0 0 ;0=18,1=0
P 3.4920225 1.319633 45 P 0 0 ;0=41,1=0
P 3.4920225 1.339323 45 P 0 0 ;0=41,1=0
P 3.4920225 1.359003 45 P 0 0 ;0=41,1=0
P 3.4920225 1.378693 45 P 0 0 ;0=41,1=0
P 3.4920225 1.398373 45 P 0 0 ;0=41,1=0
P 3.4920225 1.418063 45 P 0 0 ;0=41,1=0
P 3.4920225 1.437743 45 P 0 0 ;0=41,1=0
P 3.4920225 1.457433 45 P 0 0 ;0=41,1=0
P 3.4920225 1.477113 45 P 0 0 ;0=41,1=0
P 3.4920225 1.496803 45 P 0 0 ;0=41,1=0
P 3.4920225 1.516483 45 P 0 0 ;0=41,1=0
P 3.4920225 1.536173 45 P 0 0 ;0=41,1=0
P 3.4920225 1.555853 45 P 0 0 ;0=41,1=0
P 3.4920225 1.575543 45 P 0 0 ;0=41,1=0
P 3.4920225 1.595223 45 P 0 0 ;0=41,1=0
P 3.4920225 1.614913 45 P 0 0 ;0=41,1=0
P 3.4920225 1.634593 45 P 0 0 ;0=41,1=0
P 3.4920225 1.654283 45 P 0 0 ;0=41,1=0
P 3.4920225 1.673963 45 P 0 0 ;0=41,1=0
P 3.4920225 1.693653 45 P 0 0 ;0=41,1=0
P 3.4920225 1.713333 45 P 0 0 ;0=41,1=0
P 3.4920225 1.733023 45 P 0 0 ;0=41,1=0
P 3.4920225 1.752703 45 P 0 0 ;0=41,1=0
P 3.4920225 1.772393 45 P 0 0 ;0=41,1=0
P 3.4920225 1.792073 45 P 0 0 ;0=41,1=0
P 3.4920225 1.811763 45 P 0 0 ;0=41,1=0
P 3.4920225 1.831443 45 P 0 0 ;0=41,1=0
P 3.4920225 1.851133 45 P 0 0 ;0=41,1=0
P 3.4920225 1.870813 45 P 0 0 ;0=41,1=0
P 3.4920225 1.890503 45 P 0 0 ;0=41,1=0
P 3.4920225 1.910183 45 P 0 0 ;0=41,1=0
P 3.4920225 1.929873 45 P 0 0 ;0=41,1=0
P 3.4920225 1.949553 45 P 0 0 ;0=41,1=0
P 3.4920225 1.969243 45 P 0 0 ;0=41,1=0
P 3.4920225 1.988923 45 P 0 0 ;0=41,1=0
P 3.4920225 2.008613 45 P 0 0 ;0=41,1=0
P 3.4920225 2.028293 45 P 0 0 ;0=41,1=0
P 3.4920225 2.047983 45 P 0 0 ;0=41,1=0
P 3.4920225 2.067663 45 P 0 0 ;0=41,1=0
P 3.4920225 2.087353 45 P 0 0 ;0=41,1=0
P 3.4954331 3.7503543 14 P 0 0 ;0=10,1=0
P 3.5102756 3.2062205 19 P 0 0 ;0=15,1=0
P 3.5102756 3.3951969 19 P 0 0 ;0=15,1=0
P 3.5251968 2.948441 23 P 0 0 ;0=19,1=0
P 3.5251968 2.995685 23 P 0 0 ;0=19,1=0
P 3.5311023 2.8923386 21 P 0 0 ;0=17,1=0
P 3.5311023 3.0517874 21 P 0 0 ;0=17,1=0
P 3.5320078 2.797063 26 P 0 0 ;0=22,1=0
P 3.5693307 3.2062205 19 P 0 0 ;0=15,1=0
P 3.5693307 3.3853543 20 P 0 0 ;0=16,1=0
P 3.5717425 1.275343 46 P 0 0 ;0=42,1=0
P 3.5717425 1.309793 70 P 0 0 ;0=65,1=0
P 3.5717425 2.097193 70 P 0 0 ;0=65,1=0
P 3.5717425 2.131643 46 P 0 0 ;0=42,1=0
P 3.5898425 3.7275197 39 P 0 0 ;0=35,1=0
P 3.5898425 3.7846063 39 P 0 0 ;0=35,1=0
P 3.5898425 3.8525197 39 P 0 0 ;0=35,1=0
P 3.5898425 3.9096063 39 P 0 0 ;0=35,1=0
P 3.6179425 0.916293 69 P 0 0 ;0=64,1=0
P 3.6179425 2.486293 69 P 0 0 ;0=64,1=0
P 3.6514625 1.319633 45 P 0 0 ;0=41,1=0
P 3.6514625 1.339323 45 P 0 0 ;0=41,1=0
P 3.6514625 1.359003 45 P 0 0 ;0=41,1=0
P 3.6514625 1.378693 45 P 0 0 ;0=41,1=0
P 3.6514625 1.398373 45 P 0 0 ;0=41,1=0
P 3.6514625 1.418063 45 P 0 0 ;0=41,1=0
P 3.6514625 1.437743 45 P 0 0 ;0=41,1=0
P 3.6514625 1.457433 45 P 0 0 ;0=41,1=0
P 3.6514625 1.477113 45 P 0 0 ;0=41,1=0
P 3.6514625 1.496803 45 P 0 0 ;0=41,1=0
P 3.6514625 1.516483 45 P 0 0 ;0=41,1=0
P 3.6514625 1.536173 45 P 0 0 ;0=41,1=0
P 3.6514625 1.555853 45 P 0 0 ;0=41,1=0
P 3.6514625 1.575543 45 P 0 0 ;0=41,1=0
P 3.6514625 1.595223 45 P 0 0 ;0=41,1=0
P 3.6514625 1.614913 45 P 0 0 ;0=41,1=0
P 3.6514625 1.634593 45 P 0 0 ;0=41,1=0
P 3.6514625 1.654283 45 P 0 0 ;0=41,1=0
P 3.6514625 1.673963 45 P 0 0 ;0=41,1=0
P 3.6514625 1.693653 45 P 0 0 ;0=41,1=0
P 3.6514625 1.713333 45 P 0 0 ;0=41,1=0
P 3.6514625 1.733023 45 P 0 0 ;0=41,1=0
P 3.6514625 1.752703 45 P 0 0 ;0=41,1=0
P 3.6514625 1.772393 45 P 0 0 ;0=41,1=0
P 3.6514625 1.792073 45 P 0 0 ;0=41,1=0
P 3.6514625 1.811763 45 P 0 0 ;0=41,1=0
P 3.6514625 1.831443 45 P 0 0 ;0=41,1=0
P 3.6514625 1.851133 45 P 0 0 ;0=41,1=0
P 3.6514625 1.870813 45 P 0 0 ;0=41,1=0
P 3.6514625 1.890503 45 P 0 0 ;0=41,1=0
P 3.6514625 1.910183 45 P 0 0 ;0=41,1=0
P 3.6514625 1.929873 45 P 0 0 ;0=41,1=0
P 3.6514625 1.949553 45 P 0 0 ;0=41,1=0
P 3.6514625 1.969243 45 P 0 0 ;0=41,1=0
P 3.6514625 1.988923 45 P 0 0 ;0=41,1=0
P 3.6514625 2.008613 45 P 0 0 ;0=41,1=0
P 3.6514625 2.028293 45 P 0 0 ;0=41,1=0
P 3.6514625 2.047983 45 P 0 0 ;0=41,1=0
P 3.6514625 2.067663 45 P 0 0 ;0=41,1=0
P 3.6514625 2.087353 45 P 0 0 ;0=41,1=0
P 3.6594094 0.726063 49 P 0 0 ;0=45,1=0
P 3.6681102 3.786063 27 P 0 0 ;0=23,1=0
P 3.6681102 3.861063 27 P 0 0 ;0=23,1=0
P 3.6829133 0.636063 50 P 0 0 ;0=46,1=0
P 3.6888425 3.266567 41 P 0 0 ;0=37,1=0
P 3.6888425 3.3295591 41 P 0 0 ;0=37,1=0
P 3.6938425 3.1176299 40 P 0 0 ;0=36,1=0
P 3.6938425 3.1884961 40 P 0 0 ;0=36,1=0
P 3.6962598 4.0276378 10 P 0 0 ;0=6,1=0
P 3.6962598 4.2441732 10 P 0 0 ;0=6,1=0
P 3.7015748 3.786063 27 P 0 0 ;0=23,1=0
P 3.7015748 3.861063 27 P 0 0 ;0=23,1=0
P 3.7167716 0.636063 50 P 0 0 ;0=46,1=0
P 3.7302756 0.726063 49 P 0 0 ;0=45,1=0
P 3.7698425 3.2011339 42 P 0 0 ;0=38,1=0
P 3.7698425 3.2349922 42 P 0 0 ;0=38,1=0
P 3.772559 3.683563 15 P 0 0 ;0=11,1=0
P 3.772559 3.708563 15 P 0 0 ;0=11,1=0
P 3.772559 3.733563 15 P 0 0 ;0=11,1=0
P 3.772559 3.758563 15 P 0 0 ;0=11,1=0
P 3.772559 3.783563 15 P 0 0 ;0=11,1=0
P 3.772559 3.808563 15 P 0 0 ;0=11,1=0
P 3.772559 3.833563 15 P 0 0 ;0=11,1=0
P 3.772559 3.858563 15 P 0 0 ;0=11,1=0
P 3.7848425 4.126063 57 P 0 0 ;0=53,1=0
P 3.8084646 4.0237008 11 P 0 0 ;0=7,1=0
P 3.8399606 4.0237008 11 P 0 0 ;0=7,1=0
P 3.8714567 4.0237008 11 P 0 0 ;0=7,1=0
P 3.9029528 4.0237008 11 P 0 0 ;0=7,1=0
P 3.9114214 1.5996232 31 P 0 0 ;0=27,1=0
P 3.9114214 1.6196232 31 P 0 0 ;0=27,1=0
P 3.9114214 1.6396232 31 P 0 0 ;0=27,1=0
P 3.9114214 1.6596232 31 P 0 0 ;0=27,1=0
P 3.9114214 1.6796232 31 P 0 0 ;0=27,1=0
P 3.9114214 1.6996232 31 P 0 0 ;0=27,1=0
P 3.9114214 1.7196232 31 P 0 0 ;0=27,1=0
P 3.9114214 1.7396232 31 P 0 0 ;0=27,1=0
P 3.9114214 1.7596232 31 P 0 0 ;0=27,1=0
P 3.9114214 1.7796232 31 P 0 0 ;0=27,1=0
P 3.9344488 4.0237008 11 P 0 0 ;0=7,1=0
P 3.9580709 4.126063 57 P 0 0 ;0=53,1=0
P 3.9598425 2.7806299 40 P 0 0 ;0=36,1=0
P 3.9598425 2.8514961 40 P 0 0 ;0=36,1=0
P 3.9797272 0.8906186 62 P 0 0 ;0=57,1=0
P 3.9797272 2.4890438 62 P 0 0 ;0=57,1=0
P 3.9871259 3.683563 15 P 0 0 ;0=11,1=0
P 3.9871259 3.708563 15 P 0 0 ;0=11,1=0
P 3.9871259 3.733563 15 P 0 0 ;0=11,1=0
P 3.9871259 3.758563 15 P 0 0 ;0=11,1=0
P 3.9871259 3.783563 15 P 0 0 ;0=11,1=0
P 3.9871259 3.808563 15 P 0 0 ;0=11,1=0
P 3.9871259 3.833563 15 P 0 0 ;0=11,1=0
P 3.9871259 3.858563 15 P 0 0 ;0=11,1=0
P 4.0398425 3.029567 41 P 0 0 ;0=37,1=0
P 4.0398425 3.0925591 41 P 0 0 ;0=37,1=0
P 4.0466536 4.0276378 10 P 0 0 ;0=6,1=0
P 4.0466536 4.2441732 10 P 0 0 ;0=6,1=0
P 4.0624044 2.595343 62 P 0 0 ;0=57,1=0
P 4.0648425 2.7806299 40 P 0 0 ;0=36,1=0
P 4.0648425 2.8514961 40 P 0 0 ;0=36,1=0
P 4.0689017 1.5996232 31 P 0 0 ;0=27,1=0
P 4.0689017 1.6196232 31 P 0 0 ;0=27,1=0
P 4.0689017 1.6396232 31 P 0 0 ;0=27,1=0
P 4.0689017 1.6596232 31 P 0 0 ;0=27,1=0
P 4.0689017 1.6796232 31 P 0 0 ;0=27,1=0
P 4.0689017 1.6996232 31 P 0 0 ;0=27,1=0
P 4.0689017 1.7196232 31 P 0 0 ;0=27,1=0
P 4.0689017 1.7396232 31 P 0 0 ;0=27,1=0
P 4.0689017 1.7596232 31 P 0 0 ;0=27,1=0
P 4.0689017 1.7796232 31 P 0 0 ;0=27,1=0
P 4.1048425 3.7706299 40 P 0 0 ;0=36,1=0
P 4.1048425 3.8414961 40 P 0 0 ;0=36,1=0
P 4.1098425 3.0441338 42 P 0 0 ;0=38,1=0
P 4.1098425 3.0779921 42 P 0 0 ;0=38,1=0
P 4.1126772 3.701063 26 P 0 0 ;0=22,1=0
P 4.1498425 2.7898819 35 P 0 0 ;0=31,1=0
P 4.1498425 2.8422441 35 P 0 0 ;0=31,1=0
P 4.1505905 3.6033465 26 P 0 0 ;0=22,1=0
P 4.1648425 3.0441338 42 P 0 0 ;0=38,1=0
P 4.1648425 3.0779921 42 P 0 0 ;0=38,1=0
P 4.1670079 3.701063 26 P 0 0 ;0=22,1=0
P 4.1805146 2.595343 62 P 0 0 ;0=57,1=0
P 4.1948425 3.774567 41 P 0 0 ;0=37,1=0
P 4.1948425 3.8375591 41 P 0 0 ;0=37,1=0
P 4.2049212 3.6033465 26 P 0 0 ;0=22,1=0
P 4.2094094 3.246063 49 P 0 0 ;0=45,1=0
P 4.2198425 3.0441338 42 P 0 0 ;0=38,1=0
P 4.2198425 3.0779921 42 P 0 0 ;0=38,1=0
P 4.2348425 2.7806299 40 P 0 0 ;0=36,1=0
P 4.2348425 2.8514961 40 P 0 0 ;0=36,1=0
P 4.2748425 3.0441338 42 P 0 0 ;0=38,1=0
P 4.2748425 3.0779921 42 P 0 0 ;0=38,1=0
P 4.2755905 3.6033465 52 P 0 0 ;0=48,1=0
P 4.2802756 3.246063 49 P 0 0 ;0=45,1=0
P 4.2986248 2.595343 62 P 0 0 ;0=57,1=0
P 4.3277559 1.0074803 61 P 0 0 ;0=56,1=0
P 4.3277559 2.3074803 60 P 0 0 ;0=56,1=0
P 4.3326771 3.6033465 52 P 0 0 ;0=48,1=0
P 4.3348425 3.0441338 42 P 0 0 ;0=38,1=0
P 4.3348425 3.0779921 42 P 0 0 ;0=38,1=0
P 4.3398425 2.7806299 40 P 0 0 ;0=36,1=0
P 4.3398425 2.8514961 40 P 0 0 ;0=36,1=0
P 4.3948425 3.0441338 42 P 0 0 ;0=38,1=0
P 4.3948425 3.0779921 42 P 0 0 ;0=38,1=0
P 4.4329134 4.206063 30 P 0 0 ;0=26,1=0
P 4.4348425 2.7898819 35 P 0 0 ;0=31,1=0
P 4.4348425 2.8422441 35 P 0 0 ;0=31,1=0
P 4.4548425 3.0441338 42 P 0 0 ;0=38,1=0
P 4.4548425 3.0779921 42 P 0 0 ;0=38,1=0
P 4.5667716 4.206063 30 P 0 0 ;0=26,1=0
P 4.6526771 4.206063 26 P 0 0 ;0=22,1=0
P 4.6526772 4.121063 26 P 0 0 ;0=22,1=0
P 4.7070078 4.206063 26 P 0 0 ;0=22,1=0
P 4.7070079 4.121063 26 P 0 0 ;0=22,1=0
P 4.7277559 2.3074803 60 P 0 0 ;0=56,1=0
P 4.9094488 2.8080708 37 P 0 0 ;0=33,1=0
P 4.9094488 3.9616142 37 P 0 0 ;0=33,1=0
P 4.9277559 1.0074803 60 P 0 0 ;0=56,1=0
P 4.9277559 2.3074803 60 P 0 0 ;0=56,1=0
P 4.9579134 4.206063 30 P 0 0 ;0=26,1=0
P 5.0917716 4.206063 30 P 0 0 ;0=26,1=0
P 5.1277559 1.0074803 60 P 0 0 ;0=56,1=0
P 5.1277559 2.3074803 60 P 0 0 ;0=56,1=0
P 5.2126771 4.206063 26 P 0 0 ;0=22,1=0
P 5.2126772 4.126063 26 P 0 0 ;0=22,1=0
P 5.2670078 4.206063 26 P 0 0 ;0=22,1=0
P 5.2670079 4.126063 26 P 0 0 ;0=22,1=0
P 5.3277559 1.0074803 60 P 0 0 ;0=56,1=0
P 5.3277559 2.3074803 60 P 0 0 ;0=56,1=0
P 5.5781524 0.8906186 62 P 0 0 ;0=57,1=0
P 5.5781524 1.6898312 62 P 0 0 ;0=57,1=0
P 5.5781524 2.4890438 62 P 0 0 ;0=57,1=0
P 5.6344488 3.359252 50 P 0 0 ;0=46,1=0
P 5.6683071 3.359252 50 P 0 0 ;0=46,1=0
P 5.7234252 3.8444882 63 P 0 0 ;0=58,1=0
P 5.7234252 4.0255906 63 P 0 0 ;0=58,1=0
P 5.7411417 3.3612205 49 P 0 0 ;0=45,1=0
P 5.8120079 3.3612205 49 P 0 0 ;0=45,1=0
P 5.8879921 3.701063 17 P 0 0 ;0=13,1=0
P 5.9348031 3.9379527 64 P 0 0 ;0=59,1=0
P 6.0048425 2.3388977 53 P 0 0 ;0=49,1=0
P 6.0048425 2.3932284 53 P 0 0 ;0=49,1=0
P 6.0316929 3.701063 17 P 0 0 ;0=13,1=0
P 6.0356772 3.556063 26 P 0 0 ;0=22,1=0
P 6.0648425 2.3441339 42 P 0 0 ;0=38,1=0
P 6.0648425 2.3779922 42 P 0 0 ;0=38,1=0
P 6.0900079 3.556063 26 P 0 0 ;0=22,1=0
P 6.0933464 2.171063 51 P 0 0 ;0=47,1=0
P 6.1198425 3.8198425 66 P 0 0 ;0=61,1=0
P 6.1198425 4.056063 65 P 0 0 ;0=60,1=0
P 6.1228425 2.4338976 53 P 0 0 ;0=49,1=0
P 6.1228425 2.4882283 53 P 0 0 ;0=49,1=0
P 6.1563385 2.171063 51 P 0 0 ;0=47,1=0
P 6.1574016 2.241063 16 P 0 0 ;0=12,1=0
P 6.1574016 2.291063 16 P 0 0 ;0=12,1=0
P 6.1574016 2.341063 16 P 0 0 ;0=12,1=0
P 6.1574016 2.391063 16 P 0 0 ;0=12,1=0
P 6.1979921 3.701063 17 P 0 0 ;0=13,1=0
P 6.2029921 3.566063 17 P 0 0 ;0=13,1=0
P 6.2348425 2.1288977 53 P 0 0 ;0=49,1=0
P 6.2348425 2.1832284 53 P 0 0 ;0=49,1=0
P 6.253937 2.7559055 40 P 0 0 ;0=36,1=0
P 6.253937 2.8267717 40 P 0 0 ;0=36,1=0
P 6.3126772 2.451063 26 P 0 0 ;0=22,1=0
P 6.3198425 1.4601181 36 P 0 0 ;0=32,1=0
P 6.3198425 1.8420079 36 P 0 0 ;0=32,1=0
P 6.3279134 2.501063 50 P 0 0 ;0=46,1=0
P 6.3279134 2.556063 50 P 0 0 ;0=46,1=0
P 6.3279134 2.611063 50 P 0 0 ;0=46,1=0
P 6.3279134 2.656063 50 P 0 0 ;0=46,1=0
P 6.3348425 2.1106299 40 P 0 0 ;0=36,1=0
P 6.3348425 2.1814961 40 P 0 0 ;0=36,1=0
P 6.3416929 3.701063 17 P 0 0 ;0=13,1=0
P 6.3466929 3.566063 17 P 0 0 ;0=13,1=0
P 6.3522834 2.241063 16 P 0 0 ;0=12,1=0
P 6.3522834 2.291063 16 P 0 0 ;0=12,1=0
P 6.3522834 2.341063 16 P 0 0 ;0=12,1=0
P 6.3522834 2.391063 16 P 0 0 ;0=12,1=0
P 6.3617717 2.501063 50 P 0 0 ;0=46,1=0
P 6.3617717 2.556063 50 P 0 0 ;0=46,1=0
P 6.3617717 2.611063 50 P 0 0 ;0=46,1=0
P 6.3617717 2.656063 50 P 0 0 ;0=46,1=0
P 6.3670079 2.451063 26 P 0 0 ;0=22,1=0
P 6.3720472 2.7559055 40 P 0 0 ;0=36,1=0
P 6.3720472 2.8267717 40 P 0 0 ;0=36,1=0
P 6.3883268 3.1524803 32 P 0 0 ;0=28,1=0
P 6.3883268 3.1721654 32 P 0 0 ;0=28,1=0
P 6.3883268 3.1918504 32 P 0 0 ;0=28,1=0
P 6.3883268 3.2115354 32 P 0 0 ;0=28,1=0
P 6.3883268 3.2312205 32 P 0 0 ;0=28,1=0
P 6.3883268 3.2509055 32 P 0 0 ;0=28,1=0
P 6.3883268 3.2705906 32 P 0 0 ;0=28,1=0
P 6.3883268 3.2902756 32 P 0 0 ;0=28,1=0
P 6.3883268 3.3099606 32 P 0 0 ;0=28,1=0
P 6.3883268 3.3296457 32 P 0 0 ;0=28,1=0
P 6.4203149 3.1500197 33 P 0 0 ;0=29,1=0
P 6.4203149 3.3321063 33 P 0 0 ;0=29,1=0
P 6.4394094 3.071063 49 P 0 0 ;0=45,1=0
P 6.44 3.1500197 33 P 0 0 ;0=29,1=0
P 6.44 3.3321063 33 P 0 0 ;0=29,1=0
P 6.459685 3.3321063 33 P 0 0 ;0=29,1=0
P 6.4598425 3.1500197 33 P 0 0 ;0=29,1=0
P 6.4698425 2.2395669 41 P 0 0 ;0=37,1=0
P 6.4698425 2.302559 41 P 0 0 ;0=37,1=0
P 6.4793701 3.1500197 33 P 0 0 ;0=29,1=0
P 6.4793701 3.3321063 33 P 0 0 ;0=29,1=0
P 6.5102756 3.071063 49 P 0 0 ;0=45,1=0
P 6.5113582 3.1524803 32 P 0 0 ;0=28,1=0
P 6.5113582 3.1721654 32 P 0 0 ;0=28,1=0
P 6.5113582 3.1918504 32 P 0 0 ;0=28,1=0
P 6.5113582 3.2115354 32 P 0 0 ;0=28,1=0
P 6.5113582 3.2312205 32 P 0 0 ;0=28,1=0
P 6.5113582 3.2509055 32 P 0 0 ;0=28,1=0
P 6.5113582 3.2705906 32 P 0 0 ;0=28,1=0
P 6.5113582 3.2902756 32 P 0 0 ;0=28,1=0
P 6.5113582 3.3099606 32 P 0 0 ;0=28,1=0
P 6.5113582 3.3296457 32 P 0 0 ;0=28,1=0
P 6.5198425 1.954567 41 P 0 0 ;0=37,1=0
P 6.5198425 2.0175591 41 P 0 0 ;0=37,1=0
P 6.5694882 3.5895276 63 P 0 0 ;0=68,1=0
P 6.5694882 3.806063 63 P 0 0 ;0=68,1=0
P 6.5694882 4.0934646 73 P 0 0 ;0=69,1=0
P 6.5848425 3.0391338 42 P 0 0 ;0=38,1=0
P 6.5848425 3.0729921 42 P 0 0 ;0=38,1=0
P 6.6048425 3.1295669 41 P 0 0 ;0=37,1=0
P 6.6048425 3.192559 41 P 0 0 ;0=37,1=0
P 6.6048425 3.264567 41 P 0 0 ;0=37,1=0
P 6.6048425 3.3275591 41 P 0 0 ;0=37,1=0
P 6.6294094 1.421063 49 P 0 0 ;0=45,1=0
P 6.6294094 1.531063 49 P 0 0 ;0=45,1=0
P 6.6374016 1.881063 16 P 0 0 ;0=12,1=0
P 6.6374016 1.931063 16 P 0 0 ;0=12,1=0
P 6.6374016 1.981063 16 P 0 0 ;0=12,1=0
P 6.6374016 2.031063 16 P 0 0 ;0=12,1=0
P 6.6429133 1.611063 50 P 0 0 ;0=46,1=0
P 6.6429133 1.671063 50 P 0 0 ;0=46,1=0
P 6.6429133 1.721063 50 P 0 0 ;0=46,1=0
P 6.6429133 1.776063 50 P 0 0 ;0=46,1=0
P 6.6598425 2.0956299 40 P 0 0 ;0=36,1=0
P 6.6598425 2.1664961 40 P 0 0 ;0=36,1=0
P 6.6767716 1.611063 50 P 0 0 ;0=46,1=0
P 6.6767716 1.671063 50 P 0 0 ;0=46,1=0
P 6.6767716 1.721063 50 P 0 0 ;0=46,1=0
P 6.6767716 1.776063 50 P 0 0 ;0=46,1=0
P 6.6798425 2.4201181 36 P 0 0 ;0=32,1=0
P 6.6798425 2.8020079 36 P 0 0 ;0=32,1=0
P 6.7002756 1.421063 49 P 0 0 ;0=45,1=0
P 6.7002756 1.531063 49 P 0 0 ;0=45,1=0
P 6.7265748 3.1680709 18 P 0 0 ;0=14,1=0
P 6.7265748 3.2940551 18 P 0 0 ;0=14,1=0
P 6.7276771 1.816063 26 P 0 0 ;0=22,1=0
P 6.7348425 3.5895276 63 P 0 0 ;0=68,1=0
P 6.7348425 3.806063 63 P 0 0 ;0=68,1=0
P 6.7498425 2.0888976 53 P 0 0 ;0=49,1=0
P 6.7498425 2.1432283 53 P 0 0 ;0=49,1=0
P 6.7820078 1.816063 26 P 0 0 ;0=22,1=0
P 6.8322834 1.881063 16 P 0 0 ;0=12,1=0
P 6.8322834 1.931063 16 P 0 0 ;0=12,1=0
P 6.8322834 1.981063 16 P 0 0 ;0=12,1=0
P 6.8322834 2.031063 16 P 0 0 ;0=12,1=0
P 6.8426771 1.816063 26 P 0 0 ;0=22,1=0
P 6.8433465 2.096063 51 P 0 0 ;0=47,1=0
P 6.8970078 1.816063 26 P 0 0 ;0=22,1=0
P 6.9001969 3.5895276 63 P 0 0 ;0=68,1=0
P 6.9001969 3.806063 63 P 0 0 ;0=68,1=0
P 6.9001969 4.0934646 73 P 0 0 ;0=67,1=0
P 6.9063386 2.096063 51 P 0 0 ;0=47,1=0
P 6.9398425 1.8891338 42 P 0 0 ;0=38,1=0
P 6.9398425 1.9229921 42 P 0 0 ;0=38,1=0
P 6.9431102 3.1680709 18 P 0 0 ;0=14,1=0
P 6.9431102 3.2940551 18 P 0 0 ;0=14,1=0
P 7.0098425 1.8838977 53 P 0 0 ;0=49,1=0
P 7.0098425 1.9382284 53 P 0 0 ;0=49,1=0
P 0.149508 2.830047 76 P 0 0 ;0=72,1=1
P 0.149508 3.853669 76 P 0 0 ;0=72,1=1
P 0.6538425 1.551063 75 P 0 0 ;0=71,1=1
P 0.6539669 2.5938902 75 P 0 0 ;0=71,1=1
P 0.6548425 0.790063 75 P 0 0 ;0=71,1=1
P 0.6548425 1.314063 75 P 0 0 ;0=71,1=1
P 0.6548425 1.839063 75 P 0 0 ;0=71,1=1
P 0.6548425 2.073063 75 P 0 0 ;0=71,1=1
P 0.6548425 2.365063 75 P 0 0 ;0=71,1=1
P 0.6558425 1.028063 75 P 0 0 ;0=71,1=1
P 0.9370078 2.3179133 75 P 0 0 ;0=71,1=1
P 0.988189 1.7175197 75 P 0 0 ;0=71,1=1
P 0.9901575 0.6870079 75 P 0 0 ;0=71,1=1
P 0.996063 1.1870079 75 P 0 0 ;0=71,1=1
P 0.9968357 2.256036 75 P 0 0 ;0=71,1=1
P 1.0048425 0.906063 75 P 0 0 ;0=71,1=1
P 1.0088425 1.430063 75 P 0 0 ;0=71,1=1
P 1.0098425 1.956063 75 P 0 0 ;0=71,1=1
P 1.0208425 2.481063 75 P 0 0 ;0=71,1=1
P 1.2428425 1.472063 75 P 0 0 ;0=71,1=1
P 1.2488425 2.000063 75 P 0 0 ;0=71,1=1
P 1.2568425 0.942063 75 P 0 0 ;0=71,1=1
P 1.2618425 2.482063 75 P 0 0 ;0=71,1=1
P 1.2948425 4.256063 75 P 0 0 ;0=71,1=1
P 1.3454724 4.1751969 75 P 0 0 ;0=71,1=1
P 1.3937008 1.8169291 75 P 0 0 ;0=71,1=1
P 1.4084645 3.980315 75 P 0 0 ;0=71,1=1
P 1.4408425 3.557063 75 P 0 0 ;0=71,1=1
P 1.4598425 3.147063 75 P 0 0 ;0=71,1=1
P 1.5498425 3.621063 75 P 0 0 ;0=71,1=1
P 1.5578425 4.229063 75 P 0 0 ;0=71,1=1
P 1.5679134 1.2854331 75 P 0 0 ;0=71,1=1
P 1.5682025 2.067703 75 P 0 0 ;0=71,1=1
P 1.5698819 4.1712599 75 P 0 0 ;0=71,1=1
P 1.5748425 3.596063 75 P 0 0 ;0=71,1=1
P 1.6198425 2.121063 75 P 0 0 ;0=71,1=1
P 1.6708425 1.595063 75 P 0 0 ;0=71,1=1
P 1.6708425 1.694063 75 P 0 0 ;0=71,1=1
P 1.6718425 1.399063 75 P 0 0 ;0=71,1=1
P 1.6718425 1.497063 75 P 0 0 ;0=71,1=1
P 1.6718425 1.792063 75 P 0 0 ;0=71,1=1
P 1.6748425 1.989063 75 P 0 0 ;0=71,1=1
P 1.6758425 1.891063 75 P 0 0 ;0=71,1=1
P 1.6918425 4.079063 75 P 0 0 ;0=71,1=1
P 1.7148425 1.595063 75 P 0 0 ;0=71,1=1
P 1.7168425 1.399063 75 P 0 0 ;0=71,1=1
P 1.7188425 1.497063 75 P 0 0 ;0=71,1=1
P 1.7188425 1.792063 75 P 0 0 ;0=71,1=1
P 1.7198425 1.536063 75 P 0 0 ;0=71,1=1
P 1.7218425 1.694063 75 P 0 0 ;0=71,1=1
P 1.7218425 1.890063 75 P 0 0 ;0=71,1=1
P 1.7218425 1.989063 75 P 0 0 ;0=71,1=1
P 1.7268425 4.329374 75 P 0 0 ;0=71,1=1
P 1.7498425 4.110063 75 P 0 0 ;0=71,1=1
P 1.7548425 2.126063 75 P 0 0 ;0=71,1=1
P 1.7548425 3.661063 75 P 0 0 ;0=71,1=1
P 1.7798425 4.156063 75 P 0 0 ;0=71,1=1
P 1.7888425 4.329374 75 P 0 0 ;0=71,1=1
P 1.7978425 0.355063 75 P 0 0 ;0=71,1=1
P 1.7982283 1.3041339 75 P 0 0 ;0=71,1=1
P 1.8227825 1.674003 75 P 0 0 ;0=71,1=1
P 1.8326771 0.2559055 75 P 0 0 ;0=71,1=1
P 1.8326771 0.2874016 75 P 0 0 ;0=71,1=1
P 1.8498425 3.701063 75 P 0 0 ;0=71,1=1
P 1.8523622 0.2559055 75 P 0 0 ;0=71,1=1
P 1.8523622 0.2874016 75 P 0 0 ;0=71,1=1
P 1.8720472 0.2559055 75 P 0 0 ;0=71,1=1
P 1.8720472 0.2874016 75 P 0 0 ;0=71,1=1
P 1.8799377 1.811803 75 P 0 0 ;0=71,1=1
P 1.8848425 2.071063 75 P 0 0 ;0=71,1=1
P 1.8848425 3.601063 75 P 0 0 ;0=71,1=1
P 1.8938425 1.693063 75 P 0 0 ;0=71,1=1
P 1.8973025 1.516523 75 P 0 0 ;0=71,1=1
P 1.9038425 4.018063 75 P 0 0 ;0=71,1=1
P 1.9161425 0.244763 75 P 0 0 ;0=71,1=1
P 2.0048425 1.336063 75 P 0 0 ;0=71,1=1
P 2.0048425 3.816063 75 P 0 0 ;0=71,1=1
P 2.0288425 1.361663 75 P 0 0 ;0=71,1=1
P 2.0298425 3.836063 75 P 0 0 ;0=71,1=1
P 2.0348425 0.246063 75 P 0 0 ;0=71,1=1
P 2.0598425 1.386063 75 P 0 0 ;0=71,1=1
P 2.0598425 3.871063 75 P 0 0 ;0=71,1=1
P 2.0767716 0.2559055 75 P 0 0 ;0=71,1=1
P 2.0767716 0.2874016 75 P 0 0 ;0=71,1=1
P 2.0838425 1.411663 75 P 0 0 ;0=71,1=1
P 2.0848425 3.896063 75 P 0 0 ;0=71,1=1
P 2.1122047 0.2559055 75 P 0 0 ;0=71,1=1
P 2.1122047 0.2874016 75 P 0 0 ;0=71,1=1
P 2.1398425 3.611063 75 P 0 0 ;0=71,1=1
P 2.1398425 3.738063 75 P 0 0 ;0=71,1=1
P 2.1460663 4.1037909 75 P 0 0 ;0=71,1=1
P 2.1468425 2.753063 75 P 0 0 ;0=71,1=1
P 2.1515748 0.2559055 75 P 0 0 ;0=71,1=1
P 2.1515748 0.2874016 75 P 0 0 ;0=71,1=1
P 2.2058425 3.200063 75 P 0 0 ;0=71,1=1
P 2.2068425 1.298063 75 P 0 0 ;0=71,1=1
P 2.2317425 2.584163 75 P 0 0 ;0=71,1=1
P 2.2348425 3.506063 75 P 0 0 ;0=71,1=1
P 2.2523425 2.613563 75 P 0 0 ;0=71,1=1
P 2.2538425 2.279063 75 P 0 0 ;0=71,1=1
P 2.253937 4.0866142 75 P 0 0 ;0=71,1=1
P 2.2548425 3.536063 75 P 0 0 ;0=71,1=1
P 2.2588425 3.741063 75 P 0 0 ;0=71,1=1
P 2.2598425 3.261063 75 P 0 0 ;0=71,1=1
P 2.2720325 2.463873 75 P 0 0 ;0=71,1=1
P 2.2748425 1.506063 75 P 0 0 ;0=71,1=1
P 2.2908425 4.217063 75 P 0 0 ;0=71,1=1
P 2.2998425 1.916063 75 P 0 0 ;0=71,1=1
P 2.3098425 0.246063 75 P 0 0 ;0=71,1=1
P 2.3114125 1.0900094 75 P 0 0 ;0=71,1=1
P 2.3118425 0.934063 75 P 0 0 ;0=71,1=1
P 2.3215354 2.586063 75 P 0 0 ;0=71,1=1
P 2.3215354 3.361063 75 P 0 0 ;0=71,1=1
P 2.3308425 2.215063 75 P 0 0 ;0=71,1=1
P 2.3503937 0.4055118 75 P 0 0 ;0=71,1=1
P 2.3533464 4.0177165 75 P 0 0 ;0=71,1=1
P 2.3848425 1.941063 75 P 0 0 ;0=71,1=1
P 2.3897638 0.4055118 75 P 0 0 ;0=71,1=1
P 2.3898425 3.481063 75 P 0 0 ;0=71,1=1
P 2.394685 2.7204724 75 P 0 0 ;0=71,1=1
P 2.4048425 2.412063 75 P 0 0 ;0=71,1=1
P 2.4098325 0.932053 75 P 0 0 ;0=71,1=1
P 2.4098325 1.088053 75 P 0 0 ;0=71,1=1
P 2.4098425 1.967063 75 P 0 0 ;0=71,1=1
P 2.4098425 2.283063 75 P 0 0 ;0=71,1=1
P 2.4098425 2.314063 75 P 0 0 ;0=71,1=1
P 2.4098425 2.579063 75 P 0 0 ;0=71,1=1
P 2.4133858 0.2795276 75 P 0 0 ;0=71,1=1
P 2.4138425 3.295063 75 P 0 0 ;0=71,1=1
P 2.4140551 3.1998504 75 P 0 0 ;0=71,1=1
P 2.4187174 3.1185066 75 P 0 0 ;0=71,1=1
P 2.4192759 2.7886295 75 P 0 0 ;0=71,1=1
P 2.4291925 2.621063 75 P 0 0 ;0=71,1=1
P 2.4348425 3.546063 75 P 0 0 ;0=71,1=1
P 2.4448819 0.2795276 75 P 0 0 ;0=71,1=1
P 2.4468425 1.437063 75 P 0 0 ;0=71,1=1
P 2.4470546 0.2425914 75 P 0 0 ;0=71,1=1
P 2.4508425 2.282063 75 P 0 0 ;0=71,1=1
P 2.462374 3.1722441 75 P 0 0 ;0=71,1=1
P 2.4698827 0.4109883 75 P 0 0 ;0=71,1=1
P 2.4738425 2.980063 75 P 0 0 ;0=71,1=1
P 2.4758425 2.291063 75 P 0 0 ;0=71,1=1
P 2.4758425 2.456063 75 P 0 0 ;0=71,1=1
P 2.4788425 0.937063 75 P 0 0 ;0=71,1=1
P 2.4888425 2.413063 75 P 0 0 ;0=71,1=1
P 2.4948425 2.661063 75 P 0 0 ;0=71,1=1
P 2.4948425 2.696063 75 P 0 0 ;0=71,1=1
P 2.4998425 2.236063 75 P 0 0 ;0=71,1=1
P 2.5028425 1.316063 75 P 0 0 ;0=71,1=1
P 2.5082625 0.931483 75 P 0 0 ;0=71,1=1
P 2.5088425 1.090063 75 P 0 0 ;0=71,1=1
P 2.511811 0.4055118 75 P 0 0 ;0=71,1=1
P 2.5258425 2.463063 75 P 0 0 ;0=71,1=1
P 2.531398 2.830047 76 P 0 0 ;0=72,1=1
P 2.531398 3.853669 76 P 0 0 ;0=72,1=1
P 2.5460625 0.244843 75 P 0 0 ;0=71,1=1
P 2.5498425 1.755063 75 P 0 0 ;0=71,1=1
P 2.5708425 4.283063 75 P 0 0 ;0=71,1=1
P 2.5758425 2.412063 75 P 0 0 ;0=71,1=1
P 2.5787402 0.2795276 75 P 0 0 ;0=71,1=1
P 2.5798425 1.790063 75 P 0 0 ;0=71,1=1
P 2.5798425 2.281063 75 P 0 0 ;0=71,1=1
P 2.5798425 3.486063 75 P 0 0 ;0=71,1=1
P 2.5818425 2.308063 75 P 0 0 ;0=71,1=1
P 2.5868425 2.569063 75 P 0 0 ;0=71,1=1
P 2.5908425 3.288063 75 P 0 0 ;0=71,1=1
P 2.5918425 3.1862205 75 P 0 0 ;0=71,1=1
P 2.5984252 0.7952756 75 P 0 0 ;0=71,1=1
P 2.5998425 2.436063 75 P 0 0 ;0=71,1=1
P 2.6048425 1.734063 75 P 0 0 ;0=71,1=1
P 2.6066825 0.931903 75 P 0 0 ;0=71,1=1
P 2.6068425 1.091063 75 P 0 0 ;0=71,1=1
P 2.6102362 0.2795276 75 P 0 0 ;0=71,1=1
P 2.6220472 0.976378 75 P 0 0 ;0=71,1=1
P 2.6248425 2.461063 75 P 0 0 ;0=71,1=1
P 2.6259843 0.7952756 75 P 0 0 ;0=71,1=1
P 2.6268425 1.770063 75 P 0 0 ;0=71,1=1
P 2.6318425 2.876063 75 P 0 0 ;0=71,1=1
P 2.6348425 3.406063 75 P 0 0 ;0=71,1=1
P 2.636874 0.2479055 75 P 0 0 ;0=71,1=1
P 2.6438425 1.616063 75 P 0 0 ;0=71,1=1
P 2.6458425 2.274063 75 P 0 0 ;0=71,1=1
P 2.6496063 0.976378 75 P 0 0 ;0=71,1=1
P 2.6653543 0.4055118 75 P 0 0 ;0=71,1=1
P 2.6653543 0.7952756 75 P 0 0 ;0=71,1=1
P 2.6658425 1.092063 75 P 0 0 ;0=71,1=1
P 2.6658425 2.291063 75 P 0 0 ;0=71,1=1
P 2.6668425 1.640063 75 P 0 0 ;0=71,1=1
P 2.6748425 3.501063 75 P 0 0 ;0=71,1=1
P 2.6798425 3.661063 75 P 0 0 ;0=71,1=1
P 2.6811024 0.976378 75 P 0 0 ;0=71,1=1
P 2.6858425 2.311063 75 P 0 0 ;0=71,1=1
P 2.6858425 2.568063 75 P 0 0 ;0=71,1=1
P 2.6929134 0.7952756 75 P 0 0 ;0=71,1=1
P 2.6929134 2.7214567 75 P 0 0 ;0=71,1=1
P 2.6948425 1.481063 75 P 0 0 ;0=71,1=1
P 2.7028425 2.289063 75 P 0 0 ;0=71,1=1
P 2.7047244 0.4055118 75 P 0 0 ;0=71,1=1
P 2.7086614 0.976378 75 P 0 0 ;0=71,1=1
P 2.7198425 1.591063 75 P 0 0 ;0=71,1=1
P 2.7224094 3.7860709 75 P 0 0 ;0=71,1=1
P 2.7244825 1.093063 75 P 0 0 ;0=71,1=1
P 2.7248425 3.521063 75 P 0 0 ;0=71,1=1
P 2.7248425 3.729063 75 P 0 0 ;0=71,1=1
P 2.7268425 2.293063 75 P 0 0 ;0=71,1=1
P 2.7322835 0.7952756 75 P 0 0 ;0=71,1=1
P 2.7401575 0.976378 75 P 0 0 ;0=71,1=1
P 2.74882 0.282312 75 P 0 0 ;0=71,1=1
P 2.7598425 0.7952756 75 P 0 0 ;0=71,1=1
P 2.7677165 0.976378 75 P 0 0 ;0=71,1=1
P 2.7748425 3.566063 75 P 0 0 ;0=71,1=1
P 2.7795276 0.2795276 75 P 0 0 ;0=71,1=1
P 2.7838425 2.429063 75 P 0 0 ;0=71,1=1
P 2.7838425 2.568063 75 P 0 0 ;0=71,1=1
P 2.7841625 1.094063 75 P 0 0 ;0=71,1=1
P 2.7992126 0.7952756 75 P 0 0 ;0=71,1=1
P 2.7992126 0.976378 75 P 0 0 ;0=71,1=1
P 2.7998425 3.616063 75 P 0 0 ;0=71,1=1
P 2.7999951 0.2519685 75 P 0 0 ;0=71,1=1
P 2.8038425 2.307063 75 P 0 0 ;0=71,1=1
P 2.8218425 2.601063 75 P 0 0 ;0=71,1=1
P 2.8219832 0.4078519 75 P 0 0 ;0=71,1=1
P 2.8267717 0.7952756 75 P 0 0 ;0=71,1=1
P 2.8267717 0.976378 75 P 0 0 ;0=71,1=1
P 2.8418425 2.263063 75 P 0 0 ;0=71,1=1
P 2.8428425 1.095063 75 P 0 0 ;0=71,1=1
P 2.8543307 0.4055118 75 P 0 0 ;0=71,1=1
P 2.8608425 3.787063 75 P 0 0 ;0=71,1=1
P 2.8622047 0.7952756 75 P 0 0 ;0=71,1=1
P 2.8718425 2.297063 75 P 0 0 ;0=71,1=1
P 2.8782843 0.2495967 75 P 0 0 ;0=71,1=1
P 2.8818425 2.566063 75 P 0 0 ;0=71,1=1
P 2.8888425 4.221063 75 P 0 0 ;0=71,1=1
P 2.8937008 0.7952756 75 P 0 0 ;0=71,1=1
P 2.8948425 1.561063 75 P 0 0 ;0=71,1=1
P 2.8948425 2.431063 75 P 0 0 ;0=71,1=1
P 2.9018425 1.095063 75 P 0 0 ;0=71,1=1
P 2.9054946 0.2795104 75 P 0 0 ;0=71,1=1
P 2.9198425 1.536063 75 P 0 0 ;0=71,1=1
P 2.9208425 2.428063 75 P 0 0 ;0=71,1=1
P 2.9338425 0.953063 75 P 0 0 ;0=71,1=1
P 2.9370079 0.2795276 75 P 0 0 ;0=71,1=1
P 2.9428425 2.286063 75 P 0 0 ;0=71,1=1
P 2.9488425 2.456063 75 P 0 0 ;0=71,1=1
P 2.9574751 0.2519685 75 P 0 0 ;0=71,1=1
P 2.9588425 2.621063 75 P 0 0 ;0=71,1=1
P 2.980457 0.4091539 75 P 0 0 ;0=71,1=1
P 2.9858425 2.287063 75 P 0 0 ;0=71,1=1
P 2.9933858 3.751063 75 P 0 0 ;0=71,1=1
P 3.0148425 3.831063 75 P 0 0 ;0=71,1=1
P 3.019685 0.4055118 75 P 0 0 ;0=71,1=1
P 3.0568817 1.811803 75 P 0 0 ;0=71,1=1
P 3.0688976 3.3956693 75 P 0 0 ;0=71,1=1
P 3.0974409 0.2519685 75 P 0 0 ;0=71,1=1
P 3.1830708 3.1358268 75 P 0 0 ;0=71,1=1
P 3.1889764 3.1870079 75 P 0 0 ;0=71,1=1
P 3.1972633 1.714063 75 P 0 0 ;0=71,1=1
P 3.1978425 2.970063 75 P 0 0 ;0=71,1=1
P 3.2198425 3.806063 75 P 0 0 ;0=71,1=1
P 3.2248425 1.6613472 75 P 0 0 ;0=71,1=1
P 3.2308425 3.235063 75 P 0 0 ;0=71,1=1
P 3.2398425 3.596063 75 P 0 0 ;0=71,1=1
P 3.2528425 1.661063 75 P 0 0 ;0=71,1=1
P 3.2636972 3.3039177 75 P 0 0 ;0=71,1=1
P 3.2698425 3.788063 75 P 0 0 ;0=71,1=1
P 3.2755905 3.1417323 75 P 0 0 ;0=71,1=1
P 3.277559 2.9635827 75 P 0 0 ;0=71,1=1
P 3.2988425 1.971063 75 P 0 0 ;0=71,1=1
P 3.3028425 3.344063 75 P 0 0 ;0=71,1=1
P 3.3291721 1.826063 75 P 0 0 ;0=71,1=1
P 3.3308425 3.301063 75 P 0 0 ;0=71,1=1
P 3.3428425 2.263063 75 P 0 0 ;0=71,1=1
P 3.3448425 2.996063 75 P 0 0 ;0=71,1=1
P 3.3588425 3.448063 75 P 0 0 ;0=71,1=1
P 3.3688425 3.050063 75 P 0 0 ;0=71,1=1
P 3.3708425 2.888063 75 P 0 0 ;0=71,1=1
P 3.3748425 3.273063 75 P 0 0 ;0=71,1=1
P 3.3798425 1.336063 75 P 0 0 ;0=71,1=1
P 3.3798425 1.386063 75 P 0 0 ;0=71,1=1
P 3.3928425 1.871063 75 P 0 0 ;0=71,1=1
P 3.3948425 3.447063 75 P 0 0 ;0=71,1=1
P 3.3958425 4.222063 75 P 0 0 ;0=71,1=1
P 3.4048425 1.363323 75 P 0 0 ;0=71,1=1
P 3.4068425 1.461063 75 P 0 0 ;0=71,1=1
P 3.4072822 1.411323 75 P 0 0 ;0=71,1=1
P 3.4108425 1.7136509 75 P 0 0 ;0=71,1=1
P 3.4138425 1.573063 75 P 0 0 ;0=71,1=1
P 3.4144661 1.805063 75 P 0 0 ;0=71,1=1
P 3.4248425 3.636063 75 P 0 0 ;0=71,1=1
P 3.4368425 3.457063 75 P 0 0 ;0=71,1=1
P 3.4392507 1.870938 75 P 0 0 ;0=71,1=1
P 3.4698425 3.456063 75 P 0 0 ;0=71,1=1
P 3.4918425 3.103063 75 P 0 0 ;0=71,1=1
P 3.4918425 3.297063 75 P 0 0 ;0=71,1=1
P 3.4988425 2.341063 75 P 0 0 ;0=71,1=1
P 3.5048425 4.086063 75 P 0 0 ;0=71,1=1
P 3.5298425 3.481063 75 P 0 0 ;0=71,1=1
P 3.5318425 3.660063 75 P 0 0 ;0=71,1=1
P 3.5398425 3.806063 75 P 0 0 ;0=71,1=1
P 3.542865 3.3190405 75 P 0 0 ;0=71,1=1
P 3.5498425 1.413063 75 P 0 0 ;0=71,1=1
P 3.5498425 1.441063 75 P 0 0 ;0=71,1=1
P 3.5548425 1.841063 75 P 0 0 ;0=71,1=1
P 3.5548425 1.891063 75 P 0 0 ;0=71,1=1
P 3.5548425 1.941063 75 P 0 0 ;0=71,1=1
P 3.5548425 1.991063 75 P 0 0 ;0=71,1=1
P 3.5718425 2.033063 75 P 0 0 ;0=71,1=1
P 3.5718425 2.058063 75 P 0 0 ;0=71,1=1
P 3.5898425 1.711063 75 P 0 0 ;0=71,1=1
P 3.5908425 1.662063 75 P 0 0 ;0=71,1=1
P 3.5948425 1.514063 75 P 0 0 ;0=71,1=1
P 3.6038425 0.682063 75 P 0 0 ;0=71,1=1
P 3.6228425 3.486063 75 P 0 0 ;0=71,1=1
P 3.6238425 2.587063 75 P 0 0 ;0=71,1=1
P 3.6428425 0.636063 75 P 0 0 ;0=71,1=1
P 3.6538425 3.293063 75 P 0 0 ;0=71,1=1
P 3.6998425 3.751063 75 P 0 0 ;0=71,1=1
P 3.6998425 3.836063 75 P 0 0 ;0=71,1=1
P 3.7178425 3.072063 75 P 0 0 ;0=71,1=1
P 3.7188425 1.713063 75 P 0 0 ;0=71,1=1
P 3.7198425 1.766063 75 P 0 0 ;0=71,1=1
P 3.7198425 1.921063 75 P 0 0 ;0=71,1=1
P 3.7198425 1.996063 75 P 0 0 ;0=71,1=1
P 3.7248425 1.675063 75 P 0 0 ;0=71,1=1
P 3.7328425 1.418063 75 P 0 0 ;0=71,1=1
P 3.7448425 3.261063 75 P 0 0 ;0=71,1=1
P 3.7448425 3.342063 75 P 0 0 ;0=71,1=1
P 3.7738632 1.6661021 75 P 0 0 ;0=71,1=1
P 3.7778425 4.023063 75 P 0 0 ;0=71,1=1
P 3.7998425 3.201063 75 P 0 0 ;0=71,1=1
P 3.8038425 1.691063 75 P 0 0 ;0=71,1=1
P 3.8048425 1.840063 75 P 0 0 ;0=71,1=1
P 3.8068425 3.235063 75 P 0 0 ;0=71,1=1
P 3.8298425 3.176063 75 P 0 0 ;0=71,1=1
P 3.8298425 3.806063 75 P 0 0 ;0=71,1=1
P 3.8308425 3.762063 75 P 0 0 ;0=71,1=1
P 3.8348425 1.481063 75 P 0 0 ;0=71,1=1
P 3.8548425 3.151063 75 P 0 0 ;0=71,1=1
P 3.8648425 1.511063 75 P 0 0 ;0=71,1=1
P 3.8808425 3.109063 75 P 0 0 ;0=71,1=1
P 3.8948425 1.566063 75 P 0 0 ;0=71,1=1
P 3.9248425 1.536063 75 P 0 0 ;0=71,1=1
P 3.9398425 3.121063 75 P 0 0 ;0=71,1=1
P 3.9448425 1.816063 75 P 0 0 ;0=71,1=1
P 3.9608425 2.724063 75 P 0 0 ;0=71,1=1
P 3.9688425 1.671063 75 P 0 0 ;0=71,1=1
P 3.9698425 1.552063 75 P 0 0 ;0=71,1=1
P 3.9948425 1.551063 75 P 0 0 ;0=71,1=1
P 3.9968425 1.711063 75 P 0 0 ;0=71,1=1
P 4.0348425 1.546063 75 P 0 0 ;0=71,1=1
P 4.0398425 2.406063 75 P 0 0 ;0=71,1=1
P 4.0398425 3.784063 75 P 0 0 ;0=71,1=1
P 4.0498425 3.665063 75 P 0 0 ;0=71,1=1
P 4.0648425 1.511063 75 P 0 0 ;0=71,1=1
P 4.0648425 1.796063 75 P 0 0 ;0=71,1=1
P 4.0648425 2.722063 75 P 0 0 ;0=71,1=1
P 4.0688425 3.135063 75 P 0 0 ;0=71,1=1
P 4.0858425 3.892063 75 P 0 0 ;0=71,1=1
P 4.1148425 3.135063 75 P 0 0 ;0=71,1=1
P 4.1203866 3.5941508 75 P 0 0 ;0=71,1=1
P 4.1318425 1.686063 75 P 0 0 ;0=71,1=1
P 4.1348425 1.651063 75 P 0 0 ;0=71,1=1
P 4.1348425 1.751063 75 P 0 0 ;0=71,1=1
P 4.1513063 1.6236232 75 P 0 0 ;0=71,1=1
P 4.1528425 3.135063 75 P 0 0 ;0=71,1=1
P 4.1798425 1.601063 75 P 0 0 ;0=71,1=1
P 4.1948425 3.884063 75 P 0 0 ;0=71,1=1
P 4.2088425 3.135063 75 P 0 0 ;0=71,1=1
P 4.2348425 2.725063 75 P 0 0 ;0=71,1=1
P 4.2548425 3.776063 75 P 0 0 ;0=71,1=1
P 4.2728425 3.135063 75 P 0 0 ;0=71,1=1
P 4.3338425 3.135063 75 P 0 0 ;0=71,1=1
P 4.3398425 2.725063 75 P 0 0 ;0=71,1=1
P 4.3878425 4.206063 75 P 0 0 ;0=71,1=1
P 4.4318425 3.135063 75 P 0 0 ;0=71,1=1
P 4.4778425 3.135063 75 P 0 0 ;0=71,1=1
P 4.5036614 2.7898819 75 P 0 0 ;0=71,1=1
P 4.7547119 4.1159324 75 P 0 0 ;0=71,1=1
P 4.7942913 2.8080709 75 P 0 0 ;0=71,1=1
P 4.9108425 4.203063 75 P 0 0 ;0=71,1=1
P 5.2670079 4.0888976 75 P 0 0 ;0=71,1=1
P 5.2748425 3.511063 75 P 0 0 ;0=71,1=1
P 5.5778425 2.214063 75 P 0 0 ;0=71,1=1
P 5.6348425 2.236063 75 P 0 0 ;0=71,1=1
P 5.6768425 3.546063 75 P 0 0 ;0=71,1=1
P 5.7338425 3.556063 75 P 0 0 ;0=71,1=1
P 5.9948425 3.552063 75 P 0 0 ;0=71,1=1
P 6.0048425 2.434063 75 P 0 0 ;0=71,1=1
P 6.0488425 2.171063 75 P 0 0 ;0=71,1=1
P 6.253937 2.9094488 75 P 0 0 ;0=71,1=1
P 6.2748425 2.391063 75 P 0 0 ;0=71,1=1
P 6.2824161 3.226063 75 P 0 0 ;0=71,1=1
P 6.2848425 2.501063 75 P 0 0 ;0=71,1=1
P 6.2948425 3.701063 75 P 0 0 ;0=71,1=1
P 6.3048425 3.121063 75 P 0 0 ;0=71,1=1
P 6.3094161 3.199063 75 P 0 0 ;0=71,1=1
P 6.3348425 3.266063 75 P 0 0 ;0=71,1=1
P 6.3398425 3.151063 75 P 0 0 ;0=71,1=1
P 6.3547483 3.3311384 75 P 0 0 ;0=71,1=1
P 6.3720472 2.9094488 75 P 0 0 ;0=71,1=1
P 6.3958425 2.111063 75 P 0 0 ;0=71,1=1
P 6.3968425 2.556063 75 P 0 0 ;0=71,1=1
P 6.3978425 2.501063 75 P 0 0 ;0=71,1=1
P 6.3978425 2.610063 75 P 0 0 ;0=71,1=1
P 6.3988425 2.453063 75 P 0 0 ;0=71,1=1
P 6.3988425 2.657063 75 P 0 0 ;0=71,1=1
P 6.4098425 3.371063 75 P 0 0 ;0=71,1=1
P 6.4248425 2.181063 75 P 0 0 ;0=71,1=1
P 6.4398425 3.191063 75 P 0 0 ;0=71,1=1
P 6.4448425 3.291063 75 P 0 0 ;0=71,1=1
P 6.4475772 3.396063 75 P 0 0 ;0=71,1=1
P 6.4568425 3.009063 75 P 0 0 ;0=71,1=1
P 6.4768425 3.231063 75 P 0 0 ;0=71,1=1
P 6.4798425 3.426063 75 P 0 0 ;0=71,1=1
P 6.5098425 3.456063 75 P 0 0 ;0=71,1=1
P 6.5488425 1.531063 75 P 0 0 ;0=71,1=1
P 6.6018425 1.777063 75 P 0 0 ;0=71,1=1
P 6.6028425 1.612063 75 P 0 0 ;0=71,1=1
P 6.6028425 1.672063 75 P 0 0 ;0=71,1=1
P 6.6028425 1.722063 75 P 0 0 ;0=71,1=1
P 6.6078425 2.176063 75 P 0 0 ;0=71,1=1
P 6.6268425 3.032063 75 P 0 0 ;0=71,1=1
P 6.6288425 1.372063 75 P 0 0 ;0=71,1=1
P 6.6476378 3.1299213 75 P 0 0 ;0=71,1=1
P 6.6488425 3.341063 75 P 0 0 ;0=71,1=1
P 6.6858425 1.828063 75 P 0 0 ;0=71,1=1
P 6.6998425 1.881063 75 P 0 0 ;0=71,1=1
P 6.8448425 1.661063 75 P 0 0 ;0=71,1=1
P 6.9498425 2.095063 75 P 0 0 ;0=71,1=1
P 6.9744094 1.9399606 75 P 0 0 ;0=71,1=1

### steps/pcb/layers/comp_+_bot/components
#
#Component attribute names
#
@0 .comp_mount_type
@1 .comp_height

# CMP 0
CMP 22 2.6628937 3.9668583 90 N U14 RCB-F9T ;0=1,1=0.0000
PRP CATEGORY 'MOD'
PRP DATE ''
PRP DESC 'MOD BLE 4.2'
PRP MAXTEMP '80C'
PRP MFG_Name 'UBLOCKS'
PRP MFG_PART_NUM 'RCB-F9T'
PRP MINTEMP '-40C'
PRP MODIFY_DATE '9/11/13'
PRP OTHER ''
PRP P1 'GPS'
PRP P2 ''
PRP P3 ''
PRP SHEETPART ''
PRP SIZE ''
PRP SUB ''
PRP Supplier_1 'Digi-Key'
PRP Supplier_Part_Number_1 '672-RCB-F9T-ND'
PRP VELENTIUM_PART_NUM '<V PART NUM>'
TOP 0 2.4223425 3.2396929 90 N 0 23 U14-0
TOP 1 2.4223425 3.0822126 90 N 0 24 U14-0
TOP 2 2.5098425 3.0428426 90 N 146 4 U14-1
TOP 3 2.3348425 3.0428426 90 N 138 4 U14-2
TOP 4 2.5098425 3.1215827 90 N 97 0 U14-3
TOP 5 2.3348425 3.1215827 90 N 101 0 U14-4
TOP 6 2.5098425 3.2003229 90 N 100 0 U14-5
TOP 7 2.3348425 3.2003229 90 N 99 0 U14-6
TOP 8 2.5098425 3.279063 90 N 98 0 U14-7
TOP 9 2.3348425 3.279063 90 N 136 16 U14-8
#
# CMP 1
CMP 7 2.3628425 2.944063 180 N C87 CAP_0805_10UF_25V ;0=1,1=0.0551
PRP CATEGORY 'CAP, CER'
PRP DATE '4/11/2006 3:37:28 PM'
PRP DESC 'CAP, CER, 10.UF, 10V, 10%, X5R, 0805'
PRP MAXTEMP '85C'
PRP MFG_Name 'TAIYO YUDEN'
PRP MFG_PART_NUM 'TMK212BBJ106KG-T'
PRP MINTEMP '-55C'
PRP MODIFY_DATE '10/23/2013'
PRP OTHER ''
PRP P1 '10%'
PRP P2 '25V'
PRP P3 'X5R'
PRP SHEETPART ''
PRP SIZE '0805'
PRP SUB ''
PRP Supplier_1 'MOUSER'
PRP Supplier_Part_Number_1 '963-TMK212BBJ106KG-T'
PRP VALENTIUM_PART_NUM '<VALENTIUM>'
PRP VALUE '10uF'
TOP 0 2.3274094 2.944063 90 N 138 2 C87-1
TOP 1 2.3982756 2.944063 90 N 136 2 C87-2
#
# CMP 2
CMP 5 2.3688425 2.854063 180 N C88 CAP_0402_0.1UF_50V ;0=1,1=0.0236
PRP CATEGORY 'CAP, CER'
PRP DATE ''
PRP DESC 'CAP, CER, 0.1UF, 50V, 10%, X7R, AEC-Q200, 0402'
PRP MAXTEMP '125C'
PRP MFG_Name 'TDK'
PRP MFG_PART_NUM 'CGA2B3X7R1H104K050BB'
PRP MINTEMP '-55C'
PRP MODIFY_DATE '10/23/2013'
PRP OTHER 'AEC-Q200'
PRP P1 '10%'
PRP P2 '50V'
PRP P3 'X7R'
PRP SHEETPART ''
PRP SIZE '0402'
PRP SUB ''
PRP Supplier_1 'Digi-Key'
PRP Supplier_Part_Number_1 '445-6899-1-ND'
PRP VALENTIUM_PART_NUM '<VALENTIUM>'
PRP VALUE '0.1UF'
TOP 0 2.3519134 2.854063 90 N 138 3 C88-1
TOP 1 2.3857717 2.854063 90 N 136 3 C88-2
#
# CMP 3
CMP 7 2.6328425 3.007063 90 N C89 CAP_0805_10UF_25V ;0=1,1=0.0551
PRP CATEGORY 'CAP, CER'
PRP DATE '4/11/2006 3:37:28 PM'
PRP DESC 'CAP, CER, 10.UF, 10V, 10%, X5R, 0805'
PRP MAXTEMP '85C'
PRP MFG_Name 'TAIYO YUDEN'
PRP MFG_PART_NUM 'TMK212BBJ106KG-T'
PRP MINTEMP '-55C'
PRP MODIFY_DATE '10/23/2013'
PRP OTHER ''
PRP P1 '10%'
PRP P2 '25V'
PRP P3 'X5R'
PRP SHEETPART ''
PRP SIZE '0805'
PRP SUB ''
PRP Supplier_1 'MOUSER'
PRP Supplier_Part_Number_1 '963-TMK212BBJ106KG-T'
PRP VALENTIUM_PART_NUM '<VALENTIUM>'
PRP VALUE '10uF'
TOP 0 2.6328425 3.0424961 180 N 146 2 C89-1
TOP 1 2.6328425 2.9716299 180 N 136 4 C89-2
#
# CMP 4
CMP 5 2.7118425 3.020063 90 N C90 CAP_0402_0.1UF_50V ;0=1,1=0.0236
PRP CATEGORY 'CAP, CER'
PRP DATE ''
PRP DESC 'CAP, CER, 0.1UF, 50V, 10%, X7R, AEC-Q200, 0402'
PRP MAXTEMP '125C'
PRP MFG_Name 'TDK'
PRP MFG_PART_NUM 'CGA2B3X7R1H104K050BB'
PRP MINTEMP '-55C'
PRP MODIFY_DATE '10/23/2013'
PRP OTHER 'AEC-Q200'
PRP P1 '10%'
PRP P2 '50V'
PRP P3 'X7R'
PRP SHEETPART ''
PRP SIZE '0402'
PRP SUB ''
PRP Supplier_1 'Digi-Key'
PRP Supplier_Part_Number_1 '445-6899-1-ND'
PRP VALENTIUM_PART_NUM '<VALENTIUM>'
PRP VALUE '0.1UF'
TOP 0 2.7118425 3.0369921 180 N 146 3 C90-1
TOP 1 2.7118425 3.0031338 180 N 136 5 C90-2
#
# CMP 5
CMP 5 3.0198425 0.346063 270 N C53 CAP_0402_0.1UF_50V ;0=1,1=0.0236
PRP CATEGORY 'CAP, CER'
PRP DATE ''
PRP DESC 'CAP, CER, 0.1UF, 50V, 10%, X7R, AEC-Q200, 0402'
PRP MAXTEMP '125C'
PRP MFG_Name 'TDK'
PRP MFG_PART_NUM 'CGA2B3X7R1H104K050BB'
PRP MINTEMP '-55C'
PRP MODIFY_DATE '10/23/2013'
PRP OTHER 'AEC-Q200'
PRP P1 '10%'
PRP P2 '50V'
PRP P3 'X7R'
PRP SHEETPART ''
PRP SIZE '0402'
PRP SUB ''
PRP Supplier_1 'Digi-Key'
PRP Supplier_Part_Number_1 '445-6899-1-ND'
PRP VALENTIUM_PART_NUM '<VALENTIUM>'
PRP VALUE '0.1UF'
TOP 0 3.0198425 0.3291339 0 N 13 0 C53-1
TOP 1 3.0198425 0.3629922 0 N 115 0 C53-2
#
# CMP 6
CMP 5 2.9798425 0.346063 270 N C52 CAP_0402_0.1UF_50V ;0=1,1=0.0236
PRP CATEGORY 'CAP, CER'
PRP DATE ''
PRP DESC 'CAP, CER, 0.1UF, 50V, 10%, X7R, AEC-Q200, 0402'
PRP MAXTEMP '125C'
PRP MFG_Name 'TDK'
PRP MFG_PART_NUM 'CGA2B3X7R1H104K050BB'
PRP MINTEMP '-55C'
PRP MODIFY_DATE '10/23/2013'
PRP OTHER 'AEC-Q200'
PRP P1 '10%'
PRP P2 '50V'
PRP P3 'X7R'
PRP SHEETPART ''
PRP SIZE '0402'
PRP SUB ''
PRP Supplier_1 'Digi-Key'
PRP Supplier_Part_Number_1 '445-6899-1-ND'
PRP VALENTIUM_PART_NUM '<VALENTIUM>'
PRP VALUE '0.1UF'
TOP 0 2.9798425 0.3291339 0 N 12 0 C52-1
TOP 1 2.9798425 0.3629922 0 N 116 0 C52-2
#
# CMP 7
CMP 5 2.8548425 0.346063 270 N C51 CAP_0402_0.1UF_50V ;0=1,1=0.0236
PRP CATEGORY 'CAP, CER'
PRP DATE ''
PRP DESC 'CAP, CER, 0.1UF, 50V, 10%, X7R, AEC-Q200, 0402'
PRP MAXTEMP '125C'
PRP MFG_Name 'TDK'
PRP MFG_PART_NUM 'CGA2B3X7R1H104K050BB'
PRP MINTEMP '-55C'
PRP MODIFY_DATE '10/23/2013'
PRP OTHER 'AEC-Q200'
PRP P1 '10%'
PRP P2 '50V'
PRP P3 'X7R'
PRP SHEETPART ''
PRP SIZE '0402'
PRP SUB ''
PRP Supplier_1 'Digi-Key'
PRP Supplier_Part_Number_1 '445-6899-1-ND'
PRP VALENTIUM_PART_NUM '<VALENTIUM>'
PRP VALUE '0.1UF'
TOP 0 2.8548425 0.3291339 0 N 11 0 C51-1
TOP 1 2.8548425 0.3629922 0 N 117 0 C51-2
#
# CMP 8
CMP 5 2.8198425 0.346063 270 N C50 CAP_0402_0.1UF_50V ;0=1,1=0.0236
PRP CATEGORY 'CAP, CER'
PRP DATE ''
PRP DESC 'CAP, CER, 0.1UF, 50V, 10%, X7R, AEC-Q200, 0402'
PRP MAXTEMP '125C'
PRP MFG_Name 'TDK'
PRP MFG_PART_NUM 'CGA2B3X7R1H104K050BB'
PRP MINTEMP '-55C'
PRP MODIFY_DATE '10/23/2013'
PRP OTHER 'AEC-Q200'
PRP P1 '10%'
PRP P2 '50V'
PRP P3 'X7R'
PRP SHEETPART ''
PRP SIZE '0402'
PRP SUB ''
PRP Supplier_1 'Digi-Key'
PRP Supplier_Part_Number_1 '445-6899-1-ND'
PRP VALENTIUM_PART_NUM '<VALENTIUM>'
PRP VALUE '0.1UF'
TOP 0 2.8198425 0.3291339 0 N 10 0 C50-1
TOP 1 2.8198425 0.3629922 0 N 118 0 C50-2
#
# CMP 9
CMP 5 2.7048425 0.346063 270 N C49 CAP_0402_0.1UF_50V ;0=1,1=0.0236
PRP CATEGORY 'CAP, CER'
PRP DATE ''
PRP DESC 'CAP, CER, 0.1UF, 50V, 10%, X7R, AEC-Q200, 0402'
PRP MAXTEMP '125C'
PRP MFG_Name 'TDK'
PRP MFG_PART_NUM 'CGA2B3X7R1H104K050BB'
PRP MINTEMP '-55C'
PRP MODIFY_DATE '10/23/2013'
PRP OTHER 'AEC-Q200'
PRP P1 '10%'
PRP P2 '50V'
PRP P3 'X7R'
PRP SHEETPART ''
PRP SIZE '0402'
PRP SUB ''
PRP Supplier_1 'Digi-Key'
PRP Supplier_Part_Number_1 '445-6899-1-ND'
PRP VALENTIUM_PART_NUM '<VALENTIUM>'
PRP VALUE '0.1UF'
TOP 0 2.7048425 0.3291339 0 N 57 0 C49-1
TOP 1 2.7048425 0.3629922 0 N 119 0 C49-2
#
# CMP 10
CMP 5 2.6648425 0.346063 270 N C48 CAP_0402_0.1UF_50V ;0=1,1=0.0236
PRP CATEGORY 'CAP, CER'
PRP DATE ''
PRP DESC 'CAP, CER, 0.1UF, 50V, 10%, X7R, AEC-Q200, 0402'
PRP MAXTEMP '125C'
PRP MFG_Name 'TDK'
PRP MFG_PART_NUM 'CGA2B3X7R1H104K050BB'
PRP MINTEMP '-55C'
PRP MODIFY_DATE '10/23/2013'
PRP OTHER 'AEC-Q200'
PRP P1 '10%'
PRP P2 '50V'
PRP P3 'X7R'
PRP SHEETPART ''
PRP SIZE '0402'
PRP SUB ''
PRP Supplier_1 'Digi-Key'
PRP Supplier_Part_Number_1 '445-6899-1-ND'
PRP VALENTIUM_PART_NUM '<VALENTIUM>'
PRP VALUE '0.1UF'
TOP 0 2.6648425 0.3291339 0 N 9 0 C48-1
TOP 1 2.6648425 0.3629922 0 N 120 0 C48-2
#
# CMP 11
CMP 5 2.5118425 0.346063 270 N C47 CAP_0402_0.1UF_50V ;0=1,1=0.0236
PRP CATEGORY 'CAP, CER'
PRP DATE ''
PRP DESC 'CAP, CER, 0.1UF, 50V, 10%, X7R, AEC-Q200, 0402'
PRP MAXTEMP '125C'
PRP MFG_Name 'TDK'
PRP MFG_PART_NUM 'CGA2B3X7R1H104K050BB'
PRP MINTEMP '-55C'
PRP MODIFY_DATE '10/23/2013'
PRP OTHER 'AEC-Q200'
PRP P1 '10%'
PRP P2 '50V'
PRP P3 'X7R'
PRP SHEETPART ''
PRP SIZE '0402'
PRP SUB ''
PRP Supplier_1 'Digi-Key'
PRP Supplier_Part_Number_1 '445-6899-1-ND'
PRP VALENTIUM_PART_NUM '<VALENTIUM>'
PRP VALUE '0.1UF'
TOP 0 2.5118425 0.3291339 0 N 8 0 C47-1
TOP 1 2.5118425 0.3629922 0 N 121 0 C47-2
#
# CMP 12
CMP 5 2.4688425 0.346063 270 N C46 CAP_0402_0.1UF_50V ;0=1,1=0.0236
PRP CATEGORY 'CAP, CER'
PRP DATE ''
PRP DESC 'CAP, CER, 0.1UF, 50V, 10%, X7R, AEC-Q200, 0402'
PRP MAXTEMP '125C'
PRP MFG_Name 'TDK'
PRP MFG_PART_NUM 'CGA2B3X7R1H104K050BB'
PRP MINTEMP '-55C'
PRP MODIFY_DATE '10/23/2013'
PRP OTHER 'AEC-Q200'
PRP P1 '10%'
PRP P2 '50V'
PRP P3 'X7R'
PRP SHEETPART ''
PRP SIZE '0402'
PRP SUB ''
PRP Supplier_1 'Digi-Key'
PRP Supplier_Part_Number_1 '445-6899-1-ND'
PRP VALENTIUM_PART_NUM '<VALENTIUM>'
PRP VALUE '0.1UF'
TOP 0 2.4688425 0.3291339 0 N 7 0 C46-1
TOP 1 2.4688425 0.3629922 0 N 122 0 C46-2
#
# CMP 13
CMP 5 2.3898425 0.346063 270 N C45 CAP_0402_0.1UF_50V ;0=1,1=0.0236
PRP CATEGORY 'CAP, CER'
PRP DATE ''
PRP DESC 'CAP, CER, 0.1UF, 50V, 10%, X7R, AEC-Q200, 0402'
PRP MAXTEMP '125C'
PRP MFG_Name 'TDK'
PRP MFG_PART_NUM 'CGA2B3X7R1H104K050BB'
PRP MINTEMP '-55C'
PRP MODIFY_DATE '10/23/2013'
PRP OTHER 'AEC-Q200'
PRP P1 '10%'
PRP P2 '50V'
PRP P3 'X7R'
PRP SHEETPART ''
PRP SIZE '0402'
PRP SUB ''
PRP Supplier_1 'Digi-Key'
PRP Supplier_Part_Number_1 '445-6899-1-ND'
PRP VALENTIUM_PART_NUM '<VALENTIUM>'
PRP VALUE '0.1UF'
TOP 0 2.3898425 0.3291339 0 N 6 0 C45-1
TOP 1 2.3898425 0.3629922 0 N 124 0 C45-2
#
# CMP 14
CMP 5 2.3498425 0.346063 270 N C44 CAP_0402_0.1UF_50V ;0=1,1=0.0236
PRP CATEGORY 'CAP, CER'
PRP DATE ''
PRP DESC 'CAP, CER, 0.1UF, 50V, 10%, X7R, AEC-Q200, 0402'
PRP MAXTEMP '125C'
PRP MFG_Name 'TDK'
PRP MFG_PART_NUM 'CGA2B3X7R1H104K050BB'
PRP MINTEMP '-55C'
PRP MODIFY_DATE '10/23/2013'
PRP OTHER 'AEC-Q200'
PRP P1 '10%'
PRP P2 '50V'
PRP P3 'X7R'
PRP SHEETPART ''
PRP SIZE '0402'
PRP SUB ''
PRP Supplier_1 'Digi-Key'
PRP Supplier_Part_Number_1 '445-6899-1-ND'
PRP VALENTIUM_PART_NUM '<VALENTIUM>'
PRP VALUE '0.1UF'
TOP 0 2.3498425 0.3291339 0 N 5 0 C44-1
TOP 1 2.3498425 0.3629922 0 N 123 0 C44-2
#

### steps/pcb/layers/comp_+_top/components
#
#Component attribute names
#
@0 .comp_mount_type
@1 .comp_height

# CMP 0
CMP 4 3.2391732 2.8149606 0 N IC? BMP388 ;0=1,1=0.0000
PRP Arrow_Part_Number 'BMP388'
PRP Arrow_Price/Stock 'https://www.arrow.com/en/products/bmp388/bosch'
PRP Datasheet_Link 'https://ae-bst.resource.bosch.com/media/_tech/media/datasheets/BST-BMP388-DS001-01.pdf'
PRP Height '0mm'
PRP Manufacturer_Name 'Bosch Sensortec'
PRP Manufacturer_Part_Number 'BMP388'
PRP Mouser_Part_Number '262-BMP388'
PRP Mouser_Price/Stock 'https://www.mouser.co.uk/ProductDetail/Bosch-Sensortec/BMP388?qs=rrS6PyfT74eIcD5Rv1Kf7A%3D%3D'
TOP 0 3.2490157 2.845 270 N 109 14 IC?-1
TOP 1 3.2293307 2.845 270 N 40 1 IC?-2
TOP 2 3.2091732 2.8346456 0 N 136 164 IC?-3
TOP 3 3.2091732 2.8149606 0 N 39 1 IC?-4
TOP 4 3.2091732 2.7952756 0 N 0 219 IC?-5
TOP 5 3.2293307 2.7849212 270 N 109 15 IC?-6
TOP 6 3.2490157 2.7849212 270 N 0 220 IC?-7
TOP 7 3.2691732 2.7952756 0 N 136 165 IC?-8
TOP 8 3.2691732 2.8149606 0 N 136 166 IC?-9
TOP 9 3.2691732 2.8346456 0 N 109 16 IC?-10
#
# CMP 1
CMP 15 0.9311023 0.7185039 180 N R36 MAC10M ;0=1,1=0.0354
PRP LatestRevisionDate '29-May-2009'
PRP LatestRevisionNote 'IPC-7351 Footprint Added.'
PRP PackageDescription 'Chip Resistor'
PRP PackageReference 'J1-0603'
PRP Published '8-Jun-2000'
PRP Publisher 'Altium Limited'
PRP VALUE '0 Ohm'
TOP 0 0.9606298 0.7185038 90 N 3 3 R36-1
TOP 1 0.9015747 0.7185038 90 N 105 3 R36-2
#
# CMP 2
CMP 1 2.0433071 4.257874 90 N JP2 JUMPER_3PIN ;0=2,1=0.0000
PRP CATEGORY 'CONN, HDR'
PRP DATE ''
PRP DESC 'CONN, HDR, 1X3, VERT, .1, JUMPER, TH'
PRP MAXTEMP 'C'
PRP MFG_Name 'SAMTEC'
PRP MFG_PART_NUM 'TSW-103-08-G-S'
PRP MINTEMP 'C'
PRP MODIFY_DATE '10/10/2013'
PRP OTHER 'TSW-1XX'
PRP P1 'VERT'
PRP P2 '.1'
PRP P3 'FEATURE'
PRP SHEETPART ''
PRP SIZE 'TH'
PRP SUB ''
PRP Supplier_1 'Digi-Key'
PRP Supplier_Part_Number_1 'SAM1038-02-ND'
PRP VALENTIUM_PART_NUM '<VALENTIUM>'
PRP VALUE '1X3'
TOP 0 2.0433071 4.257874 90 N 4 0 JP2-1
TOP 1 2.0433071 4.157874 90 N 34 0 JP2-2
TOP 2 2.0433071 4.057874 90 N 94 0 JP2-3
#
# CMP 3
CMP 1 1.4576771 4.253937 90 N JP1 JUMPER_3PIN ;0=2,1=0.0000
PRP CATEGORY 'CONN, HDR'
PRP DATE ''
PRP DESC 'CONN, HDR, 1X3, VERT, .1, JUMPER, TH'
PRP MAXTEMP 'C'
PRP MFG_Name 'SAMTEC'
PRP MFG_PART_NUM 'TSW-103-08-G-S'
PRP MINTEMP 'C'
PRP MODIFY_DATE '10/10/2013'
PRP OTHER 'TSW-1XX'
PRP P1 'VERT'
PRP P2 '.1'
PRP P3 'FEATURE'
PRP SHEETPART ''
PRP SIZE 'TH'
PRP SUB ''
PRP Supplier_1 'Digi-Key'
PRP Supplier_Part_Number_1 'SAM1038-02-ND'
PRP VALENTIUM_PART_NUM '<VALENTIUM>'
PRP VALUE '1X3'
TOP 0 1.4576771 4.253937 90 N 2 0 JP1-1
TOP 1 1.4576771 4.153937 90 N 35 0 JP1-2
TOP 2 1.4576771 4.053937 90 N 92 0 JP1-3
#
# CMP 4
CMP 15 0.9340551 1.2244095 180 N R16 MAC10M ;0=1,1=0.0354
PRP LatestRevisionDate '29-May-2009'
PRP LatestRevisionNote 'IPC-7351 Footprint Added.'
PRP PackageDescription 'Chip Resistor'
PRP PackageReference 'J1-0603'
PRP Published '8-Jun-2000'
PRP Publisher 'Altium Limited'
PRP VALUE '0 Ohm'
TOP 0 0.9635826 1.2244094 90 N 42 3 R16-1
TOP 1 0.9045275 1.2244094 90 N 106 1 R16-2
#
# CMP 5
CMP 15 0.9301181 1.7470473 180 N R15 MACPPSO ;0=1,1=0.0354
PRP LatestRevisionDate '29-May-2009'
PRP LatestRevisionNote 'IPC-7351 Footprint Added.'
PRP PackageDescription 'Chip Resistor'
PRP PackageReference 'J1-0603'
PRP Published '8-Jun-2000'
PRP Publisher 'Altium Limited'
PRP VALUE '0 Ohm'
TOP 0 0.9596456 1.7470472 90 N 76 1 R15-1
TOP 1 0.9005905 1.7470472 90 N 107 1 R15-2
#
# CMP 6
CMP 15 0.9379921 2.2844488 180 N R14 MACPPSI ;0=1,1=0.0354
PRP LatestRevisionDate '29-May-2009'
PRP LatestRevisionNote 'IPC-7351 Footprint Added.'
PRP PackageDescription 'Chip Resistor'
PRP PackageReference 'J1-0603'
PRP Published '8-Jun-2000'
PRP Publisher 'Altium Limited'
PRP VALUE '0 Ohm'
TOP 0 0.9675196 2.2844487 90 N 80 1 R14-1
TOP 1 0.9084645 2.2844487 90 N 108 1 R14-2
#
# CMP 7
CMP 15 2.3877953 2.9291339 90 N R17 MACPPS ;0=1,1=0.0354
PRP LatestRevisionDate '29-May-2009'
PRP LatestRevisionNote 'IPC-7351 Footprint Added.'
PRP PackageDescription 'Chip Resistor'
PRP PackageReference 'J1-0603'
PRP Published '8-Jun-2000'
PRP Publisher 'Altium Limited'
PRP VALUE '0 Ohm'
TOP 0 2.3877954 2.9586614 0 N 3 0 R17-1
TOP 1 2.3877954 2.8996063 0 N 80 2 R17-2
#
# CMP 8
CMP 15 2.2125983 4.0452757 90 N R13 MACRX ;0=1,1=0.0354
PRP LatestRevisionDate '29-May-2009'
PRP LatestRevisionNote 'IPC-7351 Footprint Added.'
PRP PackageDescription 'Chip Resistor'
PRP PackageReference 'J1-0603'
PRP Published '8-Jun-2000'
PRP Publisher 'Altium Limited'
PRP VALUE '0 Ohm'
TOP 0 2.2125984 4.0748032 0 N 74 2 R13-1
TOP 1 2.2125984 4.0157481 0 N 94 1 R13-2
#
# CMP 9
CMP 15 2.1515747 4.0452757 90 N R12 GPS2RX ;0=1,1=0.0354
PRP LatestRevisionDate '29-May-2009'
PRP LatestRevisionNote 'IPC-7351 Footprint Added.'
PRP PackageDescription 'Chip Resistor'
PRP PackageReference 'J1-0603'
PRP Published '8-Jun-2000'
PRP Publisher 'Altium Limited'
PRP VALUE '0 Ohm'
TOP 0 2.1515748 4.0748032 0 N 100 1 R12-1
TOP 1 2.1515748 4.0157481 0 N 94 2 R12-2
#
# CMP 10
CMP 15 1.3464568 4.007874 270 N R11 MACTX ;0=1,1=0.0354
PRP LatestRevisionDate '29-May-2009'
PRP LatestRevisionNote 'IPC-7351 Footprint Added.'
PRP PackageDescription 'Chip Resistor'
PRP PackageReference 'J1-0603'
PRP Published '8-Jun-2000'
PRP Publisher 'Altium Limited'
PRP VALUE '0 Ohm'
TOP 0 1.3464567 3.9783465 180 N 73 2 R11-1
TOP 1 1.3464567 4.0374016 180 N 92 1 R11-2
#
# CMP 11
CMP 15 1.3464566 4.1122048 90 N R10 GPS2TX ;0=1,1=0.0354
PRP LatestRevisionDate '29-May-2009'
PRP LatestRevisionNote 'IPC-7351 Footprint Added.'
PRP PackageDescription 'Chip Resistor'
PRP PackageReference 'J1-0603'
PRP Published '8-Jun-2000'
PRP Publisher 'Altium Limited'
PRP VALUE '0 Ohm'
TOP 0 1.3464567 4.1417323 0 N 97 1 R10-1
TOP 1 1.3464567 4.0826772 0 N 92 2 R10-2
#
# CMP 12
CMP 37 2.9340551 3.1122047 0 N U3 DS3231SN ;0=1,1=0.1043
PRP Code_IPC 'SOIC127P1030-16'
PRP Code_JEDEC 'MS-013-AA'
PRP ComponentLink1Description 'Manufacturer URL'
PRP ComponentLink1URL 'http://www.maxim-ic.com'
PRP ComponentLink2Description 'Datasheet'
PRP ComponentLink2URL 'http://datasheets.maxim-ic.com/en/ds/DS3231.pdf'
PRP ComponentLink3Description 'Package Specification'
PRP ComponentLink3URL 'http://pdfserv.maxim-ic.com/package_dwgs/21-0042.PDF'
PRP DatasheetVersion 'Rev 8, Jul-2010'
PRP PackageDescription '16-Pin Small-Outline IC, Wide (0.3in), 1.27 mm Pitch, SOIC (W)'
PRP PackageReference 'W16-H2'
PRP PackageVersion 'revD, 2010'
TOP 0 2.7568898 3.2872047 270 N 0 284 U3-1
TOP 1 2.7568898 3.2372047 270 N 109 23 U3-2
TOP 2 2.7568898 3.1872047 270 N 95 1 U3-3
TOP 3 2.7568898 3.1372047 270 N 0 283 U3-4
TOP 4 2.7568898 3.0872047 270 N 0 282 U3-5
TOP 5 2.7568898 3.0372047 270 N 0 281 U3-6
TOP 6 2.7568898 2.9872047 270 N 0 280 U3-7
TOP 7 2.7568898 2.9372047 270 N 0 279 U3-8
TOP 8 3.1112205 2.9372047 270 N 0 275 U3-9
TOP 9 3.1112205 2.9872047 270 N 0 276 U3-10
TOP 10 3.1112205 3.0372047 270 N 0 277 U3-11
TOP 11 3.1112205 3.0872047 270 N 0 278 U3-12
TOP 12 3.1112205 3.1372047 270 N 136 201 U3-13
TOP 13 3.1112205 3.1872047 270 N 81 1 U3-14
TOP 14 3.1112205 3.2372047 270 N 39 4 U3-15
TOP 15 3.1112205 3.2872047 270 N 40 4 U3-16
#
# CMP 13
CMP 19 4.8277559 1.6574803 270 N U10AL SA.45s ;0=2,1=0.4500
PRP Datasheet_URL 'https://media.digikey.com/pdf/Data%20Sheets/Microsemi%20PDFs/090-02984-001.pdf'
PRP Datasheet_Version '03/2017'
PRP Manufacturer 'Microsemi'
PRP Manufacturer_URL 'http://www.microsemi.com/'
PRP Mounting_Technology 'ThroughHole'
PRP Package_Description '9-Pin Through Hole Device, Body 40.64 x 35.306 mm'
PRP Package_Reference '090-02984-00X'
TOP 0 4.3277559 1.0074803 270 N 0 22 U10AL-1
TOP 1 4.9277559 1.0074803 270 N 82 1 U10AL-4
TOP 2 5.1277559 1.0074803 270 N 73 1 U10AL-5
TOP 3 5.3277559 1.0074803 270 N 74 1 U10AL-6
TOP 4 5.3277559 2.3074803 270 N 109 1 U10AL-7
TOP 5 5.1277559 2.3074803 270 N 136 40 U10AL-8
TOP 6 4.9277559 2.3074803 270 N 80 0 U10AL-9
TOP 7 4.7277559 2.3074803 270 N 76 0 U10AL-10
TOP 8 4.3277559 2.3074803 270 N 42 2 U10AL-12
#
# CMP 14
CMP 11 4.9094488 3.3848425 270 N BT1 BU2032SM-BT-GTR ;0=1,1=0.0000
PRP Case/Package 'SMD/SMT'
PRP Max_Operating_Temperature '280°C'
PRP Min_Operating_Temperature '-40°C'
PRP Mount 'Surface Mount'
PRP Number_of_Cells '1'
PRP Package_Quantity '400'
PRP Termination 'SMD/SMT'
TOP 0 4.9094488 3.9616142 270 N 136 171 BT1-1
TOP 1 4.9094488 2.8080708 270 N 81 0 BT1-2
#
# CMP 15
CMP 7 4.3398425 2.816063 270 N C72 CAP_0805_22UF_16V ;0=1,1=0.0551
PRP CATEGORY 'CAP, CER'
PRP DATE '4/11/2006 3:37:28 PM'
PRP DESC 'CAP, CER, 22.UF, 16V, 20%, X5R, 0805'
PRP MAXTEMP '85C'
PRP MFG_Name 'MURATA'
PRP MFG_PART_NUM 'GRM219R61C226ME15L'
PRP MINTEMP '-55C'
PRP MODIFY_DATE '10/23/2013'
PRP OTHER ''
PRP P1 '20%'
PRP P2 '16V'
PRP P3 'X5R'
PRP SHEETPART ''
PRP SIZE '0805'
PRP SUB ''
PRP Supplier_1 'Digi-Key'
PRP Supplier_Part_Number_1 '490-9952-1-ND'
PRP VALENTIUM_PART_NUM '<VALENTIUM>'
PRP VALUE '22uF'
TOP 0 4.3398425 2.7806299 180 N 136 169 C72-1
TOP 1 4.3398425 2.8514961 180 N 14 2 C72-2
#
# CMP 16
CMP 7 4.2348425 2.816063 270 N C73 CAP_0805_22UF_16V ;0=1,1=0.0551
PRP CATEGORY 'CAP, CER'
PRP DATE '4/11/2006 3:37:28 PM'
PRP DESC 'CAP, CER, 22.UF, 16V, 20%, X5R, 0805'
PRP MAXTEMP '85C'
PRP MFG_Name 'MURATA'
PRP MFG_PART_NUM 'GRM219R61C226ME15L'
PRP MINTEMP '-55C'
PRP MODIFY_DATE '10/23/2013'
PRP OTHER ''
PRP P1 '20%'
PRP P2 '16V'
PRP P3 'X5R'
PRP SHEETPART ''
PRP SIZE '0805'
PRP SUB ''
PRP Supplier_1 'Digi-Key'
PRP Supplier_Part_Number_1 '490-9952-1-ND'
PRP VALENTIUM_PART_NUM '<VALENTIUM>'
PRP VALUE '22uF'
TOP 0 4.2348425 2.7806299 180 N 136 41 C73-1
TOP 1 4.2348425 2.8514961 180 N 14 0 C73-2
#
# CMP 17
CMP 7 3.9598425 2.816063 270 N C74 CAP_0805_22UF_16V ;0=1,1=0.0551
PRP CATEGORY 'CAP, CER'
PRP DATE '4/11/2006 3:37:28 PM'
PRP DESC 'CAP, CER, 22.UF, 16V, 20%, X5R, 0805'
PRP MAXTEMP '85C'
PRP MFG_Name 'MURATA'
PRP MFG_PART_NUM 'GRM219R61C226ME15L'
PRP MINTEMP '-55C'
PRP MODIFY_DATE '10/23/2013'
PRP OTHER ''
PRP P1 '20%'
PRP P2 '16V'
PRP P3 'X5R'
PRP SHEETPART ''
PRP SIZE '0805'
PRP SUB ''
PRP Supplier_1 'Digi-Key'
PRP Supplier_Part_Number_1 '490-9952-1-ND'
PRP VALENTIUM_PART_NUM '<VALENTIUM>'
PRP VALUE '22uF'
TOP 0 3.9598425 2.7806299 180 N 136 42 C74-1
TOP 1 3.9598425 2.8514961 180 N 109 2 C74-2
#
# CMP 18
CMP 7 4.0648425 2.816063 270 N C75 CAP_0805_22UF_16V ;0=1,1=0.0551
PRP CATEGORY 'CAP, CER'
PRP DATE '4/11/2006 3:37:28 PM'
PRP DESC 'CAP, CER, 22.UF, 16V, 20%, X5R, 0805'
PRP MAXTEMP '85C'
PRP MFG_Name 'MURATA'
PRP MFG_PART_NUM 'GRM219R61C226ME15L'
PRP MINTEMP '-55C'
PRP MODIFY_DATE '10/23/2013'
PRP OTHER ''
PRP P1 '20%'
PRP P2 '16V'
PRP P3 'X5R'
PRP SHEETPART ''
PRP SIZE '0805'
PRP SUB ''
PRP Supplier_1 'Digi-Key'
PRP Supplier_Part_Number_1 '490-9952-1-ND'
PRP VALENTIUM_PART_NUM '<VALENTIUM>'
PRP VALUE '22uF'
TOP 0 4.0648425 2.7806299 180 N 136 43 C75-1
TOP 1 4.0648425 2.8514961 180 N 109 3 C75-2
#
# CMP 19
CMP 6 4.0398425 3.061063 90 N C76 CAP_0603_0.01UF_50V ;0=1,1=0.0394
PRP CATEGORY 'CAP, CER'
PRP DATE '7/24/2013'
PRP DESC 'CAP, CER, 0.01UF, 50V, 10%, X7R, 0603'
PRP MAXTEMP '125C'
PRP MFG_Name 'KEMET'
PRP MFG_PART_NUM 'C0603C103K5RACTU'
PRP MINTEMP '-55C'
PRP MODIFY_DATE '10/23/2013'
PRP OTHER ''
PRP P1 '10%'
PRP P2 '50V'
PRP P3 'X7R'
PRP SHEETPART ''
PRP SIZE '0603'
PRP SUB ''
PRP Supplier_1 'Digi-Key'
PRP Supplier_Part_Number_1 '399-1091-1-ND'
PRP VALENTIUM_PART_NUM '<VALENTIUM>'
PRP VALUE '0.01uF'
TOP 0 4.0398425 3.0925591 0 N 136 168 C76-1
TOP 1 4.0398425 3.029567 0 N 109 18 C76-2
#
# CMP 20
CMP 5 4.1098425 3.061063 90 N C77 CAP_0402_0.1UF_50V ;0=1,1=0.0236
PRP CATEGORY 'CAP, CER'
PRP DATE ''
PRP DESC 'CAP, CER, 0.1UF, 50V, 10%, X7R, AEC-Q200, 0402'
PRP MAXTEMP '125C'
PRP MFG_Name 'TDK'
PRP MFG_PART_NUM 'CGA2B3X7R1H104K050BB'
PRP MINTEMP '-55C'
PRP MODIFY_DATE '10/23/2013'
PRP OTHER 'AEC-Q200'
PRP P1 '10%'
PRP P2 '50V'
PRP P3 'X7R'
PRP SHEETPART ''
PRP SIZE '0402'
PRP SUB ''
PRP Supplier_1 'Digi-Key'
PRP Supplier_Part_Number_1 '445-6899-1-ND'
PRP VALENTIUM_PART_NUM '<VALENTIUM>'
PRP VALUE '0.1UF'
TOP 0 4.1098425 3.0779921 0 N 136 167 C77-1
TOP 1 4.1098425 3.0441338 0 N 109 17 C77-2
#
# CMP 21
CMP 5 4.1648425 3.061063 90 N C78 CAP_0402_0.1UF_50V ;0=1,1=0.0236
PRP CATEGORY 'CAP, CER'
PRP DATE ''
PRP DESC 'CAP, CER, 0.1UF, 50V, 10%, X7R, AEC-Q200, 0402'
PRP MAXTEMP '125C'
PRP MFG_Name 'TDK'
PRP MFG_PART_NUM 'CGA2B3X7R1H104K050BB'
PRP MINTEMP '-55C'
PRP MODIFY_DATE '10/23/2013'
PRP OTHER 'AEC-Q200'
PRP P1 '10%'
PRP P2 '50V'
PRP P3 'X7R'
PRP SHEETPART ''
PRP SIZE '0402'
PRP SUB ''
PRP Supplier_1 'Digi-Key'
PRP Supplier_Part_Number_1 '445-6899-1-ND'
PRP VALENTIUM_PART_NUM '<VALENTIUM>'
PRP VALUE '0.1UF'
TOP 0 4.1648425 3.0779921 0 N 136 44 C78-1
TOP 1 4.1648425 3.0441338 0 N 109 4 C78-2
#
# CMP 22
CMP 5 4.2198425 3.061063 90 N C79 CAP_0402_0.1UF_50V ;0=1,1=0.0236
PRP CATEGORY 'CAP, CER'
PRP DATE ''
PRP DESC 'CAP, CER, 0.1UF, 50V, 10%, X7R, AEC-Q200, 0402'
PRP MAXTEMP '125C'
PRP MFG_Name 'TDK'
PRP MFG_PART_NUM 'CGA2B3X7R1H104K050BB'
PRP MINTEMP '-55C'
PRP MODIFY_DATE '10/23/2013'
PRP OTHER 'AEC-Q200'
PRP P1 '10%'
PRP P2 '50V'
PRP P3 'X7R'
PRP SHEETPART ''
PRP SIZE '0402'
PRP SUB ''
PRP Supplier_1 'Digi-Key'
PRP Supplier_Part_Number_1 '445-6899-1-ND'
PRP VALENTIUM_PART_NUM '<VALENTIUM>'
PRP VALUE '0.1UF'
TOP 0 4.2198425 3.0779921 0 N 136 45 C79-1
TOP 1 4.2198425 3.0441338 0 N 109 5 C79-2
#
# CMP 23
CMP 5 4.2748425 3.061063 90 N C80 CAP_0402_0.1UF_50V ;0=1,1=0.0236
PRP CATEGORY 'CAP, CER'
PRP DATE ''
PRP DESC 'CAP, CER, 0.1UF, 50V, 10%, X7R, AEC-Q200, 0402'
PRP MAXTEMP '125C'
PRP MFG_Name 'TDK'
PRP MFG_PART_NUM 'CGA2B3X7R1H104K050BB'
PRP MINTEMP '-55C'
PRP MODIFY_DATE '10/23/2013'
PRP OTHER 'AEC-Q200'
PRP P1 '10%'
PRP P2 '50V'
PRP P3 'X7R'
PRP SHEETPART ''
PRP SIZE '0402'
PRP SUB ''
PRP Supplier_1 'Digi-Key'
PRP Supplier_Part_Number_1 '445-6899-1-ND'
PRP VALENTIUM_PART_NUM '<VALENTIUM>'
PRP VALUE '0.1UF'
TOP 0 4.2748425 3.0779921 0 N 136 46 C80-1
TOP 1 4.2748425 3.0441338 0 N 109 6 C80-2
#
# CMP 24
CMP 5 4.3348425 3.061063 90 N C81 CAP_0402_0.1UF_50V ;0=1,1=0.0236
PRP CATEGORY 'CAP, CER'
PRP DATE ''
PRP DESC 'CAP, CER, 0.1UF, 50V, 10%, X7R, AEC-Q200, 0402'
PRP MAXTEMP '125C'
PRP MFG_Name 'TDK'
PRP MFG_PART_NUM 'CGA2B3X7R1H104K050BB'
PRP MINTEMP '-55C'
PRP MODIFY_DATE '10/23/2013'
PRP OTHER 'AEC-Q200'
PRP P1 '10%'
PRP P2 '50V'
PRP P3 'X7R'
PRP SHEETPART ''
PRP SIZE '0402'
PRP SUB ''
PRP Supplier_1 'Digi-Key'
PRP Supplier_Part_Number_1 '445-6899-1-ND'
PRP VALENTIUM_PART_NUM '<VALENTIUM>'
PRP VALUE '0.1UF'
TOP 0 4.3348425 3.0779921 0 N 136 47 C81-1
TOP 1 4.3348425 3.0441338 0 N 109 7 C81-2
#
# CMP 25
CMP 5 4.3948425 3.061063 90 N C82 CAP_0402_0.1UF_50V ;0=1,1=0.0236
PRP CATEGORY 'CAP, CER'
PRP DATE ''
PRP DESC 'CAP, CER, 0.1UF, 50V, 10%, X7R, AEC-Q200, 0402'
PRP MAXTEMP '125C'
PRP MFG_Name 'TDK'
PRP MFG_PART_NUM 'CGA2B3X7R1H104K050BB'
PRP MINTEMP '-55C'
PRP MODIFY_DATE '10/23/2013'
PRP OTHER 'AEC-Q200'
PRP P1 '10%'
PRP P2 '50V'
PRP P3 'X7R'
PRP SHEETPART ''
PRP SIZE '0402'
PRP SUB ''
PRP Supplier_1 'Digi-Key'
PRP Supplier_Part_Number_1 '445-6899-1-ND'
PRP VALENTIUM_PART_NUM '<VALENTIUM>'
PRP VALUE '0.1UF'
TOP 0 4.3948425 3.0779921 0 N 136 48 C82-1
TOP 1 4.3948425 3.0441338 0 N 109 8 C82-2
#
# CMP 26
CMP 5 4.4548425 3.061063 90 N C83 CAP_0402_0.1UF_50V ;0=1,1=0.0236
PRP CATEGORY 'CAP, CER'
PRP DATE ''
PRP DESC 'CAP, CER, 0.1UF, 50V, 10%, X7R, AEC-Q200, 0402'
PRP MAXTEMP '125C'
PRP MFG_Name 'TDK'
PRP MFG_PART_NUM 'CGA2B3X7R1H104K050BB'
PRP MINTEMP '-55C'
PRP MODIFY_DATE '10/23/2013'
PRP OTHER 'AEC-Q200'
PRP P1 '10%'
PRP P2 '50V'
PRP P3 'X7R'
PRP SHEETPART ''
PRP SIZE '0402'
PRP SUB ''
PRP Supplier_1 'Digi-Key'
PRP Supplier_Part_Number_1 '445-6899-1-ND'
PRP VALENTIUM_PART_NUM '<VALENTIUM>'
PRP VALUE '0.1UF'
TOP 0 4.4548425 3.0779921 0 N 136 49 C83-1
TOP 1 4.4548425 3.0441338 0 N 109 9 C83-2
#
# CMP 27
CMP 7 4.2448425 3.246063 0 N C84 CAP_0805_1UF_50V ;0=1,1=0.0551
PRP CATEGORY 'CAP, CER'
PRP DATE '10/31/2006 2:46:38 PM'
PRP DESC 'CAP, CER, 1.0UF, 50V, 10%, X7R, 0805'
PRP MAXTEMP '125C'
PRP MFG_Name 'MURATA'
PRP MFG_PART_NUM 'GCM21BR71H105KA03L'
PRP MINTEMP '-55C'
PRP MODIFY_DATE '10/23/2013'
PRP OTHER 'AEC-Q200'
PRP P1 '10%'
PRP P2 '50V'
PRP P3 'X7R'
PRP SHEETPART ''
PRP SIZE '0805'
PRP SUB ''
PRP Supplier_1 'Digi-Key'
PRP Supplier_Part_Number_1 '490-10675-1-ND'
PRP VALENTIUM_PART_NUM '<VALENTIUM>'
PRP VALUE '1.0UF'
TOP 0 4.2094094 3.246063 270 N 136 50 C84-1
TOP 1 4.2802756 3.246063 270 N 109 10 C84-2
#
# CMP 28
CMP 6 6.6048425 3.161063 270 N C85 CAP_0603_22PF_50V ;0=1,1=0.0394
PRP CATEGORY 'CAP, CER'
PRP DATE '7/25/2013'
PRP DESC 'CAP, CER, 22.PF, 50V, 5%, NPO, 0603'
PRP MAXTEMP '125C'
PRP MFG_Name 'KEMET'
PRP MFG_PART_NUM 'C0603C220J5GACTU'
PRP MINTEMP '-55C'
PRP MODIFY_DATE '10/23/2013'
PRP OTHER ''
PRP P1 '5%'
PRP P2 '50V'
PRP P3 'NP0'
PRP SHEETPART ''
PRP SIZE '0603'
PRP SUB ''
PRP Supplier_1 'Digi-Key'
PRP Supplier_Part_Number_1 '399-1053-1-ND'
PRP VALENTIUM_PART_NUM '<VALENTIUM>'
PRP VALUE '22pF'
TOP 0 6.6048425 3.1295669 180 N 136 51 C85-1
TOP 1 6.6048425 3.192559 180 N 15 0 C85-2
#
# CMP 29
CMP 6 6.6048425 3.296063 90 N C86 CAP_0603_22PF_50V ;0=1,1=0.0394
PRP CATEGORY 'CAP, CER'
PRP DATE '7/25/2013'
PRP DESC 'CAP, CER, 22.PF, 50V, 5%, NPO, 0603'
PRP MAXTEMP '125C'
PRP MFG_Name 'KEMET'
PRP MFG_PART_NUM 'C0603C220J5GACTU'
PRP MINTEMP '-55C'
PRP MODIFY_DATE '10/23/2013'
PRP OTHER ''
PRP P1 '5%'
PRP P2 '50V'
PRP P3 'NP0'
PRP SHEETPART ''
PRP SIZE '0603'
PRP SUB ''
PRP Supplier_1 'Digi-Key'
PRP Supplier_Part_Number_1 '399-1053-1-ND'
PRP VALENTIUM_PART_NUM '<VALENTIUM>'
PRP VALUE '22pF'
TOP 0 6.6048425 3.3275591 0 N 136 52 C86-1
TOP 1 6.6048425 3.264567 0 N 16 0 C86-2
#
# CMP 30
CMP 7 1.8378425 4.276063 0 N C91 CAP_0805_1UF_25V ;0=1,1=0.0551
PRP CATEGORY 'CAP, CER'
PRP DATE '4/11/2006 3:37:28 PM'
PRP DESC 'CAP, CER, 1.0UF, 25V, 10%, X5R, 0805'
PRP MAXTEMP '85C'
PRP MFG_Name 'AVX'
PRP MFG_PART_NUM '08053D105KAT2A'
PRP MINTEMP '-55C'
PRP MODIFY_DATE '10/23/2013'
PRP OTHER ''
PRP P1 '10%'
PRP P2 '25V'
PRP P3 'X5R'
PRP SHEETPART ''
PRP SIZE '0805'
PRP SUB ''
PRP Supplier_1 'Digi-Key'
PRP Supplier_Part_Number_1 '478-1409-1-ND'
PRP VALENTIUM_PART_NUM '<VALENTIUM>'
PRP VALUE '1.0UF'
TOP 0 1.8024094 4.276063 270 N 136 53 C91-1
TOP 1 1.8732756 4.276063 270 N 146 6 C91-2
#
# CMP 31
CMP 6 1.6958425 4.273063 180 N C92 GRT188R61E106ME13D ;0=1,1=0.0394
PRP CATEGORY 'CAP, CER'
PRP DATE '7/25/2013'
PRP DESC 'CAP, CER, 10.UF, 25V, 20%, X5R, AEC-Q200, 0603'
PRP MAXTEMP '85C'
PRP MFG_Name 'MURATA'
PRP MFG_PART_NUM 'GRT188R61E106ME13D'
PRP MINTEMP '-55C'
PRP MODIFY_DATE '10/23/2013'
PRP OTHER 'AEC-Q200'
PRP P1 '20%'
PRP P2 '25V'
PRP P3 'X5R'
PRP SHEETPART ''
PRP SIZE '0603'
PRP SUB ''
PRP Supplier_1 'Digi-Key'
PRP Supplier_Part_Number_1 '490-12323-6-ND'
PRP VALENTIUM_PART_NUM '<VALENTIUM>'
PRP VALUE '10.UF'
TOP 0 1.7273386 4.273063 90 N 136 54 C92-1
TOP 1 1.6643465 4.273063 90 N 146 7 C92-2
#
# CMP 32
CMP 24 3.5048425 2.797063 0 N R42 ERJ-3EKF1002V ;0=1,1=0.0197
PRP CATEGORY 'RES'
PRP DATE '7/26/2013'
PRP DESC 'RES, 10K, 1%, 1/10W, TF, 0603'
PRP MAXTEMP '125C'
PRP MFG_Name 'PANASONIC'
PRP MFG_PART_NUM 'ERJ-3EKF1002V'
PRP MINTEMP '-55C'
PRP ModifyDate '7/25/2013'
PRP OTHER '100PPM'
PRP P1 '1%'
PRP P2 '1/10W'
PRP P3 'TF'
PRP SHEETPART ''
PRP SIZE '0603'
PRP SUB 'GENERIC'
PRP Supplier_1 'Digi-Key'
PRP Supplier_Part_Number_1 'P10.0KHCT-ND'
PRP VALUE '10K'
PRP VELENTIUM_PART_NUM '<VELENTIUM>'
TOP 0 3.4776771 2.797063 270 N 30 0 R42-1
TOP 1 3.5320078 2.797063 270 N 109 20 R42-2
#
# CMP 33
CMP 24 1.9338425 4.102063 90 N R43 ERJ-3EKF1002V ;0=1,1=0.0197
PRP CATEGORY 'RES'
PRP DATE '7/26/2013'
PRP DESC 'RES, 10K, 1%, 1/10W, TF, 0603'
PRP MAXTEMP '125C'
PRP MFG_Name 'PANASONIC'
PRP MFG_PART_NUM 'ERJ-3EKF1002V'
PRP MINTEMP '-55C'
PRP ModifyDate '7/25/2013'
PRP OTHER '100PPM'
PRP P1 '1%'
PRP P2 '1/10W'
PRP P3 'TF'
PRP SHEETPART ''
PRP SIZE '0603'
PRP SUB 'GENERIC'
PRP Supplier_1 'Digi-Key'
PRP Supplier_Part_Number_1 'P10.0KHCT-ND'
PRP VALUE '10K'
PRP VELENTIUM_PART_NUM '<VELENTIUM>'
TOP 0 1.9338425 4.1292284 0 N 146 8 R43-1
TOP 1 1.9338425 4.0748977 0 N 31 0 R43-2
#
# CMP 34
CMP 32 1.7388425 4.112063 0 N U16 FT230XS-R ;0=1,1=0.0669
PRP CATEGORY 'IC, TCVR'
PRP DATE ''
PRP DESC 'IC, TCVR, FT230, USB TO UART, 5V, FTDI, 16SSOP'
PRP MAXTEMP '85C'
PRP MFG_Name 'FTDI'
PRP MFG_PART_NUM 'FT230XS-R'
PRP MINTEMP '-40C'
PRP MODIFY_DATE '8/14/2013'
PRP OTHER ''
PRP P1 'USB TO UART'
PRP P2 '5V'
PRP P3 'FTDI'
PRP SHEETPART ''
PRP SIZE '20SSOP'
PRP SUB ''
PRP Supplier_1 'Digi-Key'
PRP Supplier_Part_Number_1 '768-1135-1-ND'
PRP VALUE 'FT230XS'
PRP VELENTIUM_PART_NUM '<V PART NUM>'
TOP 0 1.631559 4.199563 270 N 34 1 U16-1
TOP 1 1.631559 4.174563 270 N 0 256 U16-2
TOP 2 1.631559 4.149563 270 N 33 0 U16-3
TOP 3 1.631559 4.124563 270 N 35 1 U16-4
TOP 4 1.631559 4.099563 270 N 136 194 U16-5
TOP 5 1.631559 4.074563 270 N 0 257 U16-6
TOP 6 1.631559 4.049563 270 N 0 258 U16-7
TOP 7 1.631559 4.024563 270 N 36 0 U16-8
TOP 8 1.8461259 4.024563 270 N 37 0 U16-9
TOP 9 1.8461259 4.049563 270 N 33 1 U16-10
TOP 10 1.8461259 4.074563 270 N 31 1 U16-11
TOP 11 1.8461259 4.099563 270 N 146 30 U16-12
TOP 12 1.8461259 4.124563 270 N 136 195 U16-13
TOP 13 1.8461259 4.149563 270 N 0 261 U16-14
TOP 14 1.8461259 4.174563 270 N 0 260 U16-15
TOP 15 1.8461259 4.199563 270 N 0 259 U16-16
#
# CMP 35
CMP 36 2.383748 4.1703386 180 N J4 473461001 ;0=1,1=0.0965
PRP CATEGORY 'CONN, REC'
PRP DATE ''
PRP DESC 'CONN, REC, USB, R/A, MICRO, TYPE B, 5 POS, SMT FLANGELESS'
PRP MAXTEMP '85C'
PRP MFG_Name 'MOLEX'
PRP MFG_PART_NUM '473461001'
PRP MINTEMP '-30C'
PRP MODIFY_DATE '10/10/2013'
PRP OTHER 'FLANGELESS'
PRP P1 'R/A'
PRP P2 '5 POS'
PRP P3 'USB MICRO B'
PRP SHEETPART ''
PRP SIZE 'SMT'
PRP SUB ''
PRP Supplier_1 'Digi-Key'
PRP Supplier_Part_Number_1 'WM11228CT-ND'
PRP VALENTIUM_PART_NUM '<VALENTIUM>'
PRP VALUE 'USB MICRO B'
TOP 0 2.1996929 4.275063 180 N 0 267 J4-0
TOP 1 2.4654409 4.275063 180 N 0 268 J4-0
TOP 2 2.4309921 4.1736851 180 N 0 271 J4-0
TOP 3 2.2341417 4.1736851 180 N 0 272 J4-0
TOP 4 2.3778425 4.275063 180 N 0 273 J4-0
TOP 5 2.2715433 4.275063 180 N 0 274 J4-0
TOP 6 2.383748 4.1703386 180 N 0 270 J4-1
TOP 7 2.3581575 4.1703386 180 N 37 1 J4-2
TOP 8 2.3325669 4.1703386 180 N 36 1 J4-3
TOP 9 2.3069763 4.1703386 180 N 0 269 J4-4
TOP 10 2.2813858 4.1703386 180 N 136 200 J4-5
#
# CMP 36
CMP 24 6.1228425 2.461063 270 N R5 ERJ-3EKF2612V ;0=1,1=0.0197
PRP CATEGORY 'RES'
PRP DATE '7/26/2013'
PRP DESC 'RES, 27.1K, 1%, 1/10W, TF, 0603'
PRP MAXTEMP '125C'
PRP MFG_Name 'PANASONIC'
PRP MFG_PART_NUM 'ERJ-3EKF2612V'
PRP MINTEMP '-55C'
PRP ModifyDate '7/25/2013'
PRP OTHER '100PPM'
PRP P1 '1%'
PRP P2 '1/10W'
PRP P3 'TF'
PRP SHEETPART ''
PRP SIZE '0603'
PRP SUB 'GENERIC'
PRP Supplier_1 'Digi-Key'
PRP Supplier_Part_Number_1 'P26.1KHCT-ND'
PRP VALUE '26.1K'
PRP VELENTIUM_PART_NUM '<VELENTIUM>'
TOP 0 6.1228425 2.4338976 180 N 23 0 R5-1
TOP 1 6.1228425 2.4882283 180 N 138 5 R5-2
#
# CMP 37
CMP 29 6.8348425 3.231063 0 N X1 MC306 ;0=1,1=0.0000
PRP CATEGORY 'XTAL'
PRP DATE ''
PRP DESC 'XTAL, <VAL>, P1, P2, P3, EIA, OTHER'
PRP MAXTEMP '85C'
PRP MFG_Name 'ABRACON CORPORATION'
PRP MFG_PART_NUM 'MC-306 32.768K-E3:ROHS'
PRP MINTEMP '-40C'
PRP MODIFY_DATE '9/5/2013'
PRP OTHER 'MC306, 3.8X8.00X2.54MM'
PRP P1 '6PF'
PRP P2 '20PPM'
PRP P3 'FUNDAMENTAL'
PRP SHEETPART ''
PRP SIZE '4-SOJ'
PRP SUB ''
PRP Supplier_1 'Digi-Key'
PRP Supplier_Part_Number_1 'SER2417CT-ND'
PRP VALENTIUM_PART_NUM '<VALENTIUM>'
PRP VALUE '32.768kHz'
TOP 0 6.7265748 3.1680709 270 N 15 2 X1-1
TOP 1 6.9431102 3.1680709 270 N 0 255 X1-2
TOP 2 6.9431102 3.2940551 270 N 0 254 X1-3
TOP 3 6.7265748 3.2940551 270 N 16 2 X1-4
#
# CMP 38
CMP 27 3.4848425 2.972063 0 N U13 SiT5356AI-FQA33-IT-10.000000 ;0=1,1=0.0000
PRP CATEGORY 'OSC'
PRP DATE '9/18/2013'
PRP DESC 'OSC, 10MHZ, 3.3V, 100PPB, DCTCXO, SMT'
PRP MAXTEMP '85C'
PRP MFG_Name 'SITIME'
PRP MFG_PART_NUM 'SiT5356AI-FQA33-IT-10.000000'
PRP MINTEMP '-30C'
PRP MODIFY_DATE '9/18/2013'
PRP OTHER ''
PRP P1 'OSC'
PRP P2 '3.3V'
PRP P3 '100PPB'
PRP SHEETPART ''
PRP SIZE '5.0X3.2MM'
PRP SUB ''
PRP VALUE '10MHZ'
PRP VELENTIUM_PART_NUM '<V PART NUM>'
TOP 0 3.4385827 3.0517874 0 N 43 1 U13-1
TOP 1 3.4444882 2.995685 0 N 40 2 U13-2
TOP 2 3.4444882 2.948441 0 N 0 249 U13-3
TOP 3 3.4385827 2.8923386 0 N 136 191 U13-4
TOP 4 3.4848425 2.8923386 270 N 30 1 U13-5
TOP 5 3.5311023 2.8923386 0 N 102 1 U13-6
TOP 6 3.5251968 2.948441 0 N 0 248 U13-7
TOP 7 3.5251968 2.995685 0 N 0 247 U13-8
TOP 8 3.5311023 3.0517874 0 N 109 21 U13-9
TOP 9 3.4848425 3.0517874 270 N 39 2 U13-10
#
# CMP 39
CMP 28 3.4512205 3.3007087 90 N U11 SiT5721AI-KWA33-T-10.000000 ;0=1,1=0.0394
PRP CATEGORY 'OSC'
PRP DATE '9/18/2013'
PRP DESC 'OSC, 10MHZ, 3.3V, 5PPB, DCOCXO, SMT'
PRP MAXTEMP '85C'
PRP MFG_Name 'SITIME'
PRP MFG_PART_NUM 'SiT5721AI-KWA33-T-10.000000'
PRP MINTEMP '-30C'
PRP MODIFY_DATE '9/18/2013'
PRP OTHER ''
PRP P1 'OSC'
PRP P2 '3.3V'
PRP P3 '5PPB'
PRP SHEETPART ''
PRP SIZE '9.0X7.0MM'
PRP SUB ''
PRP VALUE '10MHZ'
PRP VELENTIUM_PART_NUM '<V PART NUM>'
TOP 0 3.5693307 3.3853543 90 N 0 250 U11-1
TOP 1 3.5102756 3.3951969 90 N 38 1 U11-2
TOP 2 3.4512205 3.3951969 90 N 40 3 U11-3
TOP 3 3.3921654 3.3951969 90 N 39 3 U11-4
TOP 4 3.3331103 3.3951969 270 N 136 192 U11-5
TOP 5 3.3331103 3.2062205 90 N 103 1 U11-6
TOP 6 3.3921654 3.2062205 90 N 0 252 U11-7
TOP 7 3.4512205 3.2062205 90 N 0 253 U11-8
TOP 8 3.5102756 3.2062205 90 N 0 251 U11-9
TOP 9 3.5693307 3.2062205 270 N 109 22 U11-10
#
# CMP 40
CMP 18 3.7789398 2.6898312 90 N U10 MAC-SA5X ;0=1,1=0.0000
PRP CATEGORY 'MOD'
PRP DATE ''
PRP DESC 'MOD, MAC, MAC-SA5X, ATOMIC CLOCK'
PRP MAXTEMP '85C'
PRP MFG_Name 'MICROCHIP'
PRP MFG_PART_NUM 'MAC-SA5X'
PRP MINTEMP '-40C'
PRP MODIFY_DATE '3/22/2006 1:36:44 PM'
PRP OTHER 'AEC-Q200'
PRP P1 'ATOMIC CLOCK'
PRP P2 ''
PRP P3 ''
PRP SHEETPART ''
PRP SIZE ''
PRP SUB ''
PRP VALUE 'RV-3049-C3'
PRP VELENTIUM_PART_NUM '<V PART NUM>'
TOP 0 4.0689017 1.5996232 270 N 78 1 U10-1
TOP 1 3.9114214 1.5996232 270 N 72 1 U10-2
TOP 2 4.0689017 1.6196232 270 N 77 1 U10-3
TOP 3 3.9114214 1.6196232 270 N 71 1 U10-4
TOP 4 4.0689017 1.6396232 270 N 80 4 U10-5
TOP 5 3.9114214 1.6396232 270 N 70 1 U10-6
TOP 6 4.0689017 1.6596232 270 N 79 1 U10-7
TOP 7 3.9114214 1.6596232 270 N 136 176 U10-8
TOP 8 4.0689017 1.6796232 270 N 136 175 U10-9
TOP 9 3.9114214 1.6796232 270 N 0 237 U10-10
TOP 10 4.0689017 1.6996232 270 N 0 235 U10-11
TOP 11 3.9114214 1.6996232 270 N 0 236 U10-12
TOP 12 4.0689017 1.7196232 270 N 0 233 U10-13
TOP 13 3.9114214 1.7196232 270 N 0 234 U10-14
TOP 14 4.0689017 1.7396232 270 N 136 174 U10-15
TOP 15 3.9114214 1.7396232 270 N 0 232 U10-16
TOP 16 4.0689017 1.7596232 270 N 76 3 U10-17
TOP 17 3.9114214 1.7596232 270 N 0 231 U10-18
TOP 18 4.0689017 1.7796232 270 N 75 1 U10-19
TOP 19 3.9114214 1.7796232 270 N 83 1 U10-20
TOP 20 5.5781524 0.8906186 90 N 42 1 U10-P1
TOP 21 5.5781524 1.6898312 90 N 136 39 U10-P2
TOP 22 5.5781524 2.4890438 90 N 42 0 U10-P3
TOP 23 3.9797272 2.4890438 90 N 136 38 U10-P4
TOP 24 3.9797272 0.8906186 90 N 146 5 U10-P5
TOP 25 4.0624044 2.595343 90 N 82 0 U10-P6
TOP 26 4.1805146 2.595343 90 N 74 0 U10-P7
TOP 27 4.2986248 2.595343 90 N 73 0 U10-P8
#
# CMP 41
CMP 22 2.6628937 2.7167323 270 N U9 RCB-F9T ;0=1,1=0.0000
PRP CATEGORY 'MOD'
PRP DATE ''
PRP DESC 'MOD BLE 4.2'
PRP MAXTEMP '80C'
PRP MFG_Name 'UBLOCKS'
PRP MFG_PART_NUM 'RCB-F9T'
PRP MINTEMP '-40C'
PRP MODIFY_DATE '9/11/13'
PRP OTHER ''
PRP P1 'GPS'
PRP P2 ''
PRP P3 ''
PRP SHEETPART ''
PRP SIZE ''
PRP SUB ''
PRP Supplier_1 'Digi-Key'
PRP Supplier_Part_Number_1 '672-RCB-F9T-ND'
PRP VELENTIUM_PART_NUM '<V PART NUM>'
TOP 0 2.4223425 3.4438977 270 N 0 6 U9-0
TOP 1 2.4223425 3.601378 270 N 0 7 U9-0
TOP 2 2.5098425 3.640748 270 N 146 9 U9-1
TOP 3 2.3348425 3.640748 270 N 138 6 U9-2
TOP 4 2.5098425 3.5620079 270 N 2 1 U9-3
TOP 5 2.3348425 3.5620079 270 N 96 0 U9-4
TOP 6 2.5098425 3.4832677 270 N 4 1 U9-5
TOP 7 2.3348425 3.4832677 270 N 3 1 U9-6
TOP 8 2.5098425 3.4045276 270 N 93 0 U9-7
TOP 9 2.3348425 3.4045276 270 N 136 55 U9-8
#
# CMP 42
CMP 17 6.4498425 3.241063 90 N U8 BNO080 ;0=1,1=0.0000
PRP CATEGORY 'MOD'
PRP DATE ''
PRP DESC 'MOD, IMU, 5.2X3.8, SMT'
PRP MAXTEMP '+85C'
PRP MFG_Name 'HILLCREST'
PRP MFG_PART_NUM 'BNO080'
PRP MINTEMP '-40C'
PRP MODIFY_DATE '10/21/2013'
PRP OTHER 'IMU'
PRP P1 ''
PRP P2 ''
PRP P3 ''
PRP SHEETPART ''
PRP SIZE '5.2X3.8'
PRP SUB ''
PRP Supplier_1 'Digi-Key'
PRP Supplier_Part_Number_1 '1888-1000-1-ND'
PRP VALUE 'BNO080'
PRP VELENTIUM_PART_NUM '<V PART NUM>'
TOP 0 6.5113582 3.1524803 270 N 0 221 U8-1
TOP 1 6.4793701 3.1500197 90 N 136 172 U8-2
TOP 2 6.4598425 3.1500197 90 N 138 32 U8-3
TOP 3 6.44 3.1500197 90 N 91 1 U8-4
TOP 4 6.4203149 3.1500197 90 N 84 1 U8-5
TOP 5 6.3883268 3.1524803 270 N 85 1 U8-6
TOP 6 6.3883268 3.1721654 270 N 0 222 U8-7
TOP 7 6.3883268 3.1918504 270 N 0 223 U8-8
TOP 8 6.3883268 3.2115354 270 N 0 224 U8-9
TOP 9 6.3883268 3.2312205 270 N 90 1 U8-10
TOP 10 6.3883268 3.2509055 270 N 86 1 U8-11
TOP 11 6.3883268 3.2705906 270 N 0 225 U8-12
TOP 12 6.3883268 3.2902756 270 N 0 226 U8-13
TOP 13 6.3883268 3.3099606 270 N 87 1 U8-14
TOP 14 6.3883268 3.3296457 270 N 89 1 U8-15
TOP 15 6.4203149 3.3321063 270 N 88 1 U8-16
TOP 16 6.44 3.3321063 270 N 68 1 U8-17
TOP 17 6.459685 3.3321063 270 N 104 1 U8-18
TOP 18 6.4793701 3.3321063 270 N 41 1 U8-19
TOP 19 6.5113582 3.3296457 270 N 69 1 U8-20
TOP 20 6.5113582 3.3099606 270 N 0 227 U8-21
TOP 21 6.5113582 3.2902756 270 N 0 228 U8-22
TOP 22 6.5113582 3.2705906 270 N 0 229 U8-23
TOP 23 6.5113582 3.2509055 270 N 0 230 U8-24
TOP 24 6.5113582 3.2312205 270 N 136 173 U8-25
TOP 25 6.5113582 3.2115354 270 N 16 1 U8-26
TOP 26 6.5113582 3.1918504 270 N 15 1 U8-27
TOP 27 6.5113582 3.1721654 270 N 138 33 U8-28
#
# CMP 43
CMP 32 3.8798425 3.771063 0 N U6 FT230XS-R ;0=1,1=0.0669
PRP CATEGORY 'IC, TCVR'
PRP DATE ''
PRP DESC 'IC, TCVR, FT230, USB TO UART, 5V, FTDI, 16SSOP'
PRP MAXTEMP '85C'
PRP MFG_Name 'FTDI'
PRP MFG_PART_NUM 'FT230XS-R'
PRP MINTEMP '-40C'
PRP MODIFY_DATE '8/14/2013'
PRP OTHER ''
PRP P1 'USB TO UART'
PRP P2 '5V'
PRP P3 'FTDI'
PRP SHEETPART ''
PRP SIZE '20SSOP'
PRP SUB ''
PRP Supplier_1 'Digi-Key'
PRP Supplier_Part_Number_1 '768-1135-1-ND'
PRP VALUE 'FT230XS'
PRP VELENTIUM_PART_NUM '<V PART NUM>'
TOP 0 3.772559 3.858563 270 N 139 0 U6-1
TOP 1 3.772559 3.833563 270 N 0 29 U6-2
TOP 2 3.772559 3.808563 270 N 32 0 U6-3
TOP 3 3.772559 3.783563 270 N 140 0 U6-4
TOP 4 3.772559 3.758563 270 N 136 56 U6-5
TOP 5 3.772559 3.733563 270 N 0 30 U6-6
TOP 6 3.772559 3.708563 270 N 0 31 U6-7
TOP 7 3.772559 3.683563 270 N 46 0 U6-8
TOP 8 3.9871259 3.683563 270 N 47 0 U6-9
TOP 9 3.9871259 3.708563 270 N 32 1 U6-10
TOP 10 3.9871259 3.733563 270 N 27 0 U6-11
TOP 11 3.9871259 3.758563 270 N 1 0 U6-12
TOP 12 3.9871259 3.783563 270 N 136 57 U6-13
TOP 13 3.9871259 3.808563 270 N 0 34 U6-14
TOP 14 3.9871259 3.833563 270 N 0 33 U6-15
TOP 15 3.9871259 3.858563 270 N 0 32 U6-16
#
# CMP 44
CMP 26 3.1448425 4.0861023 0 N U5 HTST-105-01-L-DV-A ;0=1,1=0.0669
PRP CATEGORY 'CONN, HDR'
PRP DATE ''
PRP DESC 'CONN, HDR, 2X5, VERT, 0.1IN  SHROUDED, SMT, HTSH SERIES'
PRP MAXTEMP '125C'
PRP MFG_Name 'SAMTEC INC'
PRP MFG_PART_NUM 'HTST-105-01-L-DV-A'
PRP MINTEMP '-55C'
PRP MODIFY_DATE '10/10/2013'
PRP OTHER 'HTSH SERIES'
PRP P1 'VERT'
PRP P2 '0.1 IN'
PRP P3 'SHROUDED'
PRP SHEETPART ''
PRP SIZE 'SMT'
PRP SUB ''
PRP Supplier_1 'Digi-Key'
PRP Supplier_Part_Number_1 'SAM8809-ND'
PRP VALENTIUM_PART_NUM '<VALENTIUM>'
PRP VALUE '2X5'
TOP 0 2.9448425 3.951063 0 N 24 1 U5-1
TOP 1 2.9448425 4.2211417 0 N 136 189 U5-2
TOP 2 3.0448425 3.951063 0 N 44 1 U5-3
TOP 3 3.0448425 4.2211417 0 N 138 34 U5-4
TOP 4 3.1448425 3.951063 0 N 25 1 U5-5
TOP 5 3.1448425 4.2211417 0 N 138 35 U5-6
TOP 6 3.2448425 3.951063 0 N 0 245 U5-7
TOP 7 3.2448425 4.2211417 0 N 0 246 U5-8
TOP 8 3.3448425 3.951063 0 N 26 1 U5-9
TOP 9 3.3448425 4.2211417 0 N 136 190 U5-10
TOP 10 3.2948425 4.0861024 0 N 0 26 U5-empty-1
TOP 11 2.9948425 4.0861024 0 N 0 25 U5-empty-2
#
# CMP 45
CMP 31 6.2548425 2.316063 180 N U2 MP1482DS-LF ;0=1,1=0.0700
PRP CATEGORY 'IC, DC/DC'
PRP DATE ''
PRP DESC 'IC, DC/DC, MP1482DS, >4.75VIN, 0.923-15V OUT, SOIC8'
PRP MAXTEMP '+85C'
PRP MFG_Name 'MPS'
PRP MFG_PART_NUM 'MP1482DS-LF'
PRP MINTEMP '-40C'
PRP MODIFY_DATE '12/27/2005 8:34:25 AM'
PRP OTHER 'additional spec'
PRP P1 '>4.75V IN'
PRP P2 '0.923-15V OUT'
PRP P3 'W'
PRP SHEETPART ''
PRP SIZE '8SOIC'
PRP SUB ''
PRP Supplier_1 'Digi-Key'
PRP Supplier_Part_Number_1 '1589-1524-1-ND'
PRP VALUE 'MP1482DS'
PRP VELENTIUM_PART_NUM '<V PART NUM>'
TOP 0 6.3522834 2.241063 180 N 67 1 U2-1
TOP 1 6.3522834 2.291063 180 N 143 9 U2-2
TOP 2 6.3522834 2.341063 180 N 66 2 U2-3
TOP 3 6.3522834 2.391063 180 N 136 193 U2-4
TOP 4 6.1574016 2.391063 180 N 23 2 U2-5
TOP 5 6.1574016 2.341063 180 N 59 1 U2-6
TOP 6 6.1574016 2.291063 180 N 21 1 U2-7
TOP 7 6.1574016 2.241063 180 N 60 1 U2-8
#
# CMP 46
CMP 31 6.7348425 1.956063 0 N U1 MP1482DS-LF ;0=1,1=0.0700
PRP CATEGORY 'IC, DC/DC'
PRP DATE ''
PRP DESC 'IC, DC/DC, MP1482DS, >4.75VIN, 0.923-15V OUT, SOIC8'
PRP MAXTEMP '+85C'
PRP MFG_Name 'MPS'
PRP MFG_PART_NUM 'MP1482DS-LF'
PRP MINTEMP '-40C'
PRP MODIFY_DATE '12/27/2005 8:34:25 AM'
PRP OTHER 'additional spec'
PRP P1 '>4.75V IN'
PRP P2 '0.923-15V OUT'
PRP P3 'W'
PRP SHEETPART ''
PRP SIZE '8SOIC'
PRP SUB ''
PRP Supplier_1 'Digi-Key'
PRP Supplier_Part_Number_1 '1589-1524-1-ND'
PRP VALUE 'MP1482DS'
PRP VELENTIUM_PART_NUM '<V PART NUM>'
TOP 0 6.6374016 2.031063 0 N 65 0 U1-1
TOP 1 6.6374016 1.981063 0 N 143 1 U1-2
TOP 2 6.6374016 1.931063 0 N 64 0 U1-3
TOP 3 6.6374016 1.881063 0 N 136 58 U1-4
TOP 4 6.8322834 1.881063 0 N 22 0 U1-5
TOP 5 6.8322834 1.931063 0 N 62 0 U1-6
TOP 6 6.8322834 1.981063 0 N 45 0 U1-7
TOP 7 6.8322834 2.031063 0 N 63 0 U1-8
#
# CMP 47
CMP 16 5.6112205 3.8444882 180 N SW1 L101011MS02Q ;0=2,1=0.0000
PRP CATEGORY 'SW'
PRP DATE '9/5/2013'
PRP DESC 'SW, SPST, 250V, 2A, SLIDE, ON-OFF, TH'
PRP MAXTEMP '85C'
PRP MFG_Name 'C&K'
PRP MFG_PART_NUM 'L101011MS02Q'
PRP MINTEMP '-25C'
PRP MODIFY_DATE '1/21/2014'
PRP OTHER 'L101011MS02Q'
PRP P1 '250V'
PRP P2 '2A'
PRP P3 'SW, SPST, 250V, 2A, SLIDE, ON-OFF, TH'
PRP SHEETPART ''
PRP SIZE '19.1X10.79MM'
PRP SUB ''
PRP Supplier_1 'Digi-Key'
PRP Supplier_Part_Number_1 'CKC5106-ND'
PRP VALENTIUM_PART_NUM '<VALENTIUM>'
PRP VALUE 'SW-SPST'
TOP 0 5.7234252 4.0255906 180 N 54 0 SW1-1
TOP 1 5.7234252 3.8444882 180 N 56 0 SW1-2
#
# CMP 48
CMP 20 5.0248425 4.206063 0 N S6 B3U-1000P ;0=1,1=0.0630
PRP CATEGORY 'SW'
PRP DATE ''
PRP DESC 'SW, SPST-NO, TACT, 12V, 50MA, 3X2.5MM SMT, B3U SERIES'
PRP MAXTEMP '70C'
PRP MFG_Name 'OMRON'
PRP MFG_PART_NUM 'B3U-1000P'
PRP MINTEMP '-25C'
PRP MODIFY_DATE '9/5/2013'
PRP OTHER 'B3U SERIES'
PRP P1 '12V'
PRP P2 '50mA'
PRP P3 'TACT'
PRP SHEETPART ''
PRP SIZE '3X2.5MM'
PRP SUB ''
PRP Supplier_1 'Digi-Key'
PRP Supplier_Part_Number_1 'SW1020CT-ND'
PRP VALENTIUM_PART_NUM '<VALENTIUM>'
PRP VALUE 'SPST-NO'
TOP 0 4.9579134 4.206063 0 N 136 177 S6-1
TOP 1 5.0917716 4.206063 0 N 29 2 S6-2
#
# CMP 49
CMP 20 4.4998425 4.206063 0 N S5 B3U-1000P ;0=1,1=0.0630
PRP CATEGORY 'SW'
PRP DATE ''
PRP DESC 'SW, SPST-NO, TACT, 12V, 50MA, 3X2.5MM SMT, B3U SERIES'
PRP MAXTEMP '70C'
PRP MFG_Name 'OMRON'
PRP MFG_PART_NUM 'B3U-1000P'
PRP MINTEMP '-25C'
PRP MODIFY_DATE '9/5/2013'
PRP OTHER 'B3U SERIES'
PRP P1 '12V'
PRP P2 '50mA'
PRP P3 'TACT'
PRP SHEETPART ''
PRP SIZE '3X2.5MM'
PRP SUB ''
PRP Supplier_1 'Digi-Key'
PRP Supplier_Part_Number_1 'SW1020CT-ND'
PRP VALENTIUM_PART_NUM '<VALENTIUM>'
PRP VALUE 'SPST-NO'
TOP 0 4.4329134 4.206063 0 N 136 59 S5-1
TOP 1 4.5667716 4.206063 0 N 28 0 S5-2
#
# CMP 50
CMP 24 5.2398425 4.126063 180 N R35 ERJ-3EKF1001V ;0=1,1=0.0197
PRP CATEGORY 'RES'
PRP DATE '7/26/2013'
PRP DESC 'RES, 1.0K, 1%, 1/10W, TF, 0603'
PRP MAXTEMP '125C'
PRP MFG_Name 'PANASONIC'
PRP MFG_PART_NUM 'ERJ-3EKF1001V'
PRP MINTEMP '-55C'
PRP ModifyDate '7/25/2013'
PRP OTHER '100PPM'
PRP P1 '1%'
PRP P2 '1/10W'
PRP P3 'TF'
PRP SHEETPART ''
PRP SIZE '0603'
PRP SUB 'GENERIC'
PRP Supplier_1 'Digi-Key'
PRP Supplier_Part_Number_1 'P1.00KHCT-ND'
PRP VALUE '1.0K'
PRP VELENTIUM_PART_NUM '<VELENTIUM>'
TOP 0 5.2670079 4.126063 90 N 144 0 R35-1
TOP 1 5.2126772 4.126063 90 N 29 0 R35-2
#
# CMP 51
CMP 24 4.6798425 4.121063 180 N R34 ERJ-3EKF1001V ;0=1,1=0.0197
PRP CATEGORY 'RES'
PRP DATE '7/26/2013'
PRP DESC 'RES, 1.0K, 1%, 1/10W, TF, 0603'
PRP MAXTEMP '125C'
PRP MFG_Name 'PANASONIC'
PRP MFG_PART_NUM 'ERJ-3EKF1001V'
PRP MINTEMP '-55C'
PRP ModifyDate '7/25/2013'
PRP OTHER '100PPM'
PRP P1 '1%'
PRP P2 '1/10W'
PRP P3 'TF'
PRP SHEETPART ''
PRP SIZE '0603'
PRP SUB 'GENERIC'
PRP Supplier_1 'Digi-Key'
PRP Supplier_Part_Number_1 'P1.00KHCT-ND'
PRP VALUE '1.0K'
PRP VELENTIUM_PART_NUM '<VELENTIUM>'
TOP 0 4.7070079 4.121063 90 N 145 0 R34-1
TOP 1 4.6526772 4.121063 90 N 28 1 R34-2
#
# CMP 52
CMP 24 5.2398425 4.206063 0 N R33 ERJ-3EKF1002V ;0=1,1=0.0197
PRP CATEGORY 'RES'
PRP DATE '7/26/2013'
PRP DESC 'RES, 10K, 1%, 1/10W, TF, 0603'
PRP MAXTEMP '125C'
PRP MFG_Name 'PANASONIC'
PRP MFG_PART_NUM 'ERJ-3EKF1002V'
PRP MINTEMP '-55C'
PRP ModifyDate '7/25/2013'
PRP OTHER '100PPM'
PRP P1 '1%'
PRP P2 '1/10W'
PRP P3 'TF'
PRP SHEETPART ''
PRP SIZE '0603'
PRP SUB 'GENERIC'
PRP Supplier_1 'Digi-Key'
PRP Supplier_Part_Number_1 'P10.0KHCT-ND'
PRP VALUE '10K'
PRP VELENTIUM_PART_NUM '<VELENTIUM>'
TOP 0 5.2126771 4.206063 270 N 29 1 R33-1
TOP 1 5.2670078 4.206063 270 N 138 7 R33-2
#
# CMP 53
CMP 24 4.6798425 4.206063 0 N R32 ERJ-3EKF1002V ;0=1,1=0.0197
PRP CATEGORY 'RES'
PRP DATE '7/26/2013'
PRP DESC 'RES, 10K, 1%, 1/10W, TF, 0603'
PRP MAXTEMP '125C'
PRP MFG_Name 'PANASONIC'
PRP MFG_PART_NUM 'ERJ-3EKF1002V'
PRP MINTEMP '-55C'
PRP ModifyDate '7/25/2013'
PRP OTHER '100PPM'
PRP P1 '1%'
PRP P2 '1/10W'
PRP P3 'TF'
PRP SHEETPART ''
PRP SIZE '0603'
PRP SUB 'GENERIC'
PRP Supplier_1 'Digi-Key'
PRP Supplier_Part_Number_1 'P10.0KHCT-ND'
PRP VALUE '10K'
PRP VELENTIUM_PART_NUM '<VELENTIUM>'
TOP 0 4.6526771 4.206063 270 N 28 2 R32-1
TOP 1 4.7070078 4.206063 270 N 138 8 R32-2
#
# CMP 54
CMP 24 1.2439683 4.066063 270 N R31 ERJ-3EKF2000V ;0=1,1=0.0197
PRP CATEGORY 'RES'
PRP DATE '7/26/2013'
PRP DESC 'RES, 200 OHM, 1%, 1/10W, TF, 0603'
PRP MAXTEMP '125C'
PRP MFG_Name 'PANASONIC'
PRP MFG_PART_NUM 'ERJ-3EKF2000V'
PRP MINTEMP '-55C'
PRP ModifyDate '7/25/2013'
PRP OTHER '100PPM'
PRP P1 '1%'
PRP P2 '1/10W'
PRP P3 'TF'
PRP SHEETPART ''
PRP SIZE '0603'
PRP SUB 'GENERIC'
PRP Supplier_1 'Digi-Key'
PRP Supplier_Part_Number_1 'P200HCT-ND'
PRP VALUE '200 OHM'
PRP VELENTIUM_PART_NUM '<VELENTIUM>'
TOP 0 1.2439683 4.0388976 180 N 110 0 R31-1
TOP 1 1.2439683 4.0932283 180 N 48 0 R31-2
#
# CMP 55
CMP 24 1.0423017 4.066063 270 N R30 ERJ-3EKF2000V ;0=1,1=0.0197
PRP CATEGORY 'RES'
PRP DATE '7/26/2013'
PRP DESC 'RES, 200 OHM, 1%, 1/10W, TF, 0603'
PRP MAXTEMP '125C'
PRP MFG_Name 'PANASONIC'
PRP MFG_PART_NUM 'ERJ-3EKF2000V'
PRP MINTEMP '-55C'
PRP ModifyDate '7/25/2013'
PRP OTHER '100PPM'
PRP P1 '1%'
PRP P2 '1/10W'
PRP P3 'TF'
PRP SHEETPART ''
PRP SIZE '0603'
PRP SUB 'GENERIC'
PRP Supplier_1 'Digi-Key'
PRP Supplier_Part_Number_1 'P200HCT-ND'
PRP VALUE '200 OHM'
PRP VELENTIUM_PART_NUM '<VELENTIUM>'
TOP 0 1.0423017 4.0388976 180 N 111 0 R30-1
TOP 1 1.0423017 4.0932283 180 N 49 0 R30-2
#
# CMP 56
CMP 24 0.8406351 4.066063 270 N R29 ERJ-3EKF2000V ;0=1,1=0.0197
PRP CATEGORY 'RES'
PRP DATE '7/26/2013'
PRP DESC 'RES, 200 OHM, 1%, 1/10W, TF, 0603'
PRP MAXTEMP '125C'
PRP MFG_Name 'PANASONIC'
PRP MFG_PART_NUM 'ERJ-3EKF2000V'
PRP MINTEMP '-55C'
PRP ModifyDate '7/25/2013'
PRP OTHER '100PPM'
PRP P1 '1%'
PRP P2 '1/10W'
PRP P3 'TF'
PRP SHEETPART ''
PRP SIZE '0603'
PRP SUB 'GENERIC'
PRP Supplier_1 'Digi-Key'
PRP Supplier_Part_Number_1 'P200HCT-ND'
PRP VALUE '200 OHM'
PRP VELENTIUM_PART_NUM '<VELENTIUM>'
TOP 0 0.8406351 4.0388976 180 N 135 0 R29-1
TOP 1 0.8406351 4.0932283 180 N 18 0 R29-2
#
# CMP 57
CMP 24 0.6389685 4.066063 270 N R28 ERJ-3EKF2000V ;0=1,1=0.0197
PRP CATEGORY 'RES'
PRP DATE '7/26/2013'
PRP DESC 'RES, 200 OHM, 1%, 1/10W, TF, 0603'
PRP MAXTEMP '125C'
PRP MFG_Name 'PANASONIC'
PRP MFG_PART_NUM 'ERJ-3EKF2000V'
PRP MINTEMP '-55C'
PRP ModifyDate '7/25/2013'
PRP OTHER '100PPM'
PRP P1 '1%'
PRP P2 '1/10W'
PRP P3 'TF'
PRP SHEETPART ''
PRP SIZE '0603'
PRP SUB 'GENERIC'
PRP Supplier_1 'Digi-Key'
PRP Supplier_Part_Number_1 'P200HCT-ND'
PRP VALUE '200 OHM'
PRP VELENTIUM_PART_NUM '<VELENTIUM>'
TOP 0 0.6389685 4.0388976 180 N 134 0 R28-1
TOP 1 0.6389685 4.0932283 180 N 17 0 R28-2
#
# CMP 58
CMP 24 4.1398425 3.701063 180 N R27 ERJ-3EKF1002V ;0=1,1=0.0197
PRP CATEGORY 'RES'
PRP DATE '7/26/2013'
PRP DESC 'RES, 10K, 1%, 1/10W, TF, 0603'
PRP MAXTEMP '125C'
PRP MFG_Name 'PANASONIC'
PRP MFG_PART_NUM 'ERJ-3EKF1002V'
PRP MINTEMP '-55C'
PRP ModifyDate '7/25/2013'
PRP OTHER '100PPM'
PRP P1 '1%'
PRP P2 '1/10W'
PRP P3 'TF'
PRP SHEETPART ''
PRP SIZE '0603'
PRP SUB 'GENERIC'
PRP Supplier_1 'Digi-Key'
PRP Supplier_Part_Number_1 'P10.0KHCT-ND'
PRP VALUE '10K'
PRP VELENTIUM_PART_NUM '<VELENTIUM>'
TOP 0 4.1670079 3.701063 90 N 1 1 R27-1
TOP 1 4.1126772 3.701063 90 N 27 1 R27-2
#
# CMP 59
CMP 23 3.6848425 3.786063 180 N R26 ERJ-2RKF4990X ;0=1,1=0.0157
PRP CATEGORY 'RES'
PRP DATE '7/26/2013'
PRP DESC 'RES, 499. OHM, 1%, 1/16W, TF, AEC-Q200, 0402'
PRP MAXTEMP '155C'
PRP MFG_Name 'PANASONIC'
PRP MFG_PART_NUM 'ERJ-2RKF4990X'
PRP MINTEMP '-55C'
PRP ModifyDate '7/25/2013'
PRP OTHER '100PPM, AEC-Q200'
PRP P1 '1%'
PRP P2 '1/16W'
PRP P3 'TF'
PRP SHEETPART ''
PRP SIZE '0402'
PRP SUB 'GENERIC'
PRP Supplier_1 'Digi-Key'
PRP Supplier_Part_Number_1 'P499LCT-ND'
PRP VALUE '499. OHM'
PRP VELENTIUM_PART_NUM '<VELENTIUM>'
TOP 0 3.7015748 3.786063 90 N 140 2 R26-1
TOP 1 3.6681102 3.786063 90 N 50 1 R26-2
#
# CMP 60
CMP 23 3.6848425 3.861063 180 N R25 ERJ-2RKF4990X ;0=1,1=0.0157
PRP CATEGORY 'RES'
PRP DATE '7/26/2013'
PRP DESC 'RES, 499. OHM, 1%, 1/16W, TF, AEC-Q200, 0402'
PRP MAXTEMP '155C'
PRP MFG_Name 'PANASONIC'
PRP MFG_PART_NUM 'ERJ-2RKF4990X'
PRP MINTEMP '-55C'
PRP ModifyDate '7/25/2013'
PRP OTHER '100PPM, AEC-Q200'
PRP P1 '1%'
PRP P2 '1/16W'
PRP P3 'TF'
PRP SHEETPART ''
PRP SIZE '0402'
PRP SUB 'GENERIC'
PRP Supplier_1 'Digi-Key'
PRP Supplier_Part_Number_1 'P499LCT-ND'
PRP VALUE '499. OHM'
PRP VELENTIUM_PART_NUM '<VELENTIUM>'
TOP 0 3.7015748 3.861063 90 N 139 1 R25-1
TOP 1 3.6681102 3.861063 90 N 51 0 R25-2
#
# CMP 61
CMP 23 3.0551181 0.5905512 90 N R24 ERJ-2GE0R00X ;0=1,1=0.0157
PRP CATEGORY 'RES'
PRP DATE '7/26/2013'
PRP DESC 'RES, 0 OHM, 1%, 1/16W, TF, AEC-Q200, 0402'
PRP MAXTEMP '155C'
PRP MFG_Name 'PANASONIC'
PRP MFG_PART_NUM 'ERJ-2GE0R00X'
PRP MINTEMP '-55C'
PRP ModifyDate '7/25/2013'
PRP OTHER '100PPM, AEC-Q200'
PRP P1 '1%'
PRP P2 '1/16W'
PRP P3 'TF'
PRP SHEETPART ''
PRP SIZE '0402'
PRP SUB 'GENERIC'
PRP Supplier_1 'Digi-Key'
PRP Supplier_Part_Number_1 'P0.0JCT-ND'
PRP VALUE '0 OHM'
PRP VELENTIUM_PART_NUM '<VELENTIUM>'
TOP 0 3.0551181 0.6072835 0 N 114 1 R24-1
TOP 1 3.0551181 0.5738189 0 N 20 0 R24-2
#
# CMP 62
CMP 23 2.503937 0.5905512 90 N R23 ERJ-2GE0R00X ;0=1,1=0.0157
PRP CATEGORY 'RES'
PRP DATE '7/26/2013'
PRP DESC 'RES, 0 OHM, 1%, 1/16W, TF, AEC-Q200, 0402'
PRP MAXTEMP '155C'
PRP MFG_Name 'PANASONIC'
PRP MFG_PART_NUM 'ERJ-2GE0R00X'
PRP MINTEMP '-55C'
PRP ModifyDate '7/25/2013'
PRP OTHER '100PPM, AEC-Q200'
PRP P1 '1%'
PRP P2 '1/16W'
PRP P3 'TF'
PRP SHEETPART ''
PRP SIZE '0402'
PRP SUB 'GENERIC'
PRP Supplier_1 'Digi-Key'
PRP Supplier_Part_Number_1 'P0.0JCT-ND'
PRP VALUE '0 OHM'
PRP VELENTIUM_PART_NUM '<VELENTIUM>'
TOP 0 2.503937 0.6072835 0 N 114 2 R23-1
TOP 1 2.503937 0.5738189 0 N 19 0 R23-2
#
# CMP 63
CMP 24 2.1468425 2.652063 270 N R22 ERJ-3EKF4701V ;0=1,1=0.0197
PRP CATEGORY 'RES'
PRP DATE '7/26/2013'
PRP DESC 'RES, 4.7K, 1%, 1/10W, TF, 0603'
PRP MAXTEMP '125C'
PRP MFG_Name 'PANASONIC'
PRP MFG_PART_NUM 'ERJ-3EKF4701V'
PRP MINTEMP '-55C'
PRP ModifyDate '7/25/2013'
PRP OTHER '100PPM'
PRP P1 '1%'
PRP P2 '1/10W'
PRP P3 'TF'
PRP SHEETPART ''
PRP SIZE '0603'
PRP SUB 'GENERIC'
PRP Supplier_1 'Digi-Key'
PRP Supplier_Part_Number_1 'P4.70KHCT-ND'
PRP VALUE '4.7K'
PRP VELENTIUM_PART_NUM '<VELENTIUM>'
TOP 0 2.1468425 2.6248976 180 N 125 1 R22-1
TOP 1 2.1468425 2.6792283 180 N 138 9 R22-2
#
# CMP 64
CMP 25 3.3498425 3.706063 270 N R21 CRCW080533R0FKEA ;0=1,1=0.0197
PRP CATEGORY 'RES'
PRP DATE ''
PRP DESC 'RES, 33 OHM, 1%, 1/8W, TF, 0805'
PRP MAXTEMP '125C'
PRP MFG_Name 'VISHAY/DALE'
PRP MFG_PART_NUM 'CRCW080533R0FKEA'
PRP MINTEMP '-55C'
PRP ModifyDate '7/26/2013'
PRP OTHER '100PPM'
PRP P1 '1%'
PRP P2 '1/8W'
PRP P3 'TF'
PRP SHEETPART ''
PRP SIZE '0805'
PRP SUB ''
PRP Supplier_1 'Digi-Key'
PRP Supplier_Part_Number_1 '541-33.0CCT-ND'
PRP VALUE '33 OHM'
PRP VELENTIUM_PART_NUM '<VELENTIUM>'
TOP 0 3.3498425 3.6666929 180 N 147 1 R21-1
TOP 1 3.3498425 3.7454331 180 N 26 0 R21-2
#
# CMP 65
CMP 25 3.1448425 3.706063 270 N R20 CRCW080533R0FKEA ;0=1,1=0.0197
PRP CATEGORY 'RES'
PRP DATE ''
PRP DESC 'RES, 33 OHM, 1%, 1/8W, TF, 0805'
PRP MAXTEMP '125C'
PRP MFG_Name 'VISHAY/DALE'
PRP MFG_PART_NUM 'CRCW080533R0FKEA'
PRP MINTEMP '-55C'
PRP ModifyDate '7/26/2013'
PRP OTHER '100PPM'
PRP P1 '1%'
PRP P2 '1/8W'
PRP P3 'TF'
PRP SHEETPART ''
PRP SIZE '0805'
PRP SUB ''
PRP Supplier_1 'Digi-Key'
PRP Supplier_Part_Number_1 '541-33.0CCT-ND'
PRP VALUE '33 OHM'
PRP VELENTIUM_PART_NUM '<VELENTIUM>'
TOP 0 3.1448425 3.6666929 180 N 137 0 R20-1
TOP 1 3.1448425 3.7454331 180 N 25 0 R20-2
#
# CMP 66
CMP 25 3.0448425 3.706063 270 N R19 CRCW080533R0FKEA ;0=1,1=0.0197
PRP CATEGORY 'RES'
PRP DATE ''
PRP DESC 'RES, 33 OHM, 1%, 1/8W, TF, 0805'
PRP MAXTEMP '125C'
PRP MFG_Name 'VISHAY/DALE'
PRP MFG_PART_NUM 'CRCW080533R0FKEA'
PRP MINTEMP '-55C'
PRP ModifyDate '7/26/2013'
PRP OTHER '100PPM'
PRP P1 '1%'
PRP P2 '1/8W'
PRP P3 'TF'
PRP SHEETPART ''
PRP SIZE '0805'
PRP SUB ''
PRP Supplier_1 'Digi-Key'
PRP Supplier_Part_Number_1 '541-33.0CCT-ND'
PRP VALUE '33 OHM'
PRP VELENTIUM_PART_NUM '<VELENTIUM>'
TOP 0 3.0448425 3.6666929 180 N 141 0 R19-1
TOP 1 3.0448425 3.7454331 180 N 44 0 R19-2
#
# CMP 67
CMP 25 2.9448425 3.706063 270 N R18 CRCW080533R0FKEA ;0=1,1=0.0197
PRP CATEGORY 'RES'
PRP DATE ''
PRP DESC 'RES, 33 OHM, 1%, 1/8W, TF, 0805'
PRP MAXTEMP '125C'
PRP MFG_Name 'VISHAY/DALE'
PRP MFG_PART_NUM 'CRCW080533R0FKEA'
PRP MINTEMP '-55C'
PRP ModifyDate '7/26/2013'
PRP OTHER '100PPM'
PRP P1 '1%'
PRP P2 '1/8W'
PRP P3 'TF'
PRP SHEETPART ''
PRP SIZE '0805'
PRP SUB ''
PRP Supplier_1 'Digi-Key'
PRP Supplier_Part_Number_1 '541-33.0CCT-ND'
PRP VALUE '33 OHM'
PRP VELENTIUM_PART_NUM '<VELENTIUM>'
TOP 0 2.9448425 3.6666929 180 N 142 0 R18-1
TOP 1 2.9448425 3.7454331 180 N 24 0 R18-2
#
# CMP 68
CMP 24 6.0048425 2.366063 90 N R9 ERJ-3EKF2201V ;0=1,1=0.0197
PRP CATEGORY 'RES'
PRP DATE '8/15/2013'
PRP DESC 'RES, 2.2K, 1%, 1/10W, TF, 0603'
PRP MAXTEMP '125C'
PRP MFG_Name 'PANASONIC'
PRP MFG_PART_NUM 'ERJ-3EKF2201V'
PRP MINTEMP '-55C'
PRP ModifyDate '8/15/2013'
PRP OTHER '100PPM'
PRP P1 '1%'
PRP P2 '1/10W'
PRP P3 'TF'
PRP SHEETPART ''
PRP SIZE '0603'
PRP SUB 'GENERIC'
PRP Supplier_1 'Digi-Key'
PRP Supplier_Part_Number_1 'P2.20KHCT-ND'
PRP VALUE '2.2K'
PRP VELENTIUM_PART_NUM '<VELENTIUM>'
TOP 0 6.0048425 2.3932284 0 N 136 60 R9-1
TOP 1 6.0048425 2.3388977 0 N 58 0 R9-2
#
# CMP 69
CMP 24 7.0098425 1.911063 90 N R8 ERJ-3EKF2201V ;0=1,1=0.0197
PRP CATEGORY 'RES'
PRP DATE '8/15/2013'
PRP DESC 'RES, 2.2K, 1%, 1/10W, TF, 0603'
PRP MAXTEMP '125C'
PRP MFG_Name 'PANASONIC'
PRP MFG_PART_NUM 'ERJ-3EKF2201V'
PRP MINTEMP '-55C'
PRP ModifyDate '8/15/2013'
PRP OTHER '100PPM'
PRP P1 '1%'
PRP P2 '1/10W'
PRP P3 'TF'
PRP SHEETPART ''
PRP SIZE '0603'
PRP SUB 'GENERIC'
PRP Supplier_1 'Digi-Key'
PRP Supplier_Part_Number_1 'P2.20KHCT-ND'
PRP VALUE '2.2K'
PRP VELENTIUM_PART_NUM '<VELENTIUM>'
TOP 0 7.0098425 1.9382284 0 N 136 61 R8-1
TOP 1 7.0098425 1.8838977 0 N 61 0 R8-2
#
# CMP 70
CMP 24 6.3398425 2.451063 180 N R7 ERJ-3EKF1002V ;0=1,1=0.0197
PRP CATEGORY 'RES'
PRP DATE '7/26/2013'
PRP DESC 'RES, 10K, 1%, 1/10W, TF, 0603'
PRP MAXTEMP '125C'
PRP MFG_Name 'PANASONIC'
PRP MFG_PART_NUM 'ERJ-3EKF1002V'
PRP MINTEMP '-55C'
PRP ModifyDate '7/25/2013'
PRP OTHER '100PPM'
PRP P1 '1%'
PRP P2 '1/10W'
PRP P3 'TF'
PRP SHEETPART ''
PRP SIZE '0603'
PRP SUB 'GENERIC'
PRP Supplier_1 'Digi-Key'
PRP Supplier_Part_Number_1 'P10.0KHCT-ND'
PRP VALUE '10K'
PRP VELENTIUM_PART_NUM '<VELENTIUM>'
TOP 0 6.3670079 2.451063 90 N 136 62 R7-1
TOP 1 6.3126772 2.451063 90 N 23 1 R7-2
#
# CMP 71
CMP 24 6.7548425 1.816063 0 N R6 ERJ-3EKF1002V ;0=1,1=0.0197
PRP CATEGORY 'RES'
PRP DATE '7/26/2013'
PRP DESC 'RES, 10K, 1%, 1/10W, TF, 0603'
PRP MAXTEMP '125C'
PRP MFG_Name 'PANASONIC'
PRP MFG_PART_NUM 'ERJ-3EKF1002V'
PRP MINTEMP '-55C'
PRP ModifyDate '7/25/2013'
PRP OTHER '100PPM'
PRP P1 '1%'
PRP P2 '1/10W'
PRP P3 'TF'
PRP SHEETPART ''
PRP SIZE '0603'
PRP SUB 'GENERIC'
PRP Supplier_1 'Digi-Key'
PRP Supplier_Part_Number_1 'P10.0KHCT-ND'
PRP VALUE '10K'
PRP VELENTIUM_PART_NUM '<VELENTIUM>'
TOP 0 6.7276771 1.816063 270 N 136 63 R6-1
TOP 1 6.7820078 1.816063 270 N 22 1 R6-2
#
# CMP 72
CMP 24 6.8698425 1.816063 0 N R4 ERJ-3EKF4702V ;0=1,1=0.0197
PRP CATEGORY 'RES'
PRP DATE '1/22/2014'
PRP DESC 'RES, 47K, 1%, 1/10W, TF, 0603'
PRP MAXTEMP '125C'
PRP MFG_Name 'PANASONIC'
PRP MFG_PART_NUM 'ERJ-3EKF4702V'
PRP MINTEMP '-55C'
PRP ModifyDate '1/22/2014'
PRP OTHER '100PPM'
PRP P1 '1%'
PRP P2 '1/10W'
PRP P3 'TF'
PRP SHEETPART ''
PRP SIZE '0603'
PRP SUB 'GENERIC'
PRP Supplier_1 'Digi-Key'
PRP Supplier_Part_Number_1 'P47.0KHCT-ND'
PRP VALUE '47K'
PRP VELENTIUM_PART_NUM '<VELENTIUM>'
TOP 0 6.8426771 1.816063 270 N 146 10 R4-1
TOP 1 6.8970078 1.816063 270 N 22 2 R4-2
#
# CMP 73
CMP 24 6.2348425 2.156063 90 N R3 ERJ-3EKF4702V ;0=1,1=0.0197
PRP CATEGORY 'RES'
PRP DATE '1/22/2014'
PRP DESC 'RES, 47K, 1%, 1/10W, TF, 0603'
PRP MAXTEMP '125C'
PRP MFG_Name 'PANASONIC'
PRP MFG_PART_NUM 'ERJ-3EKF4702V'
PRP MINTEMP '-55C'
PRP ModifyDate '1/22/2014'
PRP OTHER '100PPM'
PRP P1 '1%'
PRP P2 '1/10W'
PRP P3 'TF'
PRP SHEETPART ''
PRP SIZE '0603'
PRP SUB 'GENERIC'
PRP Supplier_1 'Digi-Key'
PRP Supplier_Part_Number_1 'P47.0KHCT-ND'
PRP VALUE '47K'
PRP VELENTIUM_PART_NUM '<VELENTIUM>'
TOP 0 6.2348425 2.1832284 0 N 21 0 R3-1
TOP 1 6.2348425 2.1288977 0 N 143 2 R3-2
#
# CMP 74
CMP 24 6.7498425 2.116063 270 N R2 ERJ-3EKF4702V ;0=1,1=0.0197
PRP CATEGORY 'RES'
PRP DATE '1/22/2014'
PRP DESC 'RES, 47K, 1%, 1/10W, TF, 0603'
PRP MAXTEMP '125C'
PRP MFG_Name 'PANASONIC'
PRP MFG_PART_NUM 'ERJ-3EKF4702V'
PRP MINTEMP '-55C'
PRP ModifyDate '1/22/2014'
PRP OTHER '100PPM'
PRP P1 '1%'
PRP P2 '1/10W'
PRP P3 'TF'
PRP SHEETPART ''
PRP SIZE '0603'
PRP SUB 'GENERIC'
PRP Supplier_1 'Digi-Key'
PRP Supplier_Part_Number_1 'P47.0KHCT-ND'
PRP VALUE '47K'
PRP VELENTIUM_PART_NUM '<VELENTIUM>'
TOP 0 6.7498425 2.0888976 180 N 45 1 R2-1
TOP 1 6.7498425 2.1432283 180 N 143 3 R2-2
#
# CMP 75
CMP 24 4.1777559 3.6033465 0 N R1 ERJ-3EKF2000V ;0=1,1=0.0197
PRP CATEGORY 'RES'
PRP DATE '7/26/2013'
PRP DESC 'RES, 200 OHM, 1%, 1/10W, TF, 0603'
PRP MAXTEMP '125C'
PRP MFG_Name 'PANASONIC'
PRP MFG_PART_NUM 'ERJ-3EKF2000V'
PRP MINTEMP '-55C'
PRP ModifyDate '7/25/2013'
PRP OTHER '100PPM'
PRP P1 '1%'
PRP P2 '1/10W'
PRP P3 'TF'
PRP SHEETPART ''
PRP SIZE '0603'
PRP SUB 'GENERIC'
PRP Supplier_1 'Digi-Key'
PRP Supplier_Part_Number_1 'P200HCT-ND'
PRP VALUE '200 OHM'
PRP VELENTIUM_PART_NUM '<VELENTIUM>'
TOP 0 4.1505905 3.6033465 270 N 136 64 R1-1
TOP 1 4.2049212 3.6033465 270 N 52 0 R1-2
#
# CMP 76
CMP 21 2.4468451 0.2450353 0 N P2 PCIex4 ;0=1,1=0.0000
PRP Manufacturer 'NA'
PRP NOTE 'NC'
PRP Part_Number '451'
PRP Part_Type 'SMT'
PRP Vendor_P/N 'NA'
TOP 0 1.7972451 0.1572953 0 N 114 0 P2-A1
TOP 1 1.8366151 0.1377953 0 N 112 3 P2-A2
TOP 2 1.8759851 0.1377953 0 N 112 2 P2-A3
TOP 3 1.9153551 0.1377953 0 N 136 15 P2-A4
TOP 4 1.9547251 0.1377953 0 N 0 1 P2-A5
TOP 5 1.9940951 0.1377953 0 N 0 2 P2-A6
TOP 6 2.0334651 0.1377953 0 N 0 3 P2-A7
TOP 7 2.0728351 0.1377953 0 N 0 4 P2-A8
TOP 8 2.1122051 0.1377953 0 N 113 3 P2-A9
TOP 9 2.1515751 0.1377953 0 N 113 2 P2-A10
TOP 10 2.1909451 0.1377953 0 N 125 0 P2-A11
TOP 11 2.3090551 0.1377953 0 N 136 7 P2-A12
TOP 12 2.3484251 0.1377953 0 N 5 1 P2-A13
TOP 13 2.3877951 0.1377953 0 N 6 1 P2-A14
TOP 14 2.4271651 0.1377953 0 N 136 6 P2-A15
TOP 15 2.4665351 0.1377953 0 N 7 1 P2-A16
TOP 16 2.5059051 0.1377953 0 N 8 1 P2-A17
TOP 17 2.5452751 0.1377953 0 N 136 14 P2-A18
TOP 18 2.5846451 0.1377953 0 N 0 5 P2-A19
TOP 19 2.6240151 0.1377953 0 N 136 13 P2-A20
TOP 20 2.6633851 0.1377953 0 N 9 1 P2-A21
TOP 21 2.7027551 0.1377953 0 N 57 1 P2-A22
TOP 22 2.7421251 0.1377953 0 N 136 10 P2-A23
TOP 23 2.7814951 0.1377953 0 N 136 8 P2-A24
TOP 24 2.8208651 0.1377953 0 N 10 1 P2-A25
TOP 25 2.8602351 0.1377953 0 N 11 1 P2-A26
TOP 26 2.8996051 0.1377953 0 N 136 12 P2-A27
TOP 27 2.9389751 0.1377953 0 N 136 9 P2-A28
TOP 28 2.9783451 0.1377953 0 N 12 1 P2-A29
TOP 29 3.0177151 0.1377953 0 N 13 1 P2-A30
TOP 30 3.0570851 0.1377953 0 N 136 11 P2-A31
TOP 31 3.0964551 0.1377953 0 N 0 0 P2-A32
TOP 32 1.7972451 0.1377953 0 N 112 6 P2-B1
TOP 33 1.8366151 0.1377953 0 N 112 5 P2-B2
TOP 34 1.8759851 0.1377953 0 N 112 4 P2-B3
TOP 35 1.9153551 0.1377953 0 N 136 184 P2-B4
TOP 36 1.9547251 0.1377953 0 N 0 242 P2-B5
TOP 37 1.9940951 0.1377953 0 N 0 243 P2-B6
TOP 38 2.0334651 0.1377953 0 N 136 183 P2-B7
TOP 39 2.0728351 0.1377953 0 N 113 4 P2-B8
TOP 40 2.1122051 0.1377953 0 N 0 239 P2-B9
TOP 41 2.1515751 0.1377953 0 N 0 238 P2-B10
TOP 42 2.1909451 0.1377953 0 N 0 244 P2-B11
TOP 43 2.3090551 0.1377953 0 N 0 240 P2-B12
TOP 44 2.3484251 0.1377953 0 N 136 186 P2-B13
TOP 45 2.3877951 0.1377953 0 N 133 1 P2-B14
TOP 46 2.4271651 0.1377953 0 N 132 1 P2-B15
TOP 47 2.4665351 0.1377953 0 N 136 187 P2-B16
TOP 48 2.5059051 0.1377953 0 N 19 1 P2-B17
TOP 49 2.5452751 0.1377953 0 N 136 188 P2-B18
TOP 50 2.5846451 0.1377953 0 N 131 1 P2-B19
TOP 51 2.6240151 0.1377953 0 N 130 1 P2-B20
TOP 52 2.6633851 0.1377953 0 N 136 182 P2-B21
TOP 53 2.7027551 0.1377953 0 N 136 181 P2-B22
TOP 54 2.7421251 0.1377953 0 N 129 1 P2-B23
TOP 55 2.7814951 0.1377953 0 N 128 1 P2-B24
TOP 56 2.8208651 0.1377953 0 N 136 185 P2-B25
TOP 57 2.8602351 0.1377953 0 N 136 180 P2-B26
TOP 58 2.8996051 0.1377953 0 N 127 1 P2-B27
TOP 59 2.9389751 0.1377953 0 N 126 1 P2-B28
TOP 60 2.9783451 0.1377953 0 N 136 179 P2-B29
TOP 61 3.0177151 0.1377953 0 N 0 241 P2-B30
TOP 62 3.0570851 0.1572953 0 N 20 1 P2-B31
TOP 63 3.0964551 0.1377953 0 N 136 178 P2-B32
#
# CMP 77
CMP 2 2.6084325 1.699543 0 N P1 MOD,_FPGA,_AC7100 ;0=1,1=0.0000
PRP CATEGORY 'MOD, FPGA'
PRP DATE ''
PRP DESC 'CONN, HDR, 2X40, VERT, .05, ALIGN, SMT, TFM-1XX'
PRP MAXTEMP 'C'
PRP MFG_Name 'Panasonic'
PRP MFG_PART_NUM 'AXK680337YG'
PRP MINTEMP 'C'
PRP MODIFY_DATE '10/10/2013'
PRP OTHER ''
PRP P1 'VERT'
PRP P2 '.05'
PRP P3 'ALIGN, LOCK'
PRP SHEETPART ''
PRP SIZE 'SMT'
PRP SUB ''
PRP VALENTIUM_PART_NUM '<VALENTIUM>'
TOP 0 3.6179425 0.916293 0 N 0 18 P1-1
TOP 1 1.6519425 2.486293 0 N 0 19 P1-1
TOP 2 1.6529425 0.916293 0 N 0 20 P1-1
TOP 3 3.6179425 2.486293 0 N 0 21 P1-1
TOP 4 3.4920225 2.087353 0 N 146 29 P1-1-1
TOP 5 3.6514625 2.087353 0 N 146 25 P1-1-2
TOP 6 3.4920225 2.067663 0 N 146 28 P1-1-3
TOP 7 3.6514625 2.067663 0 N 146 24 P1-1-4
TOP 8 3.4920225 2.047983 0 N 146 27 P1-1-5
TOP 9 3.6514625 2.047983 0 N 146 23 P1-1-6
TOP 10 3.4920225 2.028293 0 N 146 26 P1-1-7
TOP 11 3.6514625 2.028293 0 N 146 22 P1-1-8
TOP 12 3.4920225 2.008613 0 N 136 163 P1-1-9
TOP 13 3.6514625 2.008613 0 N 136 156 P1-1-10
TOP 14 3.4920225 1.988923 0 N 0 206 P1-1-11
TOP 15 3.6514625 1.988923 0 N 0 208 P1-1-12
TOP 16 3.4920225 1.969243 0 N 0 205 P1-1-13
TOP 17 3.6514625 1.969243 0 N 0 207 P1-1-14
TOP 18 3.4920225 1.949553 0 N 0 196 P1-1-15
TOP 19 3.6514625 1.949553 0 N 0 209 P1-1-16
TOP 20 3.4920225 1.929873 0 N 0 198 P1-1-17
TOP 21 3.6514625 1.929873 0 N 0 212 P1-1-18
TOP 22 3.4920225 1.910183 0 N 136 162 P1-1-19
TOP 23 3.6514625 1.910183 0 N 136 155 P1-1-20
TOP 24 3.4920225 1.890503 0 N 68 0 P1-1-21
TOP 25 3.6514625 1.890503 0 N 96 1 P1-1-22
TOP 26 3.4920225 1.870813 0 N 69 0 P1-1-23
TOP 27 3.6514625 1.870813 0 N 0 213 P1-1-24
TOP 28 3.4920225 1.851133 0 N 41 0 P1-1-25
TOP 29 3.6514625 1.851133 0 N 0 211 P1-1-26
TOP 30 3.4920225 1.831443 0 N 104 0 P1-1-27
TOP 31 3.6514625 1.831443 0 N 0 210 P1-1-28
TOP 32 3.4920225 1.811763 0 N 136 161 P1-1-29
TOP 33 3.6514625 1.811763 0 N 136 154 P1-1-30
TOP 34 3.4920225 1.792073 0 N 0 214 P1-1-31
TOP 35 3.6514625 1.792073 0 N 3 2 P1-1-32
TOP 36 3.4920225 1.772393 0 N 0 216 P1-1-33
TOP 37 3.6514625 1.772393 0 N 93 1 P1-1-34
TOP 38 3.4920225 1.752703 0 N 101 1 P1-1-35
TOP 39 3.6514625 1.752703 0 N 0 200 P1-1-36
TOP 40 3.4920225 1.733023 0 N 0 183 P1-1-37
TOP 41 3.6514625 1.733023 0 N 0 201 P1-1-38
TOP 42 3.4920225 1.713333 0 N 136 160 P1-1-39
TOP 43 3.6514625 1.713333 0 N 136 153 P1-1-40
TOP 44 3.4920225 1.693653 0 N 0 202 P1-1-41
TOP 45 3.6514625 1.693653 0 N 0 204 P1-1-42
TOP 46 3.4920225 1.673963 0 N 99 1 P1-1-43
TOP 47 3.6514625 1.673963 0 N 0 199 P1-1-44
TOP 48 3.4920225 1.654283 0 N 98 1 P1-1-45
TOP 49 3.6514625 1.654283 0 N 87 0 P1-1-46
TOP 50 3.4920225 1.634593 0 N 0 203 P1-1-47
TOP 51 3.6514625 1.634593 0 N 86 0 P1-1-48
TOP 52 3.4920225 1.614913 0 N 136 159 P1-1-49
TOP 53 3.6514625 1.614913 0 N 136 152 P1-1-50
TOP 54 3.4920225 1.595223 0 N 0 180 P1-1-51
TOP 55 3.6514625 1.595223 0 N 0 195 P1-1-52
TOP 56 3.4920225 1.575543 0 N 0 181 P1-1-53
TOP 57 3.6514625 1.575543 0 N 85 0 P1-1-54
TOP 58 3.4920225 1.555853 0 N 0 197 P1-1-55
TOP 59 3.6514625 1.555853 0 N 84 0 P1-1-56
TOP 60 3.4920225 1.536173 0 N 0 194 P1-1-57
TOP 61 3.6514625 1.536173 0 N 0 182 P1-1-58
TOP 62 3.4920225 1.516483 0 N 136 158 P1-1-59
TOP 63 3.6514625 1.516483 0 N 136 151 P1-1-60
TOP 64 3.4920225 1.496803 0 N 0 215 P1-1-61
TOP 65 3.6514625 1.496803 0 N 91 0 P1-1-62
TOP 66 3.4920225 1.477113 0 N 0 217 P1-1-63
TOP 67 3.6514625 1.477113 0 N 90 0 P1-1-64
TOP 68 3.4920225 1.457433 0 N 0 218 P1-1-65
TOP 69 3.6514625 1.457433 0 N 0 193 P1-1-66
TOP 70 3.4920225 1.437743 0 N 144 1 P1-1-67
TOP 71 3.6514625 1.437743 0 N 0 192 P1-1-68
TOP 72 3.4920225 1.418063 0 N 136 157 P1-1-69
TOP 73 3.6514625 1.418063 0 N 136 150 P1-1-70
TOP 74 3.4920225 1.398373 0 N 110 1 P1-1-71
TOP 75 3.6514625 1.398373 0 N 0 191 P1-1-72
TOP 76 3.4920225 1.378693 0 N 111 1 P1-1-73
TOP 77 3.6514625 1.378693 0 N 0 190 P1-1-74
TOP 78 3.4920225 1.359003 0 N 135 1 P1-1-75
TOP 79 3.6514625 1.359003 0 N 0 189 P1-1-76
TOP 80 3.4920225 1.339323 0 N 134 1 P1-1-77
TOP 81 3.6514625 1.339323 0 N 0 188 P1-1-78
TOP 82 3.4920225 1.319633 0 N 0 187 P1-1-79
TOP 83 3.6514625 1.319633 0 N 0 186 P1-1-80
TOP 84 2.2129725 2.358813 0 N 0 166 P1-2-1
TOP 85 2.2129725 2.518253 0 N 0 169 P1-2-2
TOP 86 2.2326625 2.358813 0 N 0 167 P1-2-3
TOP 87 2.2326625 2.518253 0 N 0 168 P1-2-4
TOP 88 2.2523425 2.358813 0 N 0 146 P1-2-5
TOP 89 2.2523425 2.518253 0 N 43 0 P1-2-6
TOP 90 2.2720325 2.358813 0 N 0 145 P1-2-7
TOP 91 2.2720325 2.518253 0 N 70 0 P1-2-8
TOP 92 2.2917125 2.358813 0 N 136 136 P1-2-9
TOP 93 2.2917125 2.518253 0 N 136 143 P1-2-10
TOP 94 2.3114025 2.358813 0 N 42 5 P1-2-11
TOP 95 2.3114025 2.518253 0 N 0 144 P1-2-12
TOP 96 2.3310825 2.358813 0 N 42 4 P1-2-13
TOP 97 2.3310825 2.518253 0 N 0 143 P1-2-14
TOP 98 2.3507725 2.358813 0 N 0 171 P1-2-15
TOP 99 2.3507725 2.518253 0 N 103 0 P1-2-16
TOP 100 2.3704525 2.358813 0 N 0 170 P1-2-17
TOP 101 2.3704525 2.518253 0 N 0 163 P1-2-18
TOP 102 2.3901425 2.358813 0 N 136 137 P1-2-19
TOP 103 2.3901425 2.518253 0 N 136 144 P1-2-20
TOP 104 2.4098225 2.358813 0 N 108 4 P1-2-21
TOP 105 2.4098225 2.518253 0 N 0 165 P1-2-22
TOP 106 2.4295125 2.358813 0 N 107 4 P1-2-23
TOP 107 2.4295125 2.518253 0 N 0 164 P1-2-24
TOP 108 2.4491925 2.358813 0 N 106 4 P1-2-25
TOP 109 2.4491925 2.518253 0 N 73 3 P1-2-26
TOP 110 2.4688825 2.358813 0 N 105 1 P1-2-27
TOP 111 2.4688825 2.518253 0 N 74 3 P1-2-28
TOP 112 2.4885625 2.358813 0 N 136 138 P1-2-29
TOP 113 2.4885625 2.518253 0 N 136 145 P1-2-30
TOP 114 2.5082525 2.358813 0 N 0 172 P1-2-31
TOP 115 2.5082525 2.518253 0 N 0 162 P1-2-32
TOP 116 2.5279325 2.358813 0 N 42 6 P1-2-33
TOP 117 2.5279325 2.518253 0 N 102 0 P1-2-34
TOP 118 2.5476225 2.358813 0 N 83 0 P1-2-35
TOP 119 2.5476225 2.518253 0 N 0 160 P1-2-36
TOP 120 2.5673025 2.358813 0 N 82 2 P1-2-37
TOP 121 2.5673025 2.518253 0 N 0 158 P1-2-38
TOP 122 2.5869925 2.358813 0 N 136 139 P1-2-39
TOP 123 2.5869925 2.518253 0 N 136 146 P1-2-40
TOP 124 2.6066725 2.358813 0 N 76 2 P1-2-41
TOP 125 2.6066725 2.518253 0 N 0 161 P1-2-42
TOP 126 2.6263625 2.358813 0 N 75 0 P1-2-43
TOP 127 2.6263625 2.518253 0 N 0 159 P1-2-44
TOP 128 2.6460425 2.358813 0 N 80 3 P1-2-45
TOP 129 2.6460425 2.518253 0 N 0 155 P1-2-46
TOP 130 2.6657325 2.358813 0 N 79 0 P1-2-47
TOP 131 2.6657325 2.518253 0 N 0 154 P1-2-48
TOP 132 2.6854125 2.358813 0 N 136 140 P1-2-49
TOP 133 2.6854125 2.518253 0 N 136 147 P1-2-50
TOP 134 2.7051025 2.358813 0 N 78 0 P1-2-51
TOP 135 2.7051025 2.518253 0 N 0 157 P1-2-52
TOP 136 2.7247825 2.358813 0 N 77 0 P1-2-53
TOP 137 2.7247825 2.518253 0 N 0 156 P1-2-54
TOP 138 2.7444725 2.358813 0 N 0 174 P1-2-55
TOP 139 2.7444725 2.518253 0 N 0 152 P1-2-56
TOP 140 2.7641525 2.358813 0 N 0 173 P1-2-57
TOP 141 2.7641525 2.518253 0 N 0 151 P1-2-58
TOP 142 2.7838425 2.358813 0 N 136 141 P1-2-59
TOP 143 2.7838425 2.518253 0 N 136 148 P1-2-60
TOP 144 2.8035225 2.358813 0 N 39 0 P1-2-61
TOP 145 2.8035225 2.518253 0 N 0 153 P1-2-62
TOP 146 2.8232125 2.358813 0 N 0 175 P1-2-63
TOP 147 2.8232125 2.518253 0 N 38 0 P1-2-64
TOP 148 2.8428925 2.358813 0 N 0 176 P1-2-65
TOP 149 2.8428925 2.518253 0 N 0 150 P1-2-66
TOP 150 2.8625825 2.358813 0 N 40 0 P1-2-67
TOP 151 2.8625825 2.518253 0 N 0 149 P1-2-68
TOP 152 2.8822625 2.358813 0 N 136 142 P1-2-69
TOP 153 2.8822625 2.518253 0 N 136 149 P1-2-70
TOP 154 2.9019525 2.358813 0 N 140 1 P1-2-71
TOP 155 2.9019525 2.518253 0 N 72 0 P1-2-72
TOP 156 2.9216325 2.358813 0 N 0 177 P1-2-73
TOP 157 2.9216325 2.518253 0 N 71 0 P1-2-74
TOP 158 2.9413225 2.358813 0 N 0 178 P1-2-75
TOP 159 2.9413225 2.518253 0 N 0 148 P1-2-76
TOP 160 2.9610025 2.358813 0 N 139 2 P1-2-77
TOP 161 2.9610025 2.518253 0 N 0 147 P1-2-78
TOP 162 2.9806925 2.358813 0 N 4 2 P1-2-79
TOP 163 2.9806925 2.518253 0 N 2 2 P1-2-80
TOP 164 1.7765525 1.319673 0 N 100 2 P1-3-1
TOP 165 1.6171125 1.319673 0 N 97 2 P1-3-2
TOP 166 1.7765525 1.339363 0 N 0 110 P1-3-3
TOP 167 1.6171125 1.339363 0 N 0 97 P1-3-4
TOP 168 1.7765525 1.359043 0 N 0 98 P1-3-5
TOP 169 1.6171125 1.359043 0 N 0 111 P1-3-6
TOP 170 1.7765525 1.378733 0 N 0 94 P1-3-7
TOP 171 1.6171125 1.378733 0 N 0 102 P1-3-8
TOP 172 1.7765525 1.398413 0 N 136 135 P1-3-9
TOP 173 1.6171125 1.398413 0 N 136 128 P1-3-10
TOP 174 1.7765525 1.418103 0 N 0 93 P1-3-11
TOP 175 1.6171125 1.418103 0 N 0 100 P1-3-12
TOP 176 1.7765525 1.437783 0 N 0 112 P1-3-13
TOP 177 1.6171125 1.437783 0 N 0 108 P1-3-14
TOP 178 1.7765525 1.457473 0 N 0 128 P1-3-15
TOP 179 1.6171125 1.457473 0 N 0 115 P1-3-16
TOP 180 1.7765525 1.477153 0 N 0 92 P1-3-17
TOP 181 1.6171125 1.477153 0 N 0 101 P1-3-18
TOP 182 1.7765525 1.496843 0 N 136 134 P1-3-19
TOP 183 1.6171125 1.496843 0 N 136 127 P1-3-20
TOP 184 1.7765525 1.516523 0 N 125 2 P1-3-21
TOP 185 1.6171125 1.516523 0 N 0 116 P1-3-22
TOP 186 1.7765525 1.536213 0 N 145 1 P1-3-23
TOP 187 1.6171125 1.536213 0 N 0 107 P1-3-24
TOP 188 1.7765525 1.555893 0 N 0 118 P1-3-25
TOP 189 1.6171125 1.555893 0 N 0 106 P1-3-26
TOP 190 1.7765525 1.575583 0 N 0 117 P1-3-27
TOP 191 1.6171125 1.575583 0 N 0 109 P1-3-28
TOP 192 1.7765525 1.595263 0 N 136 133 P1-3-29
TOP 193 1.6171125 1.595263 0 N 136 126 P1-3-30
TOP 194 1.7765525 1.614953 0 N 89 0 P1-3-31
TOP 195 1.6171125 1.614953 0 N 0 105 P1-3-32
TOP 196 1.7765525 1.634633 0 N 0 142 P1-3-33
TOP 197 1.6171125 1.634633 0 N 0 96 P1-3-34
TOP 198 1.7765525 1.654323 0 N 0 123 P1-3-35
TOP 199 1.6171125 1.654323 0 N 0 90 P1-3-36
TOP 200 1.7765525 1.674003 0 N 88 0 P1-3-37
TOP 201 1.6171125 1.674003 0 N 0 103 P1-3-38
TOP 202 1.7765525 1.693693 0 N 136 132 P1-3-39
TOP 203 1.6171125 1.693693 0 N 136 125 P1-3-40
TOP 204 1.7765525 1.713373 0 N 0 120 P1-3-41
TOP 205 1.6171125 1.713373 0 N 0 91 P1-3-42
TOP 206 1.7765525 1.733063 0 N 0 136 P1-3-43
TOP 207 1.6171125 1.733063 0 N 0 104 P1-3-44
TOP 208 1.7765525 1.752743 0 N 0 121 P1-3-45
TOP 209 1.6171125 1.752743 0 N 0 99 P1-3-46
TOP 210 1.7765525 1.772433 0 N 0 135 P1-3-47
TOP 211 1.6171125 1.772433 0 N 0 95 P1-3-48
TOP 212 1.7765525 1.792113 0 N 136 131 P1-3-49
TOP 213 1.6171125 1.792113 0 N 136 124 P1-3-50
TOP 214 1.7765525 1.811803 0 N 95 0 P1-3-51
TOP 215 1.6171125 1.811803 0 N 0 114 P1-3-52
TOP 216 1.7765525 1.831483 0 N 0 138 P1-3-53
TOP 217 1.6171125 1.831483 0 N 0 113 P1-3-54
TOP 218 1.7765525 1.851173 0 N 0 124 P1-3-55
TOP 219 1.6171125 1.851173 0 N 0 133 P1-3-56
TOP 220 1.7765525 1.870853 0 N 0 141 P1-3-57
TOP 221 1.6171125 1.870853 0 N 0 127 P1-3-58
TOP 222 1.7765525 1.890543 0 N 136 130 P1-3-59
TOP 223 1.6171125 1.890543 0 N 136 123 P1-3-60
TOP 224 1.7765525 1.910223 0 N 0 139 P1-3-61
TOP 225 1.6171125 1.910223 0 N 0 132 P1-3-62
TOP 226 1.7765525 1.929913 0 N 0 125 P1-3-63
TOP 227 1.6171125 1.929913 0 N 0 134 P1-3-64
TOP 228 1.7765525 1.949593 0 N 0 137 P1-3-65
TOP 229 1.6171125 1.949593 0 N 0 119 P1-3-66
TOP 230 1.7765525 1.969283 0 N 0 129 P1-3-67
TOP 231 1.6171125 1.969283 0 N 0 126 P1-3-68
TOP 232 1.7765525 1.988963 0 N 136 129 P1-3-69
TOP 233 1.6171125 1.988963 0 N 136 122 P1-3-70
TOP 234 1.7765525 2.008653 0 N 0 130 P1-3-71
TOP 235 1.6171125 2.008653 0 N 0 122 P1-3-72
TOP 236 1.7765525 2.028333 0 N 0 140 P1-3-73
TOP 237 1.6171125 2.028333 0 N 0 131 P1-3-74
TOP 238 1.7765525 2.048023 0 N 0 88 P1-3-75
TOP 239 1.6171125 2.048023 0 N 0 89 P1-3-76
TOP 240 1.7765525 2.067703 0 N 142 2 P1-3-77
TOP 241 1.6171125 2.067703 0 N 147 0 P1-3-78
TOP 242 1.7765525 2.087393 0 N 141 2 P1-3-79
TOP 243 1.6171125 2.087393 0 N 137 2 P1-3-80
TOP 244 2.9807025 1.038313 0 N 0 46 P1-4-1
TOP 245 2.9807025 0.878873 0 N 0 47 P1-4-2
TOP 246 2.9610125 1.038313 0 N 0 45 P1-4-3
TOP 247 2.9610125 0.878873 0 N 0 44 P1-4-4
TOP 248 2.9413325 1.038313 0 N 0 48 P1-4-5
TOP 249 2.9413325 0.878873 0 N 0 49 P1-4-6
TOP 250 2.9216425 1.038313 0 N 0 50 P1-4-7
TOP 251 2.9216425 0.878873 0 N 0 51 P1-4-8
TOP 252 2.9019625 1.038313 0 N 136 121 P1-4-9
TOP 253 2.9019625 0.878873 0 N 136 112 P1-4-10
TOP 254 2.8822725 1.038313 0 N 0 52 P1-4-11
TOP 255 2.8822725 0.878873 0 N 118 1 P1-4-12
TOP 256 2.8625925 1.038313 0 N 0 53 P1-4-13
TOP 257 2.8625925 0.878873 0 N 117 1 P1-4-14
TOP 258 2.8429025 1.038313 0 N 136 120 P1-4-15
TOP 259 2.8429025 0.878873 0 N 0 43 P1-4-16
TOP 260 2.8232225 1.038313 0 N 116 1 P1-4-17
TOP 261 2.8232225 0.878873 0 N 129 0 P1-4-18
TOP 262 2.8035325 1.038313 0 N 115 1 P1-4-19
TOP 263 2.8035325 0.878873 0 N 128 0 P1-4-20
TOP 264 2.7838525 1.038313 0 N 136 119 P1-4-21
TOP 265 2.7838525 0.878873 0 N 0 42 P1-4-22
TOP 266 2.7641625 1.038313 0 N 127 0 P1-4-23
TOP 267 2.7641625 0.878873 0 N 120 1 P1-4-24
TOP 268 2.7444825 1.038313 0 N 126 0 P1-4-25
TOP 269 2.7444825 0.878873 0 N 119 1 P1-4-26
TOP 270 2.7247925 1.038313 0 N 136 118 P1-4-27
TOP 271 2.7247925 0.878873 0 N 0 41 P1-4-28
TOP 272 2.7051125 1.038313 0 N 122 1 P1-4-29
TOP 273 2.7051125 0.878873 0 N 131 0 P1-4-30
TOP 274 2.6854225 1.038313 0 N 121 1 P1-4-31
TOP 275 2.6854225 0.878873 0 N 130 0 P1-4-32
TOP 276 2.6657425 1.038313 0 N 136 117 P1-4-33
TOP 277 2.6657425 0.878873 0 N 0 40 P1-4-34
TOP 278 2.6460525 1.038313 0 N 133 0 P1-4-35
TOP 279 2.6460525 0.878873 0 N 123 1 P1-4-36
TOP 280 2.6263725 1.038313 0 N 132 0 P1-4-37
TOP 281 2.6263725 0.878873 0 N 124 1 P1-4-38
TOP 282 2.6066825 1.038313 0 N 136 116 P1-4-39
TOP 283 2.6066825 0.878873 0 N 136 111 P1-4-40
TOP 284 2.5870025 1.038313 0 N 0 84 P1-4-41
TOP 285 2.5870025 0.878873 0 N 0 85 P1-4-42
TOP 286 2.5673125 1.038313 0 N 0 68 P1-4-43
TOP 287 2.5673125 0.878873 0 N 0 73 P1-4-44
TOP 288 2.5476325 1.038313 0 N 0 55 P1-4-45
TOP 289 2.5476325 0.878873 0 N 0 74 P1-4-46
TOP 290 2.5279425 1.038313 0 N 0 54 P1-4-47
TOP 291 2.5279425 0.878873 0 N 0 75 P1-4-48
TOP 292 2.5082625 1.038313 0 N 136 115 P1-4-49
TOP 293 2.5082625 0.878873 0 N 136 110 P1-4-50
TOP 294 2.4885725 1.038313 0 N 0 63 P1-4-51
TOP 295 2.4885725 0.878873 0 N 0 76 P1-4-52
TOP 296 2.4688925 1.038313 0 N 0 64 P1-4-53
TOP 297 2.4688925 0.878873 0 N 0 71 P1-4-54
TOP 298 2.4492025 1.038313 0 N 0 62 P1-4-55
TOP 299 2.4492025 0.878873 0 N 0 72 P1-4-56
TOP 300 2.4295225 1.038313 0 N 0 65 P1-4-57
TOP 301 2.4295225 0.878873 0 N 0 82 P1-4-58
TOP 302 2.4098325 1.038313 0 N 136 114 P1-4-59
TOP 303 2.4098325 0.878873 0 N 136 109 P1-4-60
TOP 304 2.3901525 1.038313 0 N 0 66 P1-4-61
TOP 305 2.3901525 0.878873 0 N 0 77 P1-4-62
TOP 306 2.3704625 1.038313 0 N 0 67 P1-4-63
TOP 307 2.3704625 0.878873 0 N 0 81 P1-4-64
TOP 308 2.3507825 1.038313 0 N 0 57 P1-4-65
TOP 309 2.3507825 0.878873 0 N 0 80 P1-4-66
TOP 310 2.3310925 1.038313 0 N 0 56 P1-4-67
TOP 311 2.3310925 0.878873 0 N 0 79 P1-4-68
TOP 312 2.3114125 1.038313 0 N 136 113 P1-4-69
TOP 313 2.3114125 0.878873 0 N 136 108 P1-4-70
TOP 314 2.2917225 1.038313 0 N 0 61 P1-4-71
TOP 315 2.2917225 0.878873 0 N 0 78 P1-4-72
TOP 316 2.2720425 1.038313 0 N 0 60 P1-4-73
TOP 317 2.2720425 0.878873 0 N 0 69 P1-4-74
TOP 318 2.2523525 1.038313 0 N 0 59 P1-4-75
TOP 319 2.2523525 0.878873 0 N 0 70 P1-4-76
TOP 320 2.2326725 1.038313 0 N 0 58 P1-4-77
TOP 321 2.2326725 0.878873 0 N 0 83 P1-4-78
TOP 322 2.2129825 1.038313 0 N 0 36 P1-4-79
TOP 323 2.2129825 0.878873 0 N 0 37 P1-4-80
TOP 324 3.0249925 0.958593 0 N 0 38 P1-81
TOP 325 1.6968325 1.275383 0 N 0 87 P1-81
TOP 326 2.1686825 2.438533 0 N 0 179 P1-81
TOP 327 3.5717425 2.131643 0 N 0 185 P1-81
TOP 328 2.9905425 0.958593 0 N 0 11 P1-82
TOP 329 1.6968325 1.309833 0 N 0 14 P1-82
TOP 330 2.2031325 2.438533 0 N 0 15 P1-82
TOP 331 3.5717425 2.097193 0 N 0 17 P1-82
TOP 332 2.9905325 2.438533 0 N 0 10 P1-83
TOP 333 2.2031425 0.958593 0 N 0 12 P1-83
TOP 334 1.6968325 2.097233 0 N 0 13 P1-83
TOP 335 3.5717425 1.309793 0 N 0 16 P1-83
TOP 336 3.0249825 2.438533 0 N 0 35 P1-84
TOP 337 2.1686925 0.958593 0 N 0 39 P1-84
TOP 338 1.6968325 2.131683 0 N 0 86 P1-84
TOP 339 3.5717425 1.275343 0 N 0 184 P1-84
#
# CMP 78
CMP 13 6.6798425 2.611063 90 N L2 PM124SH-100M-RC ;0=1,1=0.0000
PRP CATEGORY 'IND, PWR'
PRP DATE '10/23/2013'
PRP DESC 'IND, PWR, 10.uH, 20%, 4A, 0.04DCR, 12.5X12.5MM, SHLD'
PRP MAXTEMP '125C'
PRP MFG_Name 'BOURNS'
PRP MFG_PART_NUM 'PM124SH-100M-RC'
PRP MINTEMP '-40C'
PRP MODIFY_DATE '10/23/2013'
PRP OTHER 'SHLD'
PRP P1 '20%'
PRP P2 '4A'
PRP P3 '36mOhm'
PRP SHEETPART ''
PRP SIZE '12.5X12.5MM'
PRP SUB ''
PRP Supplier_1 'Digi-Key'
PRP Supplier_Part_Number_1 'PM124SH-100M-RCCT-ND'
PRP VALENTIUM_PART_NUM '<VALENTIUM>'
PRP VALUE '10.uH'
TOP 0 6.6798425 2.8020079 90 N 138 31 L2-1
TOP 1 6.6798425 2.4201181 90 N 66 1 L2-2
#
# CMP 79
CMP 13 6.3198425 1.651063 270 N L1 PM124SH-100M-RC ;0=1,1=0.0000
PRP CATEGORY 'IND, PWR'
PRP DATE '10/23/2013'
PRP DESC 'IND, PWR, 10.uH, 20%, 4A, 0.04DCR, 12.5X12.5MM, SHLD'
PRP MAXTEMP '125C'
PRP MFG_Name 'BOURNS'
PRP MFG_PART_NUM 'PM124SH-100M-RC'
PRP MINTEMP '-40C'
PRP MODIFY_DATE '10/23/2013'
PRP OTHER 'SHLD'
PRP P1 '20%'
PRP P2 '4A'
PRP P3 '36mOhm'
PRP SHEETPART ''
PRP SIZE '12.5X12.5MM'
PRP SUB ''
PRP Supplier_1 'Digi-Key'
PRP Supplier_Part_Number_1 'PM124SH-100M-RCCT-ND'
PRP VALENTIUM_PART_NUM '<VALENTIUM>'
PRP VALUE '10.uH'
TOP 0 6.3198425 1.4601181 270 N 146 11 L1-1
TOP 1 6.3198425 1.8420079 270 N 64 1 L1-2
#
# CMP 80
CMP 35 3.9344488 4.0237008 180 N J3 USB_B_1734035 ;0=1,1=0.1575
PRP CATEGORY 'CONN, REC'
PRP DATE ''
PRP DESC 'CONN, REC, USB, R/A, MINI, TYPE B, 5 POS, SMT W/BRD GUIDE'
PRP MAXTEMP 'C'
PRP MFG_Name 'TE CONNECTIVITY/AMP'
PRP MFG_PART_NUM '1734035-2'
PRP MINTEMP 'C'
PRP MODIFY_DATE '10/10/2013'
PRP OTHER 'USB'
PRP P1 'R/A'
PRP P2 '5 POS'
PRP P3 'USB MINI B'
PRP SHEETPART ''
PRP SIZE 'SMT'
PRP SUB ''
PRP Supplier_1 'Digi-Key'
PRP Supplier_Part_Number_1 'A31727CT-ND'
PRP VALENTIUM_PART_NUM '<VALENTIUM>'
PRP VALUE 'USB MINI B'
TOP 0 3.7848425 4.126063 180 N 0 27 J3-0
TOP 1 3.9580709 4.126063 180 N 0 28 J3-0
TOP 2 3.6962598 4.2441732 180 N 0 263 J3-0
TOP 3 3.6962598 4.0276378 180 N 0 264 J3-0
TOP 4 4.0466536 4.0276378 180 N 0 265 J3-0
TOP 5 4.0466536 4.2441732 180 N 0 266 J3-0
TOP 6 3.9344488 4.0237008 180 N 1 4 J3-1
TOP 7 3.9029528 4.0237008 180 N 47 1 J3-2
TOP 8 3.8714567 4.0237008 180 N 46 1 J3-3
TOP 9 3.8399606 4.0237008 180 N 0 262 J3-4
TOP 10 3.8084646 4.0237008 180 N 136 199 J3-5
#
# CMP 81
CMP 0 6.5694882 3.5895276 180 N J2 39-30-1060 ;0=2,1=0.0000
PRP CATEGORY 'CONN, HDR'
PRP DATE ''
PRP DESC 'CONN, HDR, 2X3, R/A, 2.5MM, TH, NANO-FIT'
PRP MAXTEMP '105C'
PRP MFG_Name 'MOLEX'
PRP MFG_PART_NUM '105314-1206'
PRP MINTEMP '-40C'
PRP MODIFY_DATE '10/10/2013'
PRP OTHER 'NANO-FIT'
PRP P1 'R/A'
PRP P2 '2.5MM'
PRP P3 ''
PRP SHEETPART ''
PRP SIZE 'TH'
PRP SUB ''
PRP Supplier_1 'Digi-Key'
PRP Supplier_Part_Number_1 'WM14977-ND'
PRP VALENTIUM_PART_NUM '<VALENTIUM>'
PRP VALUE '2X3'
TOP 0 6.5694882 4.0934646 180 N 0 8 J2-0
TOP 1 6.9001969 4.0934646 180 N 0 9 J2-0
TOP 2 6.5694882 3.806063 90 N 53 1 J2-1
TOP 3 6.7348425 3.806063 90 N 53 2 J2-2
TOP 4 6.9001969 3.806063 90 N 53 3 J2-3
TOP 5 6.5694882 3.5895276 90 N 136 29 J2-4
TOP 6 6.7348425 3.5895276 90 N 136 30 J2-5
TOP 7 6.9001969 3.5895276 90 N 136 31 J2-6
#
# CMP 82
CMP 8 6.1198425 3.8198425 270 N J1 PJ-002A ;0=2,1=0.0000
PRP CATEGORY 'CONN, JACK'
PRP DESC 'CONN, JACK, PJ-002A, 2.1X5.5MM, 24V 2.5A, R/A TH, SPST-NC'
PRP MAXTEMP '85C'
PRP MFG_Name 'CUI DEVICES'
PRP MFG_PART_NUM 'PJ-002A'
PRP MINTEMP '-25C'
PRP MODIFY_DATE ''
PRP OTHER 'SPST-NC'
PRP P1 '2.1X5.5MM'
PRP P2 '24V'
PRP P3 '2.5A'
PRP SHEETPART ''
PRP SIZE 'R/A TH'
PRP SUB ''
PRP Supplier_1 'Digi-Key'
PRP Supplier_Part_Number_1 'CP-002A-ND'
PRP VALENTIUM_PART_NUM '<VALENTIUM>'
PRP VALUE 'PJ-002A'
TOP 0 6.1198425 3.8198425 180 N 55 0 J1-1
TOP 1 6.1198425 4.056063 180 N 136 36 J1-2
TOP 2 5.9348031 3.9379527 90 N 136 37 J1-3
#
# CMP 83
CMP 14 4.1498425 2.816063 270 N FB3 MPZ1608_220OHM_0603 ;0=1,1=0.0374
PRP CATEGORY 'FERRITE'
PRP DATE '8/6/2013'
PRP DESC 'FER, 220 OHM, 100MHZ, 2.2A, 0.05OHM DC, MPZ1608, 0603'
PRP MAXTEMP '125C'
PRP MFG_Name 'TDK CORP'
PRP MFG_PART_NUM 'MPZ1608S221ATA00'
PRP MINTEMP '-55C'
PRP MODIFY_DATE '9/4/2013'
PRP OTHER 'MPZ1608'
PRP P1 '100MHZ'
PRP P2 '2.2A'
PRP P3 '0.05 OHM'
PRP SHEETPART ''
PRP SIZE '0603'
PRP SUB ''
PRP Supplier_1 'Digi-Key'
PRP Supplier_Part_Number_1 '445-1565-1-ND'
PRP VALENTIUM_PART_NUM '<VALENTIUM>'
PRP VALUE '220 OHM'
TOP 0 4.1498425 2.7898819 180 N 14 3 FB3-1
TOP 1 4.1498425 2.8422441 180 N 109 19 FB3-2
#
# CMP 84
CMP 14 4.4348425 2.816063 270 N FB2 MPZ1608_220OHM_0603 ;0=1,1=0.0374
PRP CATEGORY 'FERRITE'
PRP DATE '8/6/2013'
PRP DESC 'FER, 220 OHM, 100MHZ, 2.2A, 0.05OHM DC, MPZ1608, 0603'
PRP MAXTEMP '125C'
PRP MFG_Name 'TDK CORP'
PRP MFG_PART_NUM 'MPZ1608S221ATA00'
PRP MINTEMP '-55C'
PRP MODIFY_DATE '9/4/2013'
PRP OTHER 'MPZ1608'
PRP P1 '100MHZ'
PRP P2 '2.2A'
PRP P3 '0.05 OHM'
PRP SHEETPART ''
PRP SIZE '0603'
PRP SUB ''
PRP Supplier_1 'Digi-Key'
PRP Supplier_Part_Number_1 '445-1565-1-ND'
PRP VALENTIUM_PART_NUM '<VALENTIUM>'
PRP VALUE '220 OHM'
TOP 0 4.4348425 2.7898819 180 N 138 10 FB2-1
TOP 1 4.4348425 2.8422441 180 N 14 1 FB2-2
#
# CMP 85
CMP 12 6.0628425 3.556063 180 N F1 FUSE_0603_2.00A ;0=1,1=0.0197
PRP CATEGORY 'FUSE'
PRP DATE '20 OCT 15'
PRP DESC 'FUSE SLOW 1.25A 32V M 0603'
PRP MAXTEMP '105C'
PRP MFG_Name 'BOURNS'
PRP MFG_PART_NUM 'SF-0603S200-2'
PRP MINTEMP '-40C'
PRP MODIFY_DATE '9/4/2013'
PRP OTHER 'UL E141069'
PRP P1 'SLOW BLO'
PRP P2 '32V'
PRP P3 'M'
PRP SHEETPART ''
PRP SIZE '0603'
PRP SUB ''
PRP Supplier_1 'Digi-Key'
PRP Supplier_Part_Number_1 'SF-0603S200-2CT-ND'
PRP VALENTIUM_PART_NUM '<VALENTIUM>'
PRP VALUE '2.00A'
TOP 0 6.0900079 3.556063 90 N 54 2 F1-1
TOP 1 6.0356772 3.556063 90 N 143 8 F1-2
#
# CMP 86
CMP 10 1.0448425 0.906063 180 N D18 SMCJ6.5CA ;0=1,1=0.1031
PRP CATEGORY 'DIO, TVS'
PRP DATE ''
PRP DESC 'DIO, TVS, SMCJ6.5, 6.5V, BIDIR, 1.5KW, SMC'
PRP MAXTEMP '150C'
PRP MFG_Name 'LITTELFUSE'
PRP MFG_PART_NUM 'SMCJ6.5CA'
PRP MINTEMP '-55C'
PRP MODIFY_DATE '9/4/2013'
PRP OTHER 'SMCJ'
PRP P1 '6.5V'
PRP P2 'BIDIR'
PRP P3 '1.5KW'
PRP SHEETPART ''
PRP SIZE 'SMC'
PRP SUB ''
PRP Supplier_1 'Digi-Key'
PRP Supplier_Part_Number_1 'SMCJ6.5CALFCT-ND'
PRP VALENTIUM_PART_NUM '<VALENTIUM>'
PRP VALUE 'SMCJ6.5'
TOP 0 0.9326378 0.906063 90 N 105 2 D18-A
TOP 1 1.1570472 0.906063 90 N 136 170 D18-K
#
# CMP 87
CMP 10 1.0448425 1.431063 180 N D17 SMCJ6.5CA ;0=1,1=0.1031
PRP CATEGORY 'DIO, TVS'
PRP DATE ''
PRP DESC 'DIO, TVS, SMCJ6.5, 6.5V, BIDIR, 1.5KW, SMC'
PRP MAXTEMP '150C'
PRP MFG_Name 'LITTELFUSE'
PRP MFG_PART_NUM 'SMCJ6.5CA'
PRP MINTEMP '-55C'
PRP MODIFY_DATE '9/4/2013'
PRP OTHER 'SMCJ'
PRP P1 '6.5V'
PRP P2 'BIDIR'
PRP P3 '1.5KW'
PRP SHEETPART ''
PRP SIZE 'SMC'
PRP SUB ''
PRP Supplier_1 'Digi-Key'
PRP Supplier_Part_Number_1 'SMCJ6.5CALFCT-ND'
PRP VALENTIUM_PART_NUM '<VALENTIUM>'
PRP VALUE 'SMCJ6.5'
TOP 0 0.9326378 1.431063 90 N 106 2 D17-A
TOP 1 1.1570472 1.431063 90 N 136 65 D17-K
#
# CMP 88
CMP 10 1.0448425 2.481063 180 N D16 SMCJ6.5CA ;0=1,1=0.1031
PRP CATEGORY 'DIO, TVS'
PRP DATE ''
PRP DESC 'DIO, TVS, SMCJ6.5, 6.5V, BIDIR, 1.5KW, SMC'
PRP MAXTEMP '150C'
PRP MFG_Name 'LITTELFUSE'
PRP MFG_PART_NUM 'SMCJ6.5CA'
PRP MINTEMP '-55C'
PRP MODIFY_DATE '9/4/2013'
PRP OTHER 'SMCJ'
PRP P1 '6.5V'
PRP P2 'BIDIR'
PRP P3 '1.5KW'
PRP SHEETPART ''
PRP SIZE 'SMC'
PRP SUB ''
PRP Supplier_1 'Digi-Key'
PRP Supplier_Part_Number_1 'SMCJ6.5CALFCT-ND'
PRP VALENTIUM_PART_NUM '<VALENTIUM>'
PRP VALUE 'SMCJ6.5'
TOP 0 0.9326378 2.481063 90 N 108 2 D16-A
TOP 1 1.1570472 2.481063 90 N 136 66 D16-K
#
# CMP 89
CMP 10 1.0448425 1.956063 180 N D15 SMCJ6.5CA ;0=1,1=0.1031
PRP CATEGORY 'DIO, TVS'
PRP DATE ''
PRP DESC 'DIO, TVS, SMCJ6.5, 6.5V, BIDIR, 1.5KW, SMC'
PRP MAXTEMP '150C'
PRP MFG_Name 'LITTELFUSE'
PRP MFG_PART_NUM 'SMCJ6.5CA'
PRP MINTEMP '-55C'
PRP MODIFY_DATE '9/4/2013'
PRP OTHER 'SMCJ'
PRP P1 '6.5V'
PRP P2 'BIDIR'
PRP P3 '1.5KW'
PRP SHEETPART ''
PRP SIZE 'SMC'
PRP SUB ''
PRP Supplier_1 'Digi-Key'
PRP Supplier_Part_Number_1 'SMCJ6.5CALFCT-ND'
PRP VALENTIUM_PART_NUM '<VALENTIUM>'
PRP VALUE 'SMCJ6.5'
TOP 0 0.9326378 1.956063 90 N 107 2 D15-A
TOP 1 1.1570472 1.956063 90 N 136 67 D15-K
#
# CMP 90
CMP 9 1.2498423 4.226063 270 N D14 RED ;0=1,1=0.0236
PRP CATEGORY 'LED'
PRP DATE ''
PRP DESC 'LED, RED, SML-LX0603, 635NM, 2V, 20MA, 0603'
PRP MAXTEMP '85C'
PRP MFG_Name 'LUMEX'
PRP MFG_PART_NUM 'SML-LX0603IW-TR'
PRP MINTEMP '-25C'
PRP MODIFY_DATE '9/4/2013'
PRP OTHER 'SML-LX0603'
PRP P1 '635NM'
PRP P2 '2V'
PRP P3 '20MA'
PRP SHEETPART ''
PRP SIZE '0603'
PRP SUB ''
PRP Supplier_1 'Digi-Key'
PRP Supplier_Part_Number_1 '67-1548-1-ND'
PRP VALENTIUM_PART_NUM '<VALENTIUM>'
PRP VALUE 'RED'
TOP 0 1.2498423 4.1975197 180 N 48 1 D14-1
TOP 1 1.2498423 4.2546063 180 N 138 30 D14-2
#
# CMP 91
CMP 9 1.0481757 4.226063 270 N D13 RED ;0=1,1=0.0236
PRP CATEGORY 'LED'
PRP DATE ''
PRP DESC 'LED, RED, SML-LX0603, 635NM, 2V, 20MA, 0603'
PRP MAXTEMP '85C'
PRP MFG_Name 'LUMEX'
PRP MFG_PART_NUM 'SML-LX0603IW-TR'
PRP MINTEMP '-25C'
PRP MODIFY_DATE '9/4/2013'
PRP OTHER 'SML-LX0603'
PRP P1 '635NM'
PRP P2 '2V'
PRP P3 '20MA'
PRP SHEETPART ''
PRP SIZE '0603'
PRP SUB ''
PRP Supplier_1 'Digi-Key'
PRP Supplier_Part_Number_1 '67-1548-1-ND'
PRP VALENTIUM_PART_NUM '<VALENTIUM>'
PRP VALUE 'RED'
TOP 0 1.0481757 4.1975197 180 N 49 1 D13-1
TOP 1 1.0481757 4.2546063 180 N 138 11 D13-2
#
# CMP 92
CMP 9 0.8465091 4.226063 270 N D12 RED ;0=1,1=0.0236
PRP CATEGORY 'LED'
PRP DATE ''
PRP DESC 'LED, RED, SML-LX0603, 635NM, 2V, 20MA, 0603'
PRP MAXTEMP '85C'
PRP MFG_Name 'LUMEX'
PRP MFG_PART_NUM 'SML-LX0603IW-TR'
PRP MINTEMP '-25C'
PRP MODIFY_DATE '9/4/2013'
PRP OTHER 'SML-LX0603'
PRP P1 '635NM'
PRP P2 '2V'
PRP P3 '20MA'
PRP SHEETPART ''
PRP SIZE '0603'
PRP SUB ''
PRP Supplier_1 'Digi-Key'
PRP Supplier_Part_Number_1 '67-1548-1-ND'
PRP VALENTIUM_PART_NUM '<VALENTIUM>'
PRP VALUE 'RED'
TOP 0 0.8465091 4.1975197 180 N 18 1 D12-1
TOP 1 0.8465091 4.2546063 180 N 138 12 D12-2
#
# CMP 93
CMP 9 0.6448425 4.226063 270 N D11 RED ;0=1,1=0.0236
PRP CATEGORY 'LED'
PRP DATE ''
PRP DESC 'LED, RED, SML-LX0603, 635NM, 2V, 20MA, 0603'
PRP MAXTEMP '85C'
PRP MFG_Name 'LUMEX'
PRP MFG_PART_NUM 'SML-LX0603IW-TR'
PRP MINTEMP '-25C'
PRP MODIFY_DATE '9/4/2013'
PRP OTHER 'SML-LX0603'
PRP P1 '635NM'
PRP P2 '2V'
PRP P3 '20MA'
PRP SHEETPART ''
PRP SIZE '0603'
PRP SUB ''
PRP Supplier_1 'Digi-Key'
PRP Supplier_Part_Number_1 '67-1548-1-ND'
PRP VALENTIUM_PART_NUM '<VALENTIUM>'
PRP VALUE 'RED'
TOP 0 0.6448425 4.1975197 180 N 17 1 D11-1
TOP 1 0.6448425 4.2546063 180 N 138 13 D11-2
#
# CMP 94
CMP 9 3.5898425 3.756063 270 N D10 RED ;0=1,1=0.0236
PRP CATEGORY 'LED'
PRP DATE ''
PRP DESC 'LED, RED, SML-LX0603, 635NM, 2V, 20MA, 0603'
PRP MAXTEMP '85C'
PRP MFG_Name 'LUMEX'
PRP MFG_PART_NUM 'SML-LX0603IW-TR'
PRP MINTEMP '-25C'
PRP MODIFY_DATE '9/4/2013'
PRP OTHER 'SML-LX0603'
PRP P1 '635NM'
PRP P2 '2V'
PRP P3 '20MA'
PRP SHEETPART ''
PRP SIZE '0603'
PRP SUB ''
PRP Supplier_1 'Digi-Key'
PRP Supplier_Part_Number_1 '67-1548-1-ND'
PRP VALENTIUM_PART_NUM '<VALENTIUM>'
PRP VALUE 'RED'
TOP 0 3.5898425 3.7275197 180 N 50 0 D10-1
TOP 1 3.5898425 3.7846063 180 N 138 14 D10-2
#
# CMP 95
CMP 9 3.5898425 3.881063 90 N D9 RED ;0=1,1=0.0236
PRP CATEGORY 'LED'
PRP DATE ''
PRP DESC 'LED, RED, SML-LX0603, 635NM, 2V, 20MA, 0603'
PRP MAXTEMP '85C'
PRP MFG_Name 'LUMEX'
PRP MFG_PART_NUM 'SML-LX0603IW-TR'
PRP MINTEMP '-25C'
PRP MODIFY_DATE '9/4/2013'
PRP OTHER 'SML-LX0603'
PRP P1 '635NM'
PRP P2 '2V'
PRP P3 '20MA'
PRP SHEETPART ''
PRP SIZE '0603'
PRP SUB ''
PRP Supplier_1 'Digi-Key'
PRP Supplier_Part_Number_1 '67-1548-1-ND'
PRP VALENTIUM_PART_NUM '<VALENTIUM>'
PRP VALUE 'RED'
TOP 0 3.5898425 3.9096063 0 N 51 1 D9-1
TOP 1 3.5898425 3.8525197 0 N 138 15 D9-2
#
# CMP 96
CMP 33 3.4698425 3.706063 90 N D8 BAT54SW ;0=1,1=0.0433
PRP CATEGORY 'DIO, SCHOTTKY'
PRP DATE ''
PRP DESC 'DIO, SCHOTTKY, BAT54S, DUAL SERIES, 30V, 200MA, SC-70'
PRP MAXTEMP '150C'
PRP MFG_Name 'DIODES INC'
PRP MFG_PART_NUM 'BAT54SWQ-7-F'
PRP MINTEMP '-55C'
PRP MODIFY_DATE '9/4/2013'
PRP OTHER 'SERIES'
PRP P1 'SCHOTTKY'
PRP P2 '30V'
PRP P3 '200mA,200mW'
PRP SHEETPART ''
PRP SIZE 'SC-70'
PRP SUB ''
PRP Supplier_1 'Digi-Key'
PRP Supplier_Part_Number_1 'BAT54SWQ-7-FDICT-ND'
PRP VALENTIUM_PART_NUM '<VALENTIUM>'
PRP VALUE 'BAT54SW'
TOP 0 3.4954331 3.7503543 0 N 136 196 D8-1
TOP 1 3.444252 3.7503543 0 N 138 36 D8-2
TOP 2 3.4698425 3.6617716 0 N 147 2 D8-3
#
# CMP 97
CMP 33 3.2448425 3.706063 90 N D7 BAT54SW ;0=1,1=0.0433
PRP CATEGORY 'DIO, SCHOTTKY'
PRP DATE ''
PRP DESC 'DIO, SCHOTTKY, BAT54S, DUAL SERIES, 30V, 200MA, SC-70'
PRP MAXTEMP '150C'
PRP MFG_Name 'DIODES INC'
PRP MFG_PART_NUM 'BAT54SWQ-7-F'
PRP MINTEMP '-55C'
PRP MODIFY_DATE '9/4/2013'
PRP OTHER 'SERIES'
PRP P1 'SCHOTTKY'
PRP P2 '30V'
PRP P3 '200mA,200mW'
PRP SHEETPART ''
PRP SIZE 'SC-70'
PRP SUB ''
PRP Supplier_1 'Digi-Key'
PRP Supplier_Part_Number_1 'BAT54SWQ-7-FDICT-ND'
PRP VALENTIUM_PART_NUM '<VALENTIUM>'
PRP VALUE 'BAT54SW'
TOP 0 3.2704331 3.7503543 0 N 136 68 D7-1
TOP 1 3.219252 3.7503543 0 N 138 16 D7-2
TOP 2 3.2448425 3.6617716 0 N 137 1 D7-3
#
# CMP 98
CMP 33 2.7198425 3.706063 90 N D6 BAT54SW ;0=1,1=0.0433
PRP CATEGORY 'DIO, SCHOTTKY'
PRP DATE ''
PRP DESC 'DIO, SCHOTTKY, BAT54S, DUAL SERIES, 30V, 200MA, SC-70'
PRP MAXTEMP '150C'
PRP MFG_Name 'DIODES INC'
PRP MFG_PART_NUM 'BAT54SWQ-7-F'
PRP MINTEMP '-55C'
PRP MODIFY_DATE '9/4/2013'
PRP OTHER 'SERIES'
PRP P1 'SCHOTTKY'
PRP P2 '30V'
PRP P3 '200mA,200mW'
PRP SHEETPART ''
PRP SIZE 'SC-70'
PRP SUB ''
PRP Supplier_1 'Digi-Key'
PRP Supplier_Part_Number_1 'BAT54SWQ-7-FDICT-ND'
PRP VALENTIUM_PART_NUM '<VALENTIUM>'
PRP VALUE 'BAT54SW'
TOP 0 2.7454331 3.7503543 0 N 136 69 D6-1
TOP 1 2.694252 3.7503543 0 N 138 17 D6-2
TOP 2 2.7198425 3.6617716 0 N 141 1 D6-3
#
# CMP 99
CMP 33 2.8348425 3.706063 90 N D5 BAT54SW ;0=1,1=0.0433
PRP CATEGORY 'DIO, SCHOTTKY'
PRP DATE ''
PRP DESC 'DIO, SCHOTTKY, BAT54S, DUAL SERIES, 30V, 200MA, SC-70'
PRP MAXTEMP '150C'
PRP MFG_Name 'DIODES INC'
PRP MFG_PART_NUM 'BAT54SWQ-7-F'
PRP MINTEMP '-55C'
PRP MODIFY_DATE '9/4/2013'
PRP OTHER 'SERIES'
PRP P1 'SCHOTTKY'
PRP P2 '30V'
PRP P3 '200mA,200mW'
PRP SHEETPART ''
PRP SIZE 'SC-70'
PRP SUB ''
PRP Supplier_1 'Digi-Key'
PRP Supplier_Part_Number_1 'BAT54SWQ-7-FDICT-ND'
PRP VALENTIUM_PART_NUM '<VALENTIUM>'
PRP VALUE 'BAT54SW'
TOP 0 2.8604331 3.7503543 0 N 136 70 D5-1
TOP 1 2.809252 3.7503543 0 N 138 18 D5-2
TOP 2 2.8348425 3.6617716 0 N 142 1 D5-3
#
# CMP 100
CMP 9 4.3041338 3.6033465 0 N D4 RED ;0=1,1=0.0236
PRP CATEGORY 'LED'
PRP DATE ''
PRP DESC 'LED, RED, SML-LX0603, 635NM, 2V, 20MA, 0603'
PRP MAXTEMP '85C'
PRP MFG_Name 'LUMEX'
PRP MFG_PART_NUM 'SML-LX0603IW-TR'
PRP MINTEMP '-25C'
PRP MODIFY_DATE '9/4/2013'
PRP OTHER 'SML-LX0603'
PRP P1 '635NM'
PRP P2 '2V'
PRP P3 '20MA'
PRP SHEETPART ''
PRP SIZE '0603'
PRP SUB ''
PRP Supplier_1 'Digi-Key'
PRP Supplier_Part_Number_1 '67-1548-1-ND'
PRP VALENTIUM_PART_NUM '<VALENTIUM>'
PRP VALUE 'RED'
TOP 0 4.2755905 3.6033465 270 N 52 1 D4-1
TOP 1 4.3326771 3.6033465 270 N 138 19 D4-2
#
# CMP 101
CMP 30 6.2698425 3.701063 0 N D3 DFLZ39-TP ;0=1,1=0.0531
PRP CATEGORY 'DIO, ZENER'
PRP DATE ''
PRP DESC 'DIO, ZENER, DFLZ39, 39V, 5%, 1W, SOD123FL'
PRP MAXTEMP '150C'
PRP MFG_Name 'MICRO COMM'
PRP MFG_PART_NUM 'DFLZ39-TP'
PRP MINTEMP '-55C'
PRP MODIFY_DATE '9/4/2013'
PRP OTHER 'SERIES'
PRP P1 '39V'
PRP P2 '5%'
PRP P3 '1W'
PRP SHEETPART ''
PRP SIZE 'SOD123FL'
PRP SUB ''
PRP Supplier_1 'Digi-Key'
PRP Supplier_Part_Number_1 'DFLZ39-TPMSDKR-ND'
PRP VALENTIUM_PART_NUM '<VALENTIUM>'
PRP VALUE 'DFLZ39'
TOP 0 6.1979921 3.701063 270 N 54 3 D3-1
TOP 1 6.3416929 3.701063 270 N 112 7 D3-2
#
# CMP 102
CMP 30 6.2748425 3.566063 0 N D2 DFLZ39-TP ;0=1,1=0.0531
PRP CATEGORY 'DIO, ZENER'
PRP DATE ''
PRP DESC 'DIO, ZENER, DFLZ39, 39V, 5%, 1W, SOD123FL'
PRP MAXTEMP '150C'
PRP MFG_Name 'MICRO COMM'
PRP MFG_PART_NUM 'DFLZ39-TP'
PRP MINTEMP '-55C'
PRP MODIFY_DATE '9/4/2013'
PRP OTHER 'SERIES'
PRP P1 '39V'
PRP P2 '5%'
PRP P3 '1W'
PRP SHEETPART ''
PRP SIZE 'SOD123FL'
PRP SUB ''
PRP Supplier_1 'Digi-Key'
PRP Supplier_Part_Number_1 'DFLZ39-TPMSDKR-ND'
PRP VALENTIUM_PART_NUM '<VALENTIUM>'
PRP VALUE 'DFLZ39'
TOP 0 6.2029921 3.566063 270 N 54 1 D2-1
TOP 1 6.3466929 3.566063 270 N 53 4 D2-2
#
# CMP 103
CMP 30 5.9598425 3.701063 0 N D1 DFLZ39-TP ;0=1,1=0.0531
PRP CATEGORY 'DIO, ZENER'
PRP DATE ''
PRP DESC 'DIO, ZENER, DFLZ39, 39V, 5%, 1W, SOD123FL'
PRP MAXTEMP '150C'
PRP MFG_Name 'MICRO COMM'
PRP MFG_PART_NUM 'DFLZ39-TP'
PRP MINTEMP '-55C'
PRP MODIFY_DATE '9/4/2013'
PRP OTHER 'SERIES'
PRP P1 '39V'
PRP P2 '5%'
PRP P3 '1W'
PRP SHEETPART ''
PRP SIZE 'SOD123FL'
PRP SUB ''
PRP Supplier_1 'Digi-Key'
PRP Supplier_Part_Number_1 'DFLZ39-TPMSDKR-ND'
PRP VALENTIUM_PART_NUM '<VALENTIUM>'
PRP VALUE 'DFLZ39'
TOP 0 5.8879921 3.701063 270 N 56 1 D1-1
TOP 1 6.0316929 3.701063 270 N 55 1 D1-2
#
# CMP 104
CMP 6 3.6888425 3.298063 90 N C67 CAP_0603_0.01UF_50V ;0=1,1=0.0394
PRP CATEGORY 'CAP, CER'
PRP DATE '7/24/2013'
PRP DESC 'CAP, CER, 0.01UF, 50V, 10%, X7R, 0603'
PRP MAXTEMP '125C'
PRP MFG_Name 'KEMET'
PRP MFG_PART_NUM 'C0603C103K5RACTU'
PRP MINTEMP '-55C'
PRP MODIFY_DATE '10/23/2013'
PRP OTHER ''
PRP P1 '10%'
PRP P2 '50V'
PRP P3 'X7R'
PRP SHEETPART ''
PRP SIZE '0603'
PRP SUB ''
PRP Supplier_1 'Digi-Key'
PRP Supplier_Part_Number_1 '399-1091-1-ND'
PRP VALENTIUM_PART_NUM '<VALENTIUM>'
PRP VALUE '0.01uF'
TOP 0 3.6888425 3.3295591 0 N 136 71 C67-1
TOP 1 3.6888425 3.266567 0 N 109 11 C67-2
#
# CMP 105
CMP 5 3.7698425 3.218063 270 N C66 CAP_0402_0.1UF_50V ;0=1,1=0.0236
PRP CATEGORY 'CAP, CER'
PRP DATE ''
PRP DESC 'CAP, CER, 0.1UF, 50V, 10%, X7R, AEC-Q200, 0402'
PRP MAXTEMP '125C'
PRP MFG_Name 'TDK'
PRP MFG_PART_NUM 'CGA2B3X7R1H104K050BB'
PRP MINTEMP '-55C'
PRP MODIFY_DATE '10/23/2013'
PRP OTHER 'AEC-Q200'
PRP P1 '10%'
PRP P2 '50V'
PRP P3 'X7R'
PRP SHEETPART ''
PRP SIZE '0402'
PRP SUB ''
PRP Supplier_1 'Digi-Key'
PRP Supplier_Part_Number_1 '445-6899-1-ND'
PRP VALENTIUM_PART_NUM '<VALENTIUM>'
PRP VALUE '0.1UF'
TOP 0 3.7698425 3.2011339 180 N 136 72 C66-1
TOP 1 3.7698425 3.2349922 180 N 109 12 C66-2
#
# CMP 106
CMP 7 3.6938425 3.153063 270 N C65 CAP_0805_1UF_50V ;0=1,1=0.0551
PRP CATEGORY 'CAP, CER'
PRP DATE '10/31/2006 2:46:38 PM'
PRP DESC 'CAP, CER, 1.0UF, 50V, 10%, X7R, 0805'
PRP MAXTEMP '125C'
PRP MFG_Name 'MURATA'
PRP MFG_PART_NUM 'GCM21BR71H105KA03L'
PRP MINTEMP '-55C'
PRP MODIFY_DATE '10/23/2013'
PRP OTHER 'AEC-Q200'
PRP P1 '10%'
PRP P2 '50V'
PRP P3 'X7R'
PRP SHEETPART ''
PRP SIZE '0805'
PRP SUB ''
PRP Supplier_1 'Digi-Key'
PRP Supplier_Part_Number_1 '490-10675-1-ND'
PRP VALENTIUM_PART_NUM '<VALENTIUM>'
PRP VALUE '1.0UF'
TOP 0 3.6938425 3.1176299 180 N 136 73 C65-1
TOP 1 3.6938425 3.1884961 180 N 109 13 C65-2
#
# CMP 107
CMP 5 3.6998425 0.636063 180 N C63 CAP_0402_0.1UF_50V ;0=1,1=0.0236
PRP CATEGORY 'CAP, CER'
PRP DATE ''
PRP DESC 'CAP, CER, 0.1UF, 50V, 10%, X7R, AEC-Q200, 0402'
PRP MAXTEMP '125C'
PRP MFG_Name 'TDK'
PRP MFG_PART_NUM 'CGA2B3X7R1H104K050BB'
PRP MINTEMP '-55C'
PRP MODIFY_DATE '10/23/2013'
PRP OTHER 'AEC-Q200'
PRP P1 '10%'
PRP P2 '50V'
PRP P3 'X7R'
PRP SHEETPART ''
PRP SIZE '0402'
PRP SUB ''
PRP Supplier_1 'Digi-Key'
PRP Supplier_Part_Number_1 '445-6899-1-ND'
PRP VALENTIUM_PART_NUM '<VALENTIUM>'
PRP VALUE '0.1UF'
TOP 0 3.7167716 0.636063 90 N 146 12 C63-1
TOP 1 3.6829133 0.636063 90 N 136 74 C63-2
#
# CMP 108
CMP 7 3.6948425 0.726063 180 N C62 CAP_0805_10UF_25V ;0=1,1=0.0551
PRP CATEGORY 'CAP, CER'
PRP DATE '4/11/2006 3:37:28 PM'
PRP DESC 'CAP, CER, 10.UF, 10V, 10%, X5R, 0805'
PRP MAXTEMP '85C'
PRP MFG_Name 'TAIYO YUDEN'
PRP MFG_PART_NUM 'TMK212BBJ106KG-T'
PRP MINTEMP '-55C'
PRP MODIFY_DATE '10/23/2013'
PRP OTHER ''
PRP P1 '10%'
PRP P2 '25V'
PRP P3 'X5R'
PRP SHEETPART ''
PRP SIZE '0805'
PRP SUB ''
PRP Supplier_1 'MOUSER'
PRP Supplier_Part_Number_1 '963-TMK212BBJ106KG-T'
PRP VALENTIUM_PART_NUM '<VALENTIUM>'
PRP VALUE '10uF'
TOP 0 3.7302756 0.726063 90 N 146 13 C62-1
TOP 1 3.6594094 0.726063 90 N 136 75 C62-2
#
# CMP 109
CMP 5 2.7248425 3.576063 90 N C61 CAP_0402_0.1UF_50V ;0=1,1=0.0236
PRP CATEGORY 'CAP, CER'
PRP DATE ''
PRP DESC 'CAP, CER, 0.1UF, 50V, 10%, X7R, AEC-Q200, 0402'
PRP MAXTEMP '125C'
PRP MFG_Name 'TDK'
PRP MFG_PART_NUM 'CGA2B3X7R1H104K050BB'
PRP MINTEMP '-55C'
PRP MODIFY_DATE '10/23/2013'
PRP OTHER 'AEC-Q200'
PRP P1 '10%'
PRP P2 '50V'
PRP P3 'X7R'
PRP SHEETPART ''
PRP SIZE '0402'
PRP SUB ''
PRP Supplier_1 'Digi-Key'
PRP Supplier_Part_Number_1 '445-6899-1-ND'
PRP VALENTIUM_PART_NUM '<VALENTIUM>'
PRP VALUE '0.1UF'
TOP 0 2.7248425 3.5929921 0 N 146 14 C61-1
TOP 1 2.7248425 3.5591338 0 N 136 76 C61-2
#
# CMP 110
CMP 7 2.6398425 3.571063 90 N C60 CAP_0805_10UF_25V ;0=1,1=0.0551
PRP CATEGORY 'CAP, CER'
PRP DATE '4/11/2006 3:37:28 PM'
PRP DESC 'CAP, CER, 10.UF, 10V, 10%, X5R, 0805'
PRP MAXTEMP '85C'
PRP MFG_Name 'TAIYO YUDEN'
PRP MFG_PART_NUM 'TMK212BBJ106KG-T'
PRP MINTEMP '-55C'
PRP MODIFY_DATE '10/23/2013'
PRP OTHER ''
PRP P1 '10%'
PRP P2 '25V'
PRP P3 'X5R'
PRP SHEETPART ''
PRP SIZE '0805'
PRP SUB ''
PRP Supplier_1 'MOUSER'
PRP Supplier_Part_Number_1 '963-TMK212BBJ106KG-T'
PRP VALENTIUM_PART_NUM '<VALENTIUM>'
PRP VALUE '10uF'
TOP 0 2.6398425 3.6064961 0 N 146 15 C60-1
TOP 1 2.6398425 3.5356299 0 N 136 77 C60-2
#
# CMP 111
CMP 5 2.1398425 3.681063 270 N C59 CAP_0402_0.1UF_50V ;0=1,1=0.0236
PRP CATEGORY 'CAP, CER'
PRP DATE ''
PRP DESC 'CAP, CER, 0.1UF, 50V, 10%, X7R, AEC-Q200, 0402'
PRP MAXTEMP '125C'
PRP MFG_Name 'TDK'
PRP MFG_PART_NUM 'CGA2B3X7R1H104K050BB'
PRP MINTEMP '-55C'
PRP MODIFY_DATE '10/23/2013'
PRP OTHER 'AEC-Q200'
PRP P1 '10%'
PRP P2 '50V'
PRP P3 'X7R'
PRP SHEETPART ''
PRP SIZE '0402'
PRP SUB ''
PRP Supplier_1 'Digi-Key'
PRP Supplier_Part_Number_1 '445-6899-1-ND'
PRP VALENTIUM_PART_NUM '<VALENTIUM>'
PRP VALUE '0.1UF'
TOP 0 2.1398425 3.6641339 180 N 138 20 C59-1
TOP 1 2.1398425 3.6979922 180 N 136 78 C59-2
#
# CMP 112
CMP 7 2.2098425 3.681063 270 N C58 CAP_0805_10UF_25V ;0=1,1=0.0551
PRP CATEGORY 'CAP, CER'
PRP DATE '4/11/2006 3:37:28 PM'
PRP DESC 'CAP, CER, 10.UF, 10V, 10%, X5R, 0805'
PRP MAXTEMP '85C'
PRP MFG_Name 'TAIYO YUDEN'
PRP MFG_PART_NUM 'TMK212BBJ106KG-T'
PRP MINTEMP '-55C'
PRP MODIFY_DATE '10/23/2013'
PRP OTHER ''
PRP P1 '10%'
PRP P2 '25V'
PRP P3 'X5R'
PRP SHEETPART ''
PRP SIZE '0805'
PRP SUB ''
PRP Supplier_1 'MOUSER'
PRP Supplier_Part_Number_1 '963-TMK212BBJ106KG-T'
PRP VALENTIUM_PART_NUM '<VALENTIUM>'
PRP VALUE '10uF'
TOP 0 2.2098425 3.6456299 180 N 138 21 C58-1
TOP 1 2.2098425 3.7164961 180 N 136 79 C58-2
#
# CMP 113
CMP 5 6.5848425 3.056063 90 N C57 CAP_0402_0.1UF_50V ;0=1,1=0.0236
PRP CATEGORY 'CAP, CER'
PRP DATE ''
PRP DESC 'CAP, CER, 0.1UF, 50V, 10%, X7R, AEC-Q200, 0402'
PRP MAXTEMP '125C'
PRP MFG_Name 'TDK'
PRP MFG_PART_NUM 'CGA2B3X7R1H104K050BB'
PRP MINTEMP '-55C'
PRP MODIFY_DATE '10/23/2013'
PRP OTHER 'AEC-Q200'
PRP P1 '10%'
PRP P2 '50V'
PRP P3 'X7R'
PRP SHEETPART ''
PRP SIZE '0402'
PRP SUB ''
PRP Supplier_1 'Digi-Key'
PRP Supplier_Part_Number_1 '445-6899-1-ND'
PRP VALENTIUM_PART_NUM '<VALENTIUM>'
PRP VALUE '0.1UF'
TOP 0 6.5848425 3.0729921 0 N 138 22 C57-1
TOP 1 6.5848425 3.0391338 0 N 136 80 C57-2
#
# CMP 114
CMP 7 6.4748425 3.071063 180 N C56 CAP_0805_10UF_25V ;0=1,1=0.0551
PRP CATEGORY 'CAP, CER'
PRP DATE '4/11/2006 3:37:28 PM'
PRP DESC 'CAP, CER, 10.UF, 10V, 10%, X5R, 0805'
PRP MAXTEMP '85C'
PRP MFG_Name 'TAIYO YUDEN'
PRP MFG_PART_NUM 'TMK212BBJ106KG-T'
PRP MINTEMP '-55C'
PRP MODIFY_DATE '10/23/2013'
PRP OTHER ''
PRP P1 '10%'
PRP P2 '25V'
PRP P3 'X5R'
PRP SHEETPART ''
PRP SIZE '0805'
PRP SUB ''
PRP Supplier_1 'MOUSER'
PRP Supplier_Part_Number_1 '963-TMK212BBJ106KG-T'
PRP VALENTIUM_PART_NUM '<VALENTIUM>'
PRP VALUE '10uF'
TOP 0 6.5102756 3.071063 90 N 138 23 C56-1
TOP 1 6.4394094 3.071063 90 N 136 81 C56-2
#
# CMP 115
CMP 6 4.1948425 3.806063 90 N C55 GRT188R61E106ME13D ;0=1,1=0.0394
PRP CATEGORY 'CAP, CER'
PRP DATE '7/25/2013'
PRP DESC 'CAP, CER, 10.UF, 25V, 20%, X5R, AEC-Q200, 0603'
PRP MAXTEMP '85C'
PRP MFG_Name 'MURATA'
PRP MFG_PART_NUM 'GRT188R61E106ME13D'
PRP MINTEMP '-55C'
PRP MODIFY_DATE '10/23/2013'
PRP OTHER 'AEC-Q200'
PRP P1 '20%'
PRP P2 '25V'
PRP P3 'X5R'
PRP SHEETPART ''
PRP SIZE '0603'
PRP SUB ''
PRP Supplier_1 'Digi-Key'
PRP Supplier_Part_Number_1 '490-12323-6-ND'
PRP VALENTIUM_PART_NUM '<VALENTIUM>'
PRP VALUE '10.UF'
TOP 0 4.1948425 3.8375591 0 N 136 82 C55-1
TOP 1 4.1948425 3.774567 0 N 1 2 C55-2
#
# CMP 116
CMP 7 4.1048425 3.806063 90 N C54 CAP_0805_1UF_25V ;0=1,1=0.0551
PRP CATEGORY 'CAP, CER'
PRP DATE '4/11/2006 3:37:28 PM'
PRP DESC 'CAP, CER, 1.0UF, 25V, 10%, X5R, 0805'
PRP MAXTEMP '85C'
PRP MFG_Name 'AVX'
PRP MFG_PART_NUM '08053D105KAT2A'
PRP MINTEMP '-55C'
PRP MODIFY_DATE '10/23/2013'
PRP OTHER ''
PRP P1 '10%'
PRP P2 '25V'
PRP P3 'X5R'
PRP SHEETPART ''
PRP SIZE '0805'
PRP SUB ''
PRP Supplier_1 'Digi-Key'
PRP Supplier_Part_Number_1 '478-1409-1-ND'
PRP VALENTIUM_PART_NUM '<VALENTIUM>'
PRP VALUE '1.0UF'
TOP 0 4.1048425 3.8414961 0 N 136 83 C54-1
TOP 1 4.1048425 3.7706299 0 N 1 3 C54-2
#
# CMP 117
CMP 5 6.0648425 2.361063 270 N C22 CGA2B3X5R1H333K050BB ;0=1,1=0.0236
PRP CATEGORY 'CAP, CER'
PRP DATE ''
PRP DESC 'CAP, CER, 0.033UF, 50V, 10%, X7R, AEC-Q200, 0402'
PRP MAXTEMP '85C'
PRP MFG_Name 'TDK'
PRP MFG_PART_NUM 'CGA2B3X5R1H333K050BB'
PRP MINTEMP '-55C'
PRP MODIFY_DATE '10/23/2013'
PRP OTHER 'AEC-Q200'
PRP P1 '10%'
PRP P2 '50V'
PRP P3 'X7R'
PRP SHEETPART ''
PRP SIZE '0402'
PRP SUB ''
PRP Supplier_1 'Digi-Key'
PRP Supplier_Part_Number_1 '445-12207-1-ND'
PRP VALENTIUM_PART_NUM '<VALENTIUM>'
PRP VALUE '0.033UF'
TOP 0 6.0648425 2.3441339 180 N 59 0 C22-1
TOP 1 6.0648425 2.3779922 180 N 58 1 C22-2
#
# CMP 118
CMP 6 6.1248425 2.171063 0 N C21 CAP_0603_0.1UF_50V ;0=1,1=0.0394
PRP CATEGORY 'CAP, CER'
PRP DATE '7/24/2013'
PRP DESC 'CAP, CER, 0.1UF, 50V, 10%, X7R, 0603'
PRP MAXTEMP '125C'
PRP MFG_Name 'KEMET'
PRP MFG_PART_NUM 'C0603C104K5RACTU'
PRP MINTEMP '-55C'
PRP MODIFY_DATE '10/23/2013'
PRP OTHER ''
PRP P1 '10%'
PRP P2 '50V'
PRP P3 'X7R'
PRP SHEETPART ''
PRP SIZE '0603'
PRP SUB ''
PRP Supplier_1 'Digi-Key'
PRP Supplier_Part_Number_1 '399-5089-1-ND'
PRP VALENTIUM_PART_NUM '<VALENTIUM>'
PRP VALUE '0.1uF'
TOP 0 6.0933464 2.171063 270 N 136 84 C21-1
TOP 1 6.1563385 2.171063 270 N 60 0 C21-2
#
# CMP 119
CMP 5 6.9398425 1.906063 90 N C20 CGA2B3X5R1H333K050BB ;0=1,1=0.0236
PRP CATEGORY 'CAP, CER'
PRP DATE ''
PRP DESC 'CAP, CER, 0.033UF, 50V, 10%, X7R, AEC-Q200, 0402'
PRP MAXTEMP '85C'
PRP MFG_Name 'TDK'
PRP MFG_PART_NUM 'CGA2B3X5R1H333K050BB'
PRP MINTEMP '-55C'
PRP MODIFY_DATE '10/23/2013'
PRP OTHER 'AEC-Q200'
PRP P1 '10%'
PRP P2 '50V'
PRP P3 'X7R'
PRP SHEETPART ''
PRP SIZE '0402'
PRP SUB ''
PRP Supplier_1 'Digi-Key'
PRP Supplier_Part_Number_1 '445-12207-1-ND'
PRP VALENTIUM_PART_NUM '<VALENTIUM>'
PRP VALUE '0.033UF'
TOP 0 6.9398425 1.9229921 0 N 62 1 C20-1
TOP 1 6.9398425 1.8891338 0 N 61 1 C20-2
#
# CMP 120
CMP 6 6.8748425 2.096063 180 N C19 CAP_0603_0.1UF_50V ;0=1,1=0.0394
PRP CATEGORY 'CAP, CER'
PRP DATE '7/24/2013'
PRP DESC 'CAP, CER, 0.1UF, 50V, 10%, X7R, 0603'
PRP MAXTEMP '125C'
PRP MFG_Name 'KEMET'
PRP MFG_PART_NUM 'C0603C104K5RACTU'
PRP MINTEMP '-55C'
PRP MODIFY_DATE '10/23/2013'
PRP OTHER ''
PRP P1 '10%'
PRP P2 '50V'
PRP P3 'X7R'
PRP SHEETPART ''
PRP SIZE '0603'
PRP SUB ''
PRP Supplier_1 'Digi-Key'
PRP Supplier_Part_Number_1 '399-5089-1-ND'
PRP VALENTIUM_PART_NUM '<VALENTIUM>'
PRP VALUE '0.1uF'
TOP 0 6.9063386 2.096063 90 N 136 85 C19-1
TOP 1 6.8433465 2.096063 90 N 63 1 C19-2
#
# CMP 121
CMP 5 6.6598425 1.776063 180 N C18 CAP_0402_0.1UF_50V ;0=1,1=0.0236
PRP CATEGORY 'CAP, CER'
PRP DATE ''
PRP DESC 'CAP, CER, 0.1UF, 50V, 10%, X7R, AEC-Q200, 0402'
PRP MAXTEMP '125C'
PRP MFG_Name 'TDK'
PRP MFG_PART_NUM 'CGA2B3X7R1H104K050BB'
PRP MINTEMP '-55C'
PRP MODIFY_DATE '10/23/2013'
PRP OTHER 'AEC-Q200'
PRP P1 '10%'
PRP P2 '50V'
PRP P3 'X7R'
PRP SHEETPART ''
PRP SIZE '0402'
PRP SUB ''
PRP Supplier_1 'Digi-Key'
PRP Supplier_Part_Number_1 '445-6899-1-ND'
PRP VALENTIUM_PART_NUM '<VALENTIUM>'
PRP VALUE '0.1UF'
TOP 0 6.6767716 1.776063 90 N 146 16 C18-1
TOP 1 6.6429133 1.776063 90 N 136 86 C18-2
#
# CMP 122
CMP 5 6.6598425 1.721063 180 N C17 CAP_0402_0.1UF_50V ;0=1,1=0.0236
PRP CATEGORY 'CAP, CER'
PRP DATE ''
PRP DESC 'CAP, CER, 0.1UF, 50V, 10%, X7R, AEC-Q200, 0402'
PRP MAXTEMP '125C'
PRP MFG_Name 'TDK'
PRP MFG_PART_NUM 'CGA2B3X7R1H104K050BB'
PRP MINTEMP '-55C'
PRP MODIFY_DATE '10/23/2013'
PRP OTHER 'AEC-Q200'
PRP P1 '10%'
PRP P2 '50V'
PRP P3 'X7R'
PRP SHEETPART ''
PRP SIZE '0402'
PRP SUB ''
PRP Supplier_1 'Digi-Key'
PRP Supplier_Part_Number_1 '445-6899-1-ND'
PRP VALENTIUM_PART_NUM '<VALENTIUM>'
PRP VALUE '0.1UF'
TOP 0 6.6767716 1.721063 90 N 146 17 C17-1
TOP 1 6.6429133 1.721063 90 N 136 87 C17-2
#
# CMP 123
CMP 5 6.6598425 1.671063 180 N C16 CAP_0402_0.1UF_50V ;0=1,1=0.0236
PRP CATEGORY 'CAP, CER'
PRP DATE ''
PRP DESC 'CAP, CER, 0.1UF, 50V, 10%, X7R, AEC-Q200, 0402'
PRP MAXTEMP '125C'
PRP MFG_Name 'TDK'
PRP MFG_PART_NUM 'CGA2B3X7R1H104K050BB'
PRP MINTEMP '-55C'
PRP MODIFY_DATE '10/23/2013'
PRP OTHER 'AEC-Q200'
PRP P1 '10%'
PRP P2 '50V'
PRP P3 'X7R'
PRP SHEETPART ''
PRP SIZE '0402'
PRP SUB ''
PRP Supplier_1 'Digi-Key'
PRP Supplier_Part_Number_1 '445-6899-1-ND'
PRP VALENTIUM_PART_NUM '<VALENTIUM>'
PRP VALUE '0.1UF'
TOP 0 6.6767716 1.671063 90 N 146 18 C16-1
TOP 1 6.6429133 1.671063 90 N 136 88 C16-2
#
# CMP 124
CMP 5 6.6598425 1.611063 180 N C15 CAP_0402_0.1UF_50V ;0=1,1=0.0236
PRP CATEGORY 'CAP, CER'
PRP DATE ''
PRP DESC 'CAP, CER, 0.1UF, 50V, 10%, X7R, AEC-Q200, 0402'
PRP MAXTEMP '125C'
PRP MFG_Name 'TDK'
PRP MFG_PART_NUM 'CGA2B3X7R1H104K050BB'
PRP MINTEMP '-55C'
PRP MODIFY_DATE '10/23/2013'
PRP OTHER 'AEC-Q200'
PRP P1 '10%'
PRP P2 '50V'
PRP P3 'X7R'
PRP SHEETPART ''
PRP SIZE '0402'
PRP SUB ''
PRP Supplier_1 'Digi-Key'
PRP Supplier_Part_Number_1 '445-6899-1-ND'
PRP VALENTIUM_PART_NUM '<VALENTIUM>'
PRP VALUE '0.1UF'
TOP 0 6.6767716 1.611063 90 N 146 19 C15-1
TOP 1 6.6429133 1.611063 90 N 136 89 C15-2
#
# CMP 125
CMP 7 6.6648425 1.531063 180 N C14 CAP_0805_10UF_25V ;0=1,1=0.0551
PRP CATEGORY 'CAP, CER'
PRP DATE '4/11/2006 3:37:28 PM'
PRP DESC 'CAP, CER, 10.UF, 10V, 10%, X5R, 0805'
PRP MAXTEMP '85C'
PRP MFG_Name 'TAIYO YUDEN'
PRP MFG_PART_NUM 'TMK212BBJ106KG-T'
PRP MINTEMP '-55C'
PRP MODIFY_DATE '10/23/2013'
PRP OTHER ''
PRP P1 '10%'
PRP P2 '25V'
PRP P3 'X5R'
PRP SHEETPART ''
PRP SIZE '0805'
PRP SUB ''
PRP Supplier_1 'MOUSER'
PRP Supplier_Part_Number_1 '963-TMK212BBJ106KG-T'
PRP VALENTIUM_PART_NUM '<VALENTIUM>'
PRP VALUE '10uF'
TOP 0 6.7002756 1.531063 90 N 146 20 C14-1
TOP 1 6.6294094 1.531063 90 N 136 90 C14-2
#
# CMP 126
CMP 7 6.6648425 1.421063 180 N C13 CAP_0805_10UF_25V ;0=1,1=0.0551
PRP CATEGORY 'CAP, CER'
PRP DATE '4/11/2006 3:37:28 PM'
PRP DESC 'CAP, CER, 10.UF, 10V, 10%, X5R, 0805'
PRP MAXTEMP '85C'
PRP MFG_Name 'TAIYO YUDEN'
PRP MFG_PART_NUM 'TMK212BBJ106KG-T'
PRP MINTEMP '-55C'
PRP MODIFY_DATE '10/23/2013'
PRP OTHER ''
PRP P1 '10%'
PRP P2 '25V'
PRP P3 'X5R'
PRP SHEETPART ''
PRP SIZE '0805'
PRP SUB ''
PRP Supplier_1 'MOUSER'
PRP Supplier_Part_Number_1 '963-TMK212BBJ106KG-T'
PRP VALENTIUM_PART_NUM '<VALENTIUM>'
PRP VALUE '10uF'
TOP 0 6.7002756 1.421063 90 N 146 21 C13-1
TOP 1 6.6294094 1.421063 90 N 136 91 C13-2
#
# CMP 127
CMP 5 6.3448425 2.611063 0 N C12 CAP_0402_0.1UF_50V ;0=1,1=0.0236
PRP CATEGORY 'CAP, CER'
PRP DATE ''
PRP DESC 'CAP, CER, 0.1UF, 50V, 10%, X7R, AEC-Q200, 0402'
PRP MAXTEMP '125C'
PRP MFG_Name 'TDK'
PRP MFG_PART_NUM 'CGA2B3X7R1H104K050BB'
PRP MINTEMP '-55C'
PRP MODIFY_DATE '10/23/2013'
PRP OTHER 'AEC-Q200'
PRP P1 '10%'
PRP P2 '50V'
PRP P3 'X7R'
PRP SHEETPART ''
PRP SIZE '0402'
PRP SUB ''
PRP Supplier_1 'Digi-Key'
PRP Supplier_Part_Number_1 '445-6899-1-ND'
PRP VALENTIUM_PART_NUM '<VALENTIUM>'
PRP VALUE '0.1UF'
TOP 0 6.3279134 2.611063 270 N 138 24 C12-1
TOP 1 6.3617717 2.611063 270 N 136 92 C12-2
#
# CMP 128
CMP 5 6.3448425 2.556063 0 N C11 CAP_0402_0.1UF_50V ;0=1,1=0.0236
PRP CATEGORY 'CAP, CER'
PRP DATE ''
PRP DESC 'CAP, CER, 0.1UF, 50V, 10%, X7R, AEC-Q200, 0402'
PRP MAXTEMP '125C'
PRP MFG_Name 'TDK'
PRP MFG_PART_NUM 'CGA2B3X7R1H104K050BB'
PRP MINTEMP '-55C'
PRP MODIFY_DATE '10/23/2013'
PRP OTHER 'AEC-Q200'
PRP P1 '10%'
PRP P2 '50V'
PRP P3 'X7R'
PRP SHEETPART ''
PRP SIZE '0402'
PRP SUB ''
PRP Supplier_1 'Digi-Key'
PRP Supplier_Part_Number_1 '445-6899-1-ND'
PRP VALENTIUM_PART_NUM '<VALENTIUM>'
PRP VALUE '0.1UF'
TOP 0 6.3279134 2.556063 270 N 138 25 C11-1
TOP 1 6.3617717 2.556063 270 N 136 93 C11-2
#
# CMP 129
CMP 5 6.3448425 2.501063 0 N C10 CAP_0402_0.1UF_50V ;0=1,1=0.0236
PRP CATEGORY 'CAP, CER'
PRP DATE ''
PRP DESC 'CAP, CER, 0.1UF, 50V, 10%, X7R, AEC-Q200, 0402'
PRP MAXTEMP '125C'
PRP MFG_Name 'TDK'
PRP MFG_PART_NUM 'CGA2B3X7R1H104K050BB'
PRP MINTEMP '-55C'
PRP MODIFY_DATE '10/23/2013'
PRP OTHER 'AEC-Q200'
PRP P1 '10%'
PRP P2 '50V'
PRP P3 'X7R'
PRP SHEETPART ''
PRP SIZE '0402'
PRP SUB ''
PRP Supplier_1 'Digi-Key'
PRP Supplier_Part_Number_1 '445-6899-1-ND'
PRP VALENTIUM_PART_NUM '<VALENTIUM>'
PRP VALUE '0.1UF'
TOP 0 6.3279134 2.501063 270 N 138 26 C10-1
TOP 1 6.3617717 2.501063 270 N 136 94 C10-2
#
# CMP 130
CMP 5 6.3448425 2.656063 0 N C9 CAP_0402_0.1UF_50V ;0=1,1=0.0236
PRP CATEGORY 'CAP, CER'
PRP DATE ''
PRP DESC 'CAP, CER, 0.1UF, 50V, 10%, X7R, AEC-Q200, 0402'
PRP MAXTEMP '125C'
PRP MFG_Name 'TDK'
PRP MFG_PART_NUM 'CGA2B3X7R1H104K050BB'
PRP MINTEMP '-55C'
PRP MODIFY_DATE '10/23/2013'
PRP OTHER 'AEC-Q200'
PRP P1 '10%'
PRP P2 '50V'
PRP P3 'X7R'
PRP SHEETPART ''
PRP SIZE '0402'
PRP SUB ''
PRP Supplier_1 'Digi-Key'
PRP Supplier_Part_Number_1 '445-6899-1-ND'
PRP VALENTIUM_PART_NUM '<VALENTIUM>'
PRP VALUE '0.1UF'
TOP 0 6.3279134 2.656063 270 N 138 27 C9-1
TOP 1 6.3617717 2.656063 270 N 136 95 C9-2
#
# CMP 131
CMP 7 6.3720472 2.7913386 270 N C8 CAP_0805_10UF_25V ;0=1,1=0.0551
PRP CATEGORY 'CAP, CER'
PRP DATE '4/11/2006 3:37:28 PM'
PRP DESC 'CAP, CER, 10.UF, 10V, 10%, X5R, 0805'
PRP MAXTEMP '85C'
PRP MFG_Name 'TAIYO YUDEN'
PRP MFG_PART_NUM 'TMK212BBJ106KG-T'
PRP MINTEMP '-55C'
PRP MODIFY_DATE '10/23/2013'
PRP OTHER ''
PRP P1 '10%'
PRP P2 '25V'
PRP P3 'X5R'
PRP SHEETPART ''
PRP SIZE '0805'
PRP SUB ''
PRP Supplier_1 'MOUSER'
PRP Supplier_Part_Number_1 '963-TMK212BBJ106KG-T'
PRP VALENTIUM_PART_NUM '<VALENTIUM>'
PRP VALUE '10uF'
TOP 0 6.3720472 2.7559055 180 N 138 28 C8-1
TOP 1 6.3720472 2.8267717 180 N 136 96 C8-2
#
# CMP 132
CMP 7 6.253937 2.7913386 270 N C7 CAP_0805_10UF_25V ;0=1,1=0.0551
PRP CATEGORY 'CAP, CER'
PRP DATE '4/11/2006 3:37:28 PM'
PRP DESC 'CAP, CER, 10.UF, 10V, 10%, X5R, 0805'
PRP MAXTEMP '85C'
PRP MFG_Name 'TAIYO YUDEN'
PRP MFG_PART_NUM 'TMK212BBJ106KG-T'
PRP MINTEMP '-55C'
PRP MODIFY_DATE '10/23/2013'
PRP OTHER ''
PRP P1 '10%'
PRP P2 '25V'
PRP P3 'X5R'
PRP SHEETPART ''
PRP SIZE '0805'
PRP SUB ''
PRP Supplier_1 'MOUSER'
PRP Supplier_Part_Number_1 '963-TMK212BBJ106KG-T'
PRP VALENTIUM_PART_NUM '<VALENTIUM>'
PRP VALUE '10uF'
TOP 0 6.253937 2.7559055 180 N 138 29 C7-1
TOP 1 6.253937 2.8267717 180 N 136 97 C7-2
#
# CMP 133
CMP 7 6.6598425 2.131063 270 N C6 CAP_0805_10UF_25V ;0=1,1=0.0551
PRP CATEGORY 'CAP, CER'
PRP DATE '4/11/2006 3:37:28 PM'
PRP DESC 'CAP, CER, 10.UF, 10V, 10%, X5R, 0805'
PRP MAXTEMP '85C'
PRP MFG_Name 'TAIYO YUDEN'
PRP MFG_PART_NUM 'TMK212BBJ106KG-T'
PRP MINTEMP '-55C'
PRP MODIFY_DATE '10/23/2013'
PRP OTHER ''
PRP P1 '10%'
PRP P2 '25V'
PRP P3 'X5R'
PRP SHEETPART ''
PRP SIZE '0805'
PRP SUB ''
PRP Supplier_1 'MOUSER'
PRP Supplier_Part_Number_1 '963-TMK212BBJ106KG-T'
PRP VALENTIUM_PART_NUM '<VALENTIUM>'
PRP VALUE '10uF'
TOP 0 6.6598425 2.0956299 180 N 143 4 C6-1
TOP 1 6.6598425 2.1664961 180 N 136 98 C6-2
#
# CMP 134
CMP 7 6.3348425 2.146063 90 N C5 CAP_0805_10UF_25V ;0=1,1=0.0551
PRP CATEGORY 'CAP, CER'
PRP DATE '4/11/2006 3:37:28 PM'
PRP DESC 'CAP, CER, 10.UF, 10V, 10%, X5R, 0805'
PRP MAXTEMP '85C'
PRP MFG_Name 'TAIYO YUDEN'
PRP MFG_PART_NUM 'TMK212BBJ106KG-T'
PRP MINTEMP '-55C'
PRP MODIFY_DATE '10/23/2013'
PRP OTHER ''
PRP P1 '10%'
PRP P2 '25V'
PRP P3 'X5R'
PRP SHEETPART ''
PRP SIZE '0805'
PRP SUB ''
PRP Supplier_1 'MOUSER'
PRP Supplier_Part_Number_1 '963-TMK212BBJ106KG-T'
PRP VALENTIUM_PART_NUM '<VALENTIUM>'
PRP VALUE '10uF'
TOP 0 6.3348425 2.1814961 0 N 143 5 C5-1
TOP 1 6.3348425 2.1106299 0 N 136 99 C5-2
#
# CMP 135
CMP 6 6.5198425 1.986063 90 N C4 CAP_0603_0.01UF_50V ;0=1,1=0.0394
PRP CATEGORY 'CAP, CER'
PRP DATE '7/24/2013'
PRP DESC 'CAP, CER, 0.01UF, 50V, 10%, X7R, 0603'
PRP MAXTEMP '125C'
PRP MFG_Name 'KEMET'
PRP MFG_PART_NUM 'C0603C103K5RACTU'
PRP MINTEMP '-55C'
PRP MODIFY_DATE '10/23/2013'
PRP OTHER ''
PRP P1 '10%'
PRP P2 '50V'
PRP P3 'X7R'
PRP SHEETPART ''
PRP SIZE '0603'
PRP SUB ''
PRP Supplier_1 'Digi-Key'
PRP Supplier_Part_Number_1 '399-1091-1-ND'
PRP VALENTIUM_PART_NUM '<VALENTIUM>'
PRP VALUE '0.01uF'
TOP 0 6.5198425 2.0175591 0 N 65 1 C4-1
TOP 1 6.5198425 1.954567 0 N 64 2 C4-2
#
# CMP 136
CMP 6 6.4698425 2.271063 270 N C3 CAP_0603_0.01UF_50V ;0=1,1=0.0394
PRP CATEGORY 'CAP, CER'
PRP DATE '7/24/2013'
PRP DESC 'CAP, CER, 0.01UF, 50V, 10%, X7R, 0603'
PRP MAXTEMP '125C'
PRP MFG_Name 'KEMET'
PRP MFG_PART_NUM 'C0603C103K5RACTU'
PRP MINTEMP '-55C'
PRP MODIFY_DATE '10/23/2013'
PRP OTHER ''
PRP P1 '10%'
PRP P2 '50V'
PRP P3 'X7R'
PRP SHEETPART ''
PRP SIZE '0603'
PRP SUB ''
PRP Supplier_1 'Digi-Key'
PRP Supplier_Part_Number_1 '399-1091-1-ND'
PRP VALENTIUM_PART_NUM '<VALENTIUM>'
PRP VALUE '0.01uF'
TOP 0 6.4698425 2.2395669 180 N 67 0 C3-1
TOP 1 6.4698425 2.302559 180 N 66 0 C3-2
#
# CMP 137
CMP 5 5.6513779 3.359252 0 N C2 CAP_0402_0.1UF_50V ;0=1,1=0.0236
PRP CATEGORY 'CAP, CER'
PRP DATE ''
PRP DESC 'CAP, CER, 0.1UF, 50V, 10%, X7R, AEC-Q200, 0402'
PRP MAXTEMP '125C'
PRP MFG_Name 'TDK'
PRP MFG_PART_NUM 'CGA2B3X7R1H104K050BB'
PRP MINTEMP '-55C'
PRP MODIFY_DATE '10/23/2013'
PRP OTHER 'AEC-Q200'
PRP P1 '10%'
PRP P2 '50V'
PRP P3 'X7R'
PRP SHEETPART ''
PRP SIZE '0402'
PRP SUB ''
PRP Supplier_1 'Digi-Key'
PRP Supplier_Part_Number_1 '445-6899-1-ND'
PRP VALENTIUM_PART_NUM '<VALENTIUM>'
PRP VALUE '0.1UF'
TOP 0 5.6344488 3.359252 270 N 143 6 C2-1
TOP 1 5.6683071 3.359252 270 N 136 100 C2-2
#
# CMP 138
CMP 7 5.7765748 3.3612205 180 N C1 CAP_0805_10UF_25V ;0=1,1=0.0551
PRP CATEGORY 'CAP, CER'
PRP DATE '4/11/2006 3:37:28 PM'
PRP DESC 'CAP, CER, 10.UF, 10V, 10%, X5R, 0805'
PRP MAXTEMP '85C'
PRP MFG_Name 'TAIYO YUDEN'
PRP MFG_PART_NUM 'TMK212BBJ106KG-T'
PRP MINTEMP '-55C'
PRP MODIFY_DATE '10/23/2013'
PRP OTHER ''
PRP P1 '10%'
PRP P2 '25V'
PRP P3 'X5R'
PRP SHEETPART ''
PRP SIZE '0805'
PRP SUB ''
PRP Supplier_1 'MOUSER'
PRP Supplier_Part_Number_1 '963-TMK212BBJ106KG-T'
PRP VALENTIUM_PART_NUM '<VALENTIUM>'
PRP VALUE '10uF'
TOP 0 5.8120079 3.3612205 90 N 143 7 C1-1
TOP 1 5.7411417 3.3612205 90 N 136 101 C1-2
#
# CMP 139
CMP 34 0.6548425 0.906063 90 N AN8 1909763-1 ;0=1,1=0.3898
PRP CATEGORY 'CONN, JACK'
PRP DATE ''
PRP DESC 'CONN, JACK, UMCC, MALE, 50 OHM, U.FL, GOLD, SMT'
PRP MAXTEMP '90C'
PRP MFG_Name 'TE'
PRP MFG_PART_NUM '1909763-1'
PRP MINTEMP '-40C'
PRP MODIFY_DATE '10/10/2013'
PRP OTHER 'GOLD'
PRP P1 'MALE'
PRP P2 '50 OHM'
PRP P3 'ST'
PRP SHEETPART ''
PRP SIZE '1.25MM HT'
PRP SUB ''
PRP Supplier_1 'Digi-Key'
PRP Supplier_Part_Number_1 'A118077CT-ND'
PRP VALENTIUM_PART_NUM '<VALENTIUM>'
PRP VALUE 'UMCC'
TOP 0 0.5948031 0.906063 90 N 105 4 AN8-1
TOP 1 0.6548425 0.9641339 90 N 136 198 AN8-2
TOP 2 0.6548425 0.8479921 90 N 136 197 AN8-3
#
# CMP 140
CMP 34 0.6548425 1.431063 90 N AN7 1909763-1 ;0=1,1=0.3898
PRP CATEGORY 'CONN, JACK'
PRP DATE ''
PRP DESC 'CONN, JACK, UMCC, MALE, 50 OHM, U.FL, GOLD, SMT'
PRP MAXTEMP '90C'
PRP MFG_Name 'TE'
PRP MFG_PART_NUM '1909763-1'
PRP MINTEMP '-40C'
PRP MODIFY_DATE '10/10/2013'
PRP OTHER 'GOLD'
PRP P1 'MALE'
PRP P2 '50 OHM'
PRP P3 'ST'
PRP SHEETPART ''
PRP SIZE '1.25MM HT'
PRP SUB ''
PRP Supplier_1 'Digi-Key'
PRP Supplier_Part_Number_1 'A118077CT-ND'
PRP VALENTIUM_PART_NUM '<VALENTIUM>'
PRP VALUE 'UMCC'
TOP 0 0.5948031 1.431063 90 N 106 3 AN7-1
TOP 1 0.6548425 1.4891339 90 N 136 103 AN7-2
TOP 2 0.6548425 1.3729921 90 N 136 102 AN7-3
#
# CMP 141
CMP 34 0.6548425 2.481063 90 N AN6 1909763-1 ;0=1,1=0.0000
PRP CATEGORY 'CONN, JACK'
PRP DATE ''
PRP DESC 'CONN, JACK, UMCC, MALE, 50 OHM, U.FL, GOLD, SMT'
PRP MAXTEMP '90C'
PRP MFG_Name 'TE'
PRP MFG_PART_NUM '1909763-1'
PRP MINTEMP '-40C'
PRP MODIFY_DATE '10/10/2013'
PRP OTHER 'GOLD'
PRP P1 'MALE'
PRP P2 '50 OHM'
PRP P3 'ST'
PRP SHEETPART ''
PRP SIZE '1.25MM HT'
PRP SUB ''
PRP Supplier_1 'Digi-Key'
PRP Supplier_Part_Number_1 'A118077CT-ND'
PRP VALENTIUM_PART_NUM '<VALENTIUM>'
PRP VALUE 'UMCC'
TOP 0 0.5948031 2.481063 90 N 108 3 AN6-1
TOP 1 0.6548425 2.5391339 90 N 136 104 AN6-2
TOP 2 0.6548425 2.4229921 90 N 136 105 AN6-3
#
# CMP 142
CMP 34 0.6548425 1.956063 90 N AN5 1909763-1 ;0=1,1=0.0000
PRP CATEGORY 'CONN, JACK'
PRP DATE ''
PRP DESC 'CONN, JACK, UMCC, MALE, 50 OHM, U.FL, GOLD, SMT'
PRP MAXTEMP '90C'
PRP MFG_Name 'TE'
PRP MFG_PART_NUM '1909763-1'
PRP MINTEMP '-40C'
PRP MODIFY_DATE '10/10/2013'
PRP OTHER 'GOLD'
PRP P1 'MALE'
PRP P2 '50 OHM'
PRP P3 'ST'
PRP SHEETPART ''
PRP SIZE '1.25MM HT'
PRP SUB ''
PRP Supplier_1 'Digi-Key'
PRP Supplier_Part_Number_1 'A118077CT-ND'
PRP VALENTIUM_PART_NUM '<VALENTIUM>'
PRP VALUE 'UMCC'
TOP 0 0.5948031 1.956063 90 N 107 3 AN5-1
TOP 1 0.6548425 2.0141339 90 N 136 106 AN5-2
TOP 2 0.6548425 1.8979921 90 N 136 107 AN5-3
#
# CMP 143
CMP 3 0.1998425 0.906063 180 N AN4 RF-901-143-6FRX ;0=2,1=0.3898
PRP CATEGORY 'CONN, JACK'
PRP DATE ''
PRP DESC 'CONN, JACK, SMA, FEMALE, 50 OHM, R/A, GOLD, TH'
PRP MAXTEMP '165C'
PRP MFG_Name 'AMPHENOL'
PRP MFG_PART_NUM '901-143-6RFX'
PRP MINTEMP '-65C'
PRP MODIFY_DATE '10/10/2013'
PRP OTHER 'GOLD'
PRP P1 'FEMALE'
PRP P2 '50 OHM'
PRP P3 'R/A'
PRP SHEETPART ''
PRP SIZE '9.86MM HT'
PRP SUB ''
PRP Supplier_1 'Digi-Key'
PRP Supplier_Part_Number_1 'ARFX1232-ND'
PRP VALENTIUM_PART_NUM '<VALENTIUM>'
PRP VALUE 'SMA'
TOP 0 0.1998425 0.906063 180 N 105 0 AN4-1
TOP 1 0.2998425 1.006063 180 N 136 35 AN4-2
TOP 2 0.2998425 0.806063 180 N 136 34 AN4-3
TOP 3 0.0998425 0.806063 180 N 136 33 AN4-4
TOP 4 0.0998425 1.006063 180 N 136 32 AN4-5
#
# CMP 144
CMP 3 0.1998425 1.431063 180 N AN3 RF-901-143-6FRX ;0=2,1=0.3898
PRP CATEGORY 'CONN, JACK'
PRP DATE ''
PRP DESC 'CONN, JACK, SMA, FEMALE, 50 OHM, R/A, GOLD, TH'
PRP MAXTEMP '165C'
PRP MFG_Name 'AMPHENOL'
PRP MFG_PART_NUM '901-143-6RFX'
PRP MINTEMP '-65C'
PRP MODIFY_DATE '10/10/2013'
PRP OTHER 'GOLD'
PRP P1 'FEMALE'
PRP P2 '50 OHM'
PRP P3 'R/A'
PRP SHEETPART ''
PRP SIZE '9.86MM HT'
PRP SUB ''
PRP Supplier_1 'Digi-Key'
PRP Supplier_Part_Number_1 'ARFX1232-ND'
PRP VALENTIUM_PART_NUM '<VALENTIUM>'
PRP VALUE 'SMA'
TOP 0 0.1998425 1.431063 180 N 106 0 AN3-1
TOP 1 0.2998425 1.531063 180 N 136 20 AN3-2
TOP 2 0.2998425 1.331063 180 N 136 19 AN3-3
TOP 3 0.0998425 1.331063 180 N 136 18 AN3-4
TOP 4 0.0998425 1.531063 180 N 136 17 AN3-5
#
# CMP 145
CMP 3 0.1998425 1.956063 180 N AN2 RF-901-143-6FRX ;0=2,1=0.3898
PRP CATEGORY 'CONN, JACK'
PRP DATE ''
PRP DESC 'CONN, JACK, SMA, FEMALE, 50 OHM, R/A, GOLD, TH'
PRP MAXTEMP '165C'
PRP MFG_Name 'AMPHENOL'
PRP MFG_PART_NUM '901-143-6RFX'
PRP MINTEMP '-65C'
PRP MODIFY_DATE '10/10/2013'
PRP OTHER 'GOLD'
PRP P1 'FEMALE'
PRP P2 '50 OHM'
PRP P3 'R/A'
PRP SHEETPART ''
PRP SIZE '9.86MM HT'
PRP SUB ''
PRP Supplier_1 'Digi-Key'
PRP Supplier_Part_Number_1 'ARFX1232-ND'
PRP VALENTIUM_PART_NUM '<VALENTIUM>'
PRP VALUE 'SMA'
TOP 0 0.1998425 1.956063 180 N 107 0 AN2-1
TOP 1 0.2998425 2.056063 180 N 136 24 AN2-2
TOP 2 0.2998425 1.856063 180 N 136 23 AN2-3
TOP 3 0.0998425 1.856063 180 N 136 22 AN2-4
TOP 4 0.0998425 2.056063 180 N 136 21 AN2-5
#
# CMP 146
CMP 3 0.1998425 2.481063 180 N AN1 RF-901-143-6FRX ;0=2,1=0.3898
PRP CATEGORY 'CONN, JACK'
PRP DATE ''
PRP DESC 'CONN, JACK, SMA, FEMALE, 50 OHM, R/A, GOLD, TH'
PRP MAXTEMP '165C'
PRP MFG_Name 'AMPHENOL'
PRP MFG_PART_NUM '901-143-6RFX'
PRP MINTEMP '-65C'
PRP MODIFY_DATE '10/10/2013'
PRP OTHER 'GOLD'
PRP P1 'FEMALE'
PRP P2 '50 OHM'
PRP P3 'R/A'
PRP SHEETPART ''
PRP SIZE '9.86MM HT'
PRP SUB ''
PRP Supplier_1 'Digi-Key'
PRP Supplier_Part_Number_1 'ARFX1232-ND'
PRP VALENTIUM_PART_NUM '<VALENTIUM>'
PRP VALUE 'SMA'
TOP 0 0.1998425 2.481063 180 N 108 0 AN1-1
TOP 1 0.2998425 2.581063 180 N 136 28 AN1-2
TOP 2 0.2998425 2.381063 180 N 136 27 AN1-3
TOP 3 0.0998425 2.381063 180 N 136 26 AN1-4
TOP 4 0.0998425 2.581063 180 N 136 25 AN1-5
#

### steps/pcb/layers/drill/tools
THICKNESS=0
USER_PARAMS=

TOOLS {
    NUM=1
    TYPE=VIA
    MIN_TOL=0
    MAX_TOL=0
    BIT=
    FINISH_SIZE=8
    DRILL_SIZE=8
}

TOOLS {
    NUM=2
    TYPE=PLATED
    MIN_TOL=0
    MAX_TOL=0
    BIT=
    FINISH_SIZE=21.66
    DRILL_SIZE=21.66
}

TOOLS {
    NUM=3
    TYPE=PLATED
    MIN_TOL=0
    MAX_TOL=0
    BIT=
    FINISH_SIZE=29.9213
    DRILL_SIZE=29.9213
}

TOOLS {
    NUM=4
    TYPE=PLATED
    MIN_TOL=0
    MAX_TOL=0
    BIT=
    FINISH_SIZE=30
    DRILL_SIZE=30
}

TOOLS {
    NUM=5
    TYPE=PLATED
    MIN_TOL=0
    MAX_TOL=0
    BIT=
    FINISH_SIZE=39.3701
    DRILL_SIZE=39.3701
}

TOOLS {
    NUM=6
    TYPE=PLATED
    MIN_TOL=0
    MAX_TOL=0
    BIT=
    FINISH_SIZE=41.3386
    DRILL_SIZE=41.3386
}

TOOLS {
    NUM=7
    TYPE=PLATED
    MIN_TOL=0
    MAX_TOL=0
    BIT=
    FINISH_SIZE=50
    DRILL_SIZE=50
}

TOOLS {
    NUM=8
    TYPE=PLATED
    MIN_TOL=0
    MAX_TOL=0
    BIT=
    FINISH_SIZE=60
    DRILL_SIZE=60
}

TOOLS {
    NUM=9
    TYPE=PLATED
    MIN_TOL=0
    MAX_TOL=0
    BIT=
    FINISH_SIZE=64.9606
    DRILL_SIZE=64.9606
}

TOOLS {
    NUM=10
    TYPE=PLATED
    MIN_TOL=0
    MAX_TOL=0
    BIT=
    FINISH_SIZE=68
    DRILL_SIZE=68
}

TOOLS {
    NUM=11
    TYPE=PLATED
    MIN_TOL=0
    MAX_TOL=0
    BIT=
    FINISH_SIZE=70.8661
    DRILL_SIZE=70.8661
}

TOOLS {
    NUM=12
    TYPE=PLATED
    MIN_TOL=0
    MAX_TOL=0
    BIT=
    FINISH_SIZE=118.11
    DRILL_SIZE=118.11
}

TOOLS {
    NUM=13
    TYPE=VIA
    MIN_TOL=0
    MAX_TOL=0
    BIT=
    FINISH_SIZE=125.9843
    DRILL_SIZE=125.9843
}

TOOLS {
    NUM=14
    TYPE=NON_PLATED
    MIN_TOL=0
    MAX_TOL=0
    BIT=
    FINISH_SIZE=35.4331
    DRILL_SIZE=35.4331
}

TOOLS {
    NUM=15
    TYPE=NON_PLATED
    MIN_TOL=0
    MAX_TOL=0
    BIT=
    FINISH_SIZE=65.9843
    DRILL_SIZE=65.9843
}

TOOLS {
    NUM=16
    TYPE=NON_PLATED
    MIN_TOL=0
    MAX_TOL=0
    BIT=
    FINISH_SIZE=118.1102
    DRILL_SIZE=118.1102
}

TOOLS {
    NUM=17
    TYPE=NON_PLATED
    MIN_TOL=0
    MAX_TOL=0
    BIT=
    FINISH_SIZE=125.1969
    DRILL_SIZE=125.1969
}

